(kicad_pcb (version 20221018) (generator pcbnew)

  (general
    (thickness 1.586)
  )

  (paper "A4")
  (title_block
    (date "2024-03-26")
    (rev "1.1.3")
  )

  (layers
    (0 "F.Cu" signal)
    (1 "In1.Cu" power)
    (2 "In2.Cu" power)
    (31 "B.Cu" signal)
    (32 "B.Adhes" user "B.Adhesive")
    (33 "F.Adhes" user "F.Adhesive")
    (34 "B.Paste" user)
    (35 "F.Paste" user)
    (36 "B.SilkS" user "B.Silkscreen")
    (37 "F.SilkS" user "F.Silkscreen")
    (38 "B.Mask" user)
    (39 "F.Mask" user)
    (40 "Dwgs.User" user "User.Drawings")
    (41 "Cmts.User" user "User.Comments")
    (42 "Eco1.User" user "User.Eco1")
    (43 "Eco2.User" user "User.Eco2")
    (44 "Edge.Cuts" user)
    (45 "Margin" user)
    (46 "B.CrtYd" user "B.Courtyard")
    (47 "F.CrtYd" user "F.Courtyard")
    (48 "B.Fab" user)
    (49 "F.Fab" user)
  )

  (setup
    (stackup
      (layer "F.SilkS" (type "Top Silk Screen"))
      (layer "F.Paste" (type "Top Solder Paste"))
      (layer "F.Mask" (type "Top Solder Mask") (thickness 0.02))
      (layer "F.Cu" (type "copper") (thickness 0.018))
      (layer "dielectric 1" (type "prepreg") (thickness 0.12) (material "FR4") (epsilon_r 4.2) (loss_tangent 0.02))
      (layer "In1.Cu" (type "copper") (thickness 0.035))
      (layer "dielectric 2" (type "core") (thickness 1.2) (material "FR4") (epsilon_r 4.2) (loss_tangent 0.02))
      (layer "In2.Cu" (type "copper") (thickness 0.035))
      (layer "dielectric 3" (type "prepreg") (thickness 0.12) (material "FR4") (epsilon_r 4.2) (loss_tangent 0.02))
      (layer "B.Cu" (type "copper") (thickness 0.018))
      (layer "B.Mask" (type "Bottom Solder Mask") (thickness 0.02))
      (layer "B.Paste" (type "Bottom Solder Paste"))
      (layer "B.SilkS" (type "Bottom Silk Screen"))
      (copper_finish "None")
      (dielectric_constraints yes)
    )
    (pad_to_mask_clearance 0)
    (aux_axis_origin 75.1 96.7)
    (pcbplotparams
      (layerselection 0x00010fc_ffffffff)
      (plot_on_all_layers_selection 0x0000000_00000000)
      (disableapertmacros false)
      (usegerberextensions false)
      (usegerberattributes false)
      (usegerberadvancedattributes false)
      (creategerberjobfile false)
      (dashed_line_dash_ratio 12.000000)
      (dashed_line_gap_ratio 3.000000)
      (svgprecision 6)
      (plotframeref false)
      (viasonmask false)
      (mode 1)
      (useauxorigin false)
      (hpglpennumber 1)
      (hpglpenspeed 20)
      (hpglpendiameter 15.000000)
      (dxfpolygonmode true)
      (dxfimperialunits true)
      (dxfusepcbnewfont true)
      (psnegative false)
      (psa4output false)
      (plotreference true)
      (plotvalue true)
      (plotinvisibletext false)
      (sketchpadsonfab false)
      (subtractmaskfromsilk false)
      (outputformat 1)
      (mirror false)
      (drillshape 0)
      (scaleselection 1)
      (outputdirectory "./")
    )
  )

  (net 0 "")
  (net 1 "/PoE/PAIR12")
  (net 2 "/PoE/PAIR36")
  (net 3 "/PoE/PAIR45")
  (net 4 "GNDD")
  (net 5 "VSS")
  (net 6 "/PoE/VDD_POE_IN")
  (net 7 "Net-(C27-Pad1)")
  (net 8 "Net-(C31-Pad1)")
  (net 9 "Net-(C30-Pad1)")
  (net 10 "Net-(C33-Pad1)")
  (net 11 "GND")
  (net 12 "VCC5V0")
  (net 13 "/PoE/VO5V")
  (net 14 "Net-(C34-Pad1)")
  (net 15 "PCIE_TX_N")
  (net 16 "PCIE_RX_N")
  (net 17 "PCIE_TX_P")
  (net 18 "PCIE_RX_P")
  (net 19 "Net-(U2-SW)")
  (net 20 "/PoE/PAIR78")
  (net 21 "Net-(D7-Pad1)")
  (net 22 "Net-(U2-BST)")
  (net 23 "Net-(U6-3.3VOUT)")
  (net 24 "/Interfaces/RPi_USB_N")
  (net 25 "/Interfaces/RPi_USB_P")
  (net 26 "Net-(J3-LED)")
  (net 27 "/Interfaces/VBus_Slave")
  (net 28 "SD_DAT1")
  (net 29 "SD_DAT0")
  (net 30 "SD_CLK")
  (net 31 "SD_CMD")
  (net 32 "SD_DAT3")
  (net 33 "SD_DAT2")
  (net 34 "/PoE/POE_ACTIVE")
  (net 35 "unconnected-(D3-ID-Pad3)")
  (net 36 "HDMI0_D2_P")
  (net 37 "HDMI0_D2_N")
  (net 38 "HDMI0_D1_P")
  (net 39 "HDMI0_D1_N")
  (net 40 "HDMI0_CK_P")
  (net 41 "HDMI0_CK_N")
  (net 42 "nEXTRST")
  (net 43 "GLOBAL_EN")
  (net 44 "CAM_GPIO")
  (net 45 "AIN0")
  (net 46 "nPWR_LED")
  (net 47 "AIN1")
  (net 48 "RUN_PG")
  (net 49 "BT_nDis")
  (net 50 "VCC1V8")
  (net 51 "WL_nDis")
  (net 52 "SDA0")
  (net 53 "SCL0")
  (net 54 "RESERVED")
  (net 55 "SD_PWR_ON")
  (net 56 "GPIO2")
  (net 57 "GPIO3")
  (net 58 "GPIO4")
  (net 59 "GPIO17")
  (net 60 "GPIO27")
  (net 61 "GPIO18")
  (net 62 "GPIO22")
  (net 63 "GPIO23")
  (net 64 "GPIO10")
  (net 65 "GPIO24")
  (net 66 "GPIO9")
  (net 67 "GPIO25")
  (net 68 "GPIO11")
  (net 69 "GPIO8")
  (net 70 "ID_SD")
  (net 71 "GPIO7")
  (net 72 "GPIO5")
  (net 73 "ID_SC")
  (net 74 "GPIO6")
  (net 75 "GPIO12")
  (net 76 "GPIO13")
  (net 77 "GPIO16")
  (net 78 "GPIO19")
  (net 79 "GPIO20")
  (net 80 "GPIO26")
  (net 81 "GPIO21")
  (net 82 "EEPROM_nWP")
  (net 83 "SYNC_OUT")
  (net 84 "ETH_LEDG")
  (net 85 "SYNC_IN")
  (net 86 "ETH_LEDY")
  (net 87 "TRD0_P")
  (net 88 "TRD2_P")
  (net 89 "TRD0_N")
  (net 90 "TRD2_N")
  (net 91 "TRD1_N")
  (net 92 "TRD3_N")
  (net 93 "TRD1_P")
  (net 94 "TRD3_P")
  (net 95 "USBOTG_ID")
  (net 96 "PCIE_CLK_nREQ")
  (net 97 "USB2_N")
  (net 98 "USB2_P")
  (net 99 "PSCIE_nRST")
  (net 100 "PCIE_CLK_P")
  (net 101 "TV_OUT")
  (net 102 "PCIE_CLK_N")
  (net 103 "CAM1_D0_N")
  (net 104 "CAM1_D0_P")
  (net 105 "CAM1_D1_N")
  (net 106 "CAM1_D1_P")
  (net 107 "CAM1_C_N")
  (net 108 "CAM0_D0_N")
  (net 109 "CAM1_C_P")
  (net 110 "CAM0_D0_P")
  (net 111 "CAM1_D2_N")
  (net 112 "CAM0_D1_N")
  (net 113 "CAM1_D2_P")
  (net 114 "CAM0_D1_P")
  (net 115 "CAM1_D3_N")
  (net 116 "CAM0_C_N")
  (net 117 "CAM1_D3_P")
  (net 118 "CAM0_C_P")
  (net 119 "HDMI1_HOTPLUG")
  (net 120 "HDMI1_SDA")
  (net 121 "HDMI1_D2_P")
  (net 122 "HDMI1_SCL")
  (net 123 "HDMI1_D2_N")
  (net 124 "HDMI1_CEC")
  (net 125 "HDMI0_CEC")
  (net 126 "HDMI1_D1_P")
  (net 127 "HDMI0_HOTPLUG")
  (net 128 "HDMI1_D1_N")
  (net 129 "DSI0_D0_N")
  (net 130 "HDMI1_D0_P")
  (net 131 "DSI0_D0_P")
  (net 132 "HDMI1_D0_N")
  (net 133 "DSI0_D1_N")
  (net 134 "HDMI1_CK_P")
  (net 135 "DSI0_D1_P")
  (net 136 "HDMI1_CK_N")
  (net 137 "DSI0_C_N")
  (net 138 "DSI0_C_P")
  (net 139 "DSI1_D0_N")
  (net 140 "DSI1_D0_P")
  (net 141 "DSI1_D1_N")
  (net 142 "HDMI0_D0_P")
  (net 143 "DSI1_D1_P")
  (net 144 "HDMI0_D0_N")
  (net 145 "DSI1_C_N")
  (net 146 "DSI1_C_P")
  (net 147 "DSI2_D1_N")
  (net 148 "DSI1_D3_N")
  (net 149 "DSI2_D1_P")
  (net 150 "DSI1_D3_P")
  (net 151 "HDMI0_SDA")
  (net 152 "HDMI0_SCL")
  (net 153 "/PoE/T_ETH_D0_P")
  (net 154 "/PoE/T_ETH_D0_N")
  (net 155 "/PoE/T_ETH_D1_P")
  (net 156 "/PoE/T_ETH_D2_P")
  (net 157 "/PoE/T_ETH_D2_N")
  (net 158 "/PoE/T_ETH_D1_N")
  (net 159 "/PoE/T_ETH_D3_P")
  (net 160 "/PoE/T_ETH_D3_N")
  (net 161 "unconnected-(D3-NC-Pad5)")
  (net 162 "PCIE_WAKE")
  (net 163 "unconnected-(J3-PER3_N-Pad5)")
  (net 164 "unconnected-(J3-NC-Pad6)")
  (net 165 "unconnected-(J3-PER3_P-Pad7)")
  (net 166 "unconnected-(J3-NC-Pad8)")
  (net 167 "unconnected-(J3-PET3_N-Pad11)")
  (net 168 "unconnected-(J3-PET3_P-Pad13)")
  (net 169 "unconnected-(J3-PER2_N-Pad17)")
  (net 170 "3V3_SSD")
  (net 171 "unconnected-(J3-PER2_P-Pad19)")
  (net 172 "unconnected-(J3-NC-Pad20)")
  (net 173 "unconnected-(J3-NC-Pad22)")
  (net 174 "unconnected-(J3-PET2_N-Pad23)")
  (net 175 "Net-(C25-Pad2)")
  (net 176 "unconnected-(J3-NC-Pad24)")
  (net 177 "unconnected-(J3-PET2_P-Pad25)")
  (net 178 "unconnected-(J3-NC-Pad26)")
  (net 179 "unconnected-(J3-NC-Pad28)")
  (net 180 "unconnected-(J3-PER1_N-Pad29)")
  (net 181 "unconnected-(J3-NC-Pad30)")
  (net 182 "unconnected-(J3-PER1_P-Pad31)")
  (net 183 "unconnected-(J3-NC-Pad32)")
  (net 184 "unconnected-(J3-NC-Pad34)")
  (net 185 "unconnected-(J3-PET1_N-Pad35)")
  (net 186 "unconnected-(J3-NC-Pad36)")
  (net 187 "unconnected-(J3-PET1_P-Pad37)")
  (net 188 "Net-(D1-Pad1)")
  (net 189 "unconnected-(J3-NC-Pad38)")
  (net 190 "unconnected-(J3-SMB_CLK-Pad40)")
  (net 191 "Net-(D4-Pad1)")
  (net 192 "unconnected-(J3-SMB_DATA-Pad42)")
  (net 193 "unconnected-(J3-ALERT-Pad44)")
  (net 194 "unconnected-(J3-NC-Pad46)")
  (net 195 "unconnected-(J3-NC-Pad48)")
  (net 196 "unconnected-(J3-NC-Pad56)")
  (net 197 "unconnected-(J3-NC-Pad58)")
  (net 198 "unconnected-(J3-NC-Pad67)")
  (net 199 "unconnected-(J3-SUSCLK-Pad68)")
  (net 200 "unconnected-(J3-NC-Pad69)")
  (net 201 "Net-(J4-CD1)")
  (net 202 "unconnected-(J5-ID-Pad4)")
  (net 203 "unconnected-(J7-Pad19)")
  (net 204 "unconnected-(J7-Pad64)")
  (net 205 "unconnected-(J7-Pad68)")
  (net 206 "unconnected-(J7-Pad70)")
  (net 207 "unconnected-(J7-Pad72)")
  (net 208 "unconnected-(J7-Pad73)")
  (net 209 "unconnected-(J8-Pad4)")
  (net 210 "unconnected-(J8-Pad6)")
  (net 211 "unconnected-(J10-Pad13)")
  (net 212 "unconnected-(J10-Pad14)")
  (net 213 "unconnected-(J10-Pad15)")
  (net 214 "unconnected-(J10-Pad16)")
  (net 215 "unconnected-(S1-Pad3)")
  (net 216 "unconnected-(SP1-Pad1)")
  (net 217 "unconnected-(SP2-Pad1)")
  (net 218 "unconnected-(SP3-Pad1)")
  (net 219 "unconnected-(SP4-Pad1)")
  (net 220 "unconnected-(SP5-Pad1)")
  (net 221 "unconnected-(SP6-Pad1)")
  (net 222 "Net-(L3-TCT1)")
  (net 223 "Net-(L3-TCT2)")
  (net 224 "Net-(L3-TCT3)")
  (net 225 "Net-(J6-Pad10)")
  (net 226 "Net-(J6-Pad12)")
  (net 227 "Net-(J7-Pad21)")
  (net 228 "Net-(L3-TCT4)")
  (net 229 "unconnected-(MP1-Pad1)")
  (net 230 "Earth")
  (net 231 "Net-(D4-Pad2)")
  (net 232 "3V3_RPi")
  (net 233 "Net-(D11-Pad2)")
  (net 234 "unconnected-(MP2-Pad1)")
  (net 235 "/Interfaces/CONN_USB_N")
  (net 236 "/Interfaces/CONN_USB_P")
  (net 237 "Adapter_RXD")
  (net 238 "Adapter_TXD")
  (net 239 "Adapter_USB_P")
  (net 240 "Adapter_USB_N")
  (net 241 "RPi_RXD")
  (net 242 "RPi_TXD")
  (net 243 "/Compute module/nRPi_BOOT")
  (net 244 "PROG_MODE")
  (net 245 "unconnected-(MP3-Pad1)")
  (net 246 "Net-(Q6-G)")
  (net 247 "Net-(U1-D+)")
  (net 248 "Net-(U1-D-)")
  (net 249 "/Interfaces/FTDI_USB_N")
  (net 250 "Net-(U1-~{OE})")
  (net 251 "/Interfaces/FTDI_USB_P")
  (net 252 "Net-(U2-FB)")
  (net 253 "3V3_OUT")
  (net 254 "Net-(U3-CLSA)")
  (net 255 "Net-(U8-CLS)")
  (net 256 "Net-(U8-DEN)")
  (net 257 "Net-(U3-CLSB)")
  (net 258 "Net-(U3-DEN)")
  (net 259 "Net-(U3-AMPS_CTL)")
  (net 260 "Net-(U3-REF)")
  (net 261 "Net-(U3-TPH)")
  (net 262 "Net-(U3-TPL)")
  (net 263 "Net-(U3-~{BT})")
  (net 264 "Net-(U5-~{OE})")
  (net 265 "Net-(U6-RXD)")
  (net 266 "Net-(U6-USBDM)")
  (net 267 "Net-(U6-USBDP)")
  (net 268 "Net-(U6-TXD)")
  (net 269 "Net-(U3-VC_IN)")
  (net 270 "Net-(U2-EN)")
  (net 271 "Net-(U3-VC_OUT)")
  (net 272 "Net-(U3-UVLO_SEL)")
  (net 273 "unconnected-(U4-TRIM-Pad5)")
  (net 274 "unconnected-(U6-CBUS0-Pad6)")
  (net 275 "unconnected-(U6-~{RTS}-Pad8)")
  (net 276 "unconnected-(U6-~{CTS}-Pad11)")
  (net 277 "unconnected-(U7-TRIM-Pad5)")
  (net 278 "unconnected-(U8-T2P-Pad7)")

  (footprint "scalenode-cm4-baseboard-footprints:Spacer_Drill3.7mm_H3mm_9774030151R" (layer "F.Cu")
    (at 193.488 93.2)
    (property "Author" "Antmicro")
    (property "License" "Apache-2.0")
    (property "MPN" "9774030151R")
    (property "Manufacturer" "Würth Elektronik")
    (property "Sheetfile" "compute-module.kicad_sch")
    (property "Sheetname" "Compute module")
    (property "ki_description" "Spacer, SMT,  Steel, Swage Round, 5.1mmx3mm, M3 Thread, WA-SMSI Series")
    (property "ki_keywords" "SPACER")
    (attr through_hole)
    (fp_text reference "SP5" (at -0.052 -3.65) (layer "F.SilkS")
        (effects (font (size 0.7 0.7) (thickness 0.15)) (justify left bottom))
    )
    (fp_text value "Spacer_Drill3.7mm_H3mm_9774030151R" (at 1.387 2.4) (layer "F.Fab")
        (effects (font (size 0.7 0.7) (thickness 0.15)) (justify left bottom))
    )
    (fp_text user "License: Apache-2.0" (at -2.601 8.8) (layer "F.Fab") hide
        (effects (font (size 0.7 0.7) (thickness 0.15)) (justify left bottom))
    )
    (fp_text user "${REFERENCE}" (at -2.601 6.398) (layer "F.Fab") hide
        (effects (font (size 0.7 0.7) (thickness 0.15)) (justify left bottom))
    )
    (fp_text user "Author: Antmicro" (at -2.601 7.599) (layer "F.Fab") hide
        (effects (font (size 0.7 0.7) (thickness 0.15)) (justify left bottom))
    )
    (fp_circle (center 0 0) (end 3.1 0)
      (stroke (width 0.12) (type solid)) (fill none) (layer "F.SilkS"))
    (fp_circle (center 0 0) (end 3.15 0)
      (stroke (width 0.05) (type solid)) (fill none) (layer "F.CrtYd"))
    (pad "" smd custom (at -1.709 -1.709) (size 0.62 0.62) (layers "F.Paste")
      (options (clearance outline) (anchor circle))
      (primitives
        (gr_arc (start -0.250195 1.279127) (mid 0.285453 0.294389) (end 1.266786 -0.24747) (width 0.2))
        (gr_arc (start -0.34334 1.279127) (mid 0.221018 0.229971) (end 1.266737 -0.340731) (width 0.2))
        (gr_arc (start -0.436309 1.279127) (mid 0.15516 0.166988) (end 1.262733 -0.432988) (width 0.2))
        (gr_arc (start -0.529126 1.279127) (mid 0.093127 0.100154) (end 1.269368 -0.527248) (width 0.2))
        (gr_arc (start -0.621807 1.279127) (mid 0.0309 0.033527) (end 1.275473 -0.621136) (width 0.2))
        (gr_arc (start -0.71437 1.279127) (mid -0.037758 -0.026651) (end 1.263665 -0.711602) (width 0.2))
        (gr_arc (start -0.806826 1.279127) (mid -0.105832 -0.087398) (end 1.253445 -0.802344) (width 0.2))
        (gr_arc (start -0.899187 1.279127) (mid -0.163611 -0.158516) (end 1.272017 -0.898016) (width 0.2))
        (gr_arc (start -0.991463 1.279127) (mid -0.228522 -0.222449) (end 1.270645 -0.990112) (width 0.2))
        (gr_arc (start -1.083663 1.279127) (mid -0.294507 -0.285313) (end 1.266278 -1.081674) (width 0.2))
        (gr_line (start 1.279127 -0.250195) (end 1.279127 -1.083663) (width 0.2))
        (gr_line (start -0.250195 1.279127) (end -1.083663 1.279127) (width 0.2))
      ))
    (pad "" smd custom (at -1.709 1.7 90) (size 0.62 0.62) (layers "F.Paste")
      (options (clearance outline) (anchor circle))
      (primitives
        (gr_arc (start -0.250195 1.279127) (mid 0.285453 0.294389) (end 1.266786 -0.24747) (width 0.2))
        (gr_arc (start -0.34334 1.279127) (mid 0.221018 0.229971) (end 1.266737 -0.340731) (width 0.2))
        (gr_arc (start -0.436309 1.279127) (mid 0.15516 0.166988) (end 1.262733 -0.432988) (width 0.2))
        (gr_arc (start -0.529126 1.279127) (mid 0.093127 0.100154) (end 1.269368 -0.527248) (width 0.2))
        (gr_arc (start -0.621807 1.279127) (mid 0.0309 0.033527) (end 1.275473 -0.621136) (width 0.2))
        (gr_arc (start -0.71437 1.279127) (mid -0.037758 -0.026651) (end 1.263665 -0.711602) (width 0.2))
        (gr_arc (start -0.806826 1.279127) (mid -0.105832 -0.087398) (end 1.253445 -0.802344) (width 0.2))
        (gr_arc (start -0.899187 1.279127) (mid -0.163611 -0.158516) (end 1.272017 -0.898016) (width 0.2))
        (gr_arc (start -0.991463 1.279127) (mid -0.228522 -0.222449) (end 1.270645 -0.990112) (width 0.2))
        (gr_arc (start -1.083663 1.279127) (mid -0.294507 -0.285313) (end 1.266278 -1.081674) (width 0.2))
        (gr_line (start 1.279127 -0.250195) (end 1.279127 -1.083663) (width 0.2))
        (gr_line (start -0.250195 1.279127) (end -1.083663 1.279127) (width 0.2))
      ))
    (pad "" smd custom (at 1.7 -1.709 270) (size 0.62 0.62) (layers "F.Paste")
      (options (clearance outline) (anchor circle))
      (primitives
        (gr_arc (start -0.250195 1.279127) (mid 0.285453 0.294389) (end 1.266786 -0.24747) (width 0.2))
        (gr_arc (start -0.34334 1.279127) (mid 0.221018 0.229971) (end 1.266737 -0.340731) (width 0.2))
        (gr_arc (start -0.436309 1.279127) (mid 0.15516 0.166988) (end 1.262733 -0.432988) (width 0.2))
        (gr_arc (start -0.529126 1.279127) (mid 0.093127 0.100154) (end 1.269368 -0.527248) (width 0.2))
        (gr_arc (start -0.621807 1.279127) (mid 0.0309 0.033527) (end 1.275473 -0.621136) (width 0.2))
        (gr_arc (start -0.71437 1.279127) (mid -0.037758 -0.026651) (end 1.263665 -0.711602) (width 0.2))
        (gr_arc (start -0.806826 1.279127) (mid -0.105832 -0.087398) (end 1.253445 -0.802344) (width 0.2))
        (gr_arc (start -0.899187 1.279127) (mid -0.163611 -0.158516) (end 1.272017 -0.898016) (width 0.2))
        (gr_arc (start -0.991463 1.279127) (mid -0.228522 -0.222449) (end 1.270645 -0.990112) (width 0.2))
        (gr_arc (start -1.083663 1.279127) (mid -0.294507 -0.285313) (end 1.266278 -1.081674) (width 0.2))
        (gr_line (start 1.279127 -0.250195) (end 1.279127 -1.083663) (width 0.2))
        (gr_line (start -0.250195 1.279127) (end -1.083663 1.279127) (width 0.2))
      ))
    (pad "" smd custom (at 1.7 1.7 180) (size 0.62 0.62) (layers "F.Paste")
      (options (clearance outline) (anchor circle))
      (primitives
        (gr_arc (start -0.250195 1.279127) (mid 0.285453 0.294389) (end 1.266786 -0.24747) (width 0.2))
        (gr_arc (start -0.34334 1.279127) (mid 0.221018 0.229971) (end 1.266737 -0.340731) (width 0.2))
        (gr_arc (start -0.436309 1.279127) (mid 0.15516 0.166988) (end 1.262733 -0.432988) (width 0.2))
        (gr_arc (start -0.529126 1.279127) (mid 0.093127 0.100154) (end 1.269368 -0.527248) (width 0.2))
        (gr_arc (start -0.621807 1.279127) (mid 0.0309 0.033527) (end 1.275473 -0.621136) (width 0.2))
        (gr_arc (start -0.71437 1.279127) (mid -0.037758 -0.026651) (end 1.263665 -0.711602) (width 0.2))
        (gr_arc (start -0.806826 1.279127) (mid -0.105832 -0.087398) (end 1.253445 -0.802344) (width 0.2))
        (gr_arc (start -0.899187 1.279127) (mid -0.163611 -0.158516) (end 1.272017 -0.898016) (width 0.2))
        (gr_arc (start -0.991463 1.279127) (mid -0.228522 -0.222449) (end 1.270645 -0.990112) (width 0.2))
        (gr_arc (start -1.083663 1.279127) (mid -0.294507 -0.285313) (end 1.266278 -1.081674) (width 0.2))
        (gr_line (start 1.279127 -0.250195) (end 1.279127 -1.083663) (width 0.2))
        (gr_line (start -0.250195 1.279127) (end -1.083663 1.279127) (width 0.2))
      ))
    (pad "1" thru_hole circle (at 0 0) (size 6 6) (drill 3.7) (layers "*.Cu" "*.Mask")
      (net 220 "unconnected-(SP5-Pad1)") (pintype "passive+no_connect") (solder_paste_margin -1.2))
  )

  (footprint "scalenode-cm4-baseboard-footprints:Spacer_Drill3.7mm_H3mm_9774030151R" (layer "F.Cu")
    (at 145.488 93.2)
    (property "Author" "Antmicro")
    (property "License" "Apache-2.0")
    (property "MPN" "9774030151R")
    (property "Manufacturer" "Würth Elektronik")
    (property "Sheetfile" "compute-module.kicad_sch")
    (property "Sheetname" "Compute module")
    (property "ki_description" "Spacer, SMT,  Steel, Swage Round, 5.1mmx3mm, M3 Thread, WA-SMSI Series")
    (property "ki_keywords" "SPACER")
    (attr through_hole)
    (fp_text reference "SP4" (at -0.713 -3.65) (layer "F.SilkS")
        (effects (font (size 0.7 0.7) (thickness 0.15)) (justify left bottom))
    )
    (fp_text value "Spacer_Drill3.7mm_H3mm_9774030151R" (at 1.762 2.475) (layer "F.Fab")
        (effects (font (size 0.7 0.7) (thickness 0.15)) (justify left bottom))
    )
    (fp_text user "Author: Antmicro" (at -2.601 7.599) (layer "F.Fab") hide
        (effects (font (size 0.7 0.7) (thickness 0.15)) (justify left bottom))
    )
    (fp_text user "License: Apache-2.0" (at -2.601 8.8) (layer "F.Fab") hide
        (effects (font (size 0.7 0.7) (thickness 0.15)) (justify left bottom))
    )
    (fp_text user "${REFERENCE}" (at -2.601 6.398) (layer "F.Fab") hide
        (effects (font (size 0.7 0.7) (thickness 0.15)) (justify left bottom))
    )
    (fp_circle (center 0 0) (end 3.1 0)
      (stroke (width 0.12) (type solid)) (fill none) (layer "F.SilkS"))
    (fp_circle (center 0 0) (end 3.15 0)
      (stroke (width 0.05) (type solid)) (fill none) (layer "F.CrtYd"))
    (pad "" smd custom (at -1.709 -1.709) (size 0.62 0.62) (layers "F.Paste")
      (options (clearance outline) (anchor circle))
      (primitives
        (gr_arc (start -0.250195 1.279127) (mid 0.285453 0.294389) (end 1.266786 -0.24747) (width 0.2))
        (gr_arc (start -0.34334 1.279127) (mid 0.221018 0.229971) (end 1.266737 -0.340731) (width 0.2))
        (gr_arc (start -0.436309 1.279127) (mid 0.15516 0.166988) (end 1.262733 -0.432988) (width 0.2))
        (gr_arc (start -0.529126 1.279127) (mid 0.093127 0.100154) (end 1.269368 -0.527248) (width 0.2))
        (gr_arc (start -0.621807 1.279127) (mid 0.0309 0.033527) (end 1.275473 -0.621136) (width 0.2))
        (gr_arc (start -0.71437 1.279127) (mid -0.037758 -0.026651) (end 1.263665 -0.711602) (width 0.2))
        (gr_arc (start -0.806826 1.279127) (mid -0.105832 -0.087398) (end 1.253445 -0.802344) (width 0.2))
        (gr_arc (start -0.899187 1.279127) (mid -0.163611 -0.158516) (end 1.272017 -0.898016) (width 0.2))
        (gr_arc (start -0.991463 1.279127) (mid -0.228522 -0.222449) (end 1.270645 -0.990112) (width 0.2))
        (gr_arc (start -1.083663 1.279127) (mid -0.294507 -0.285313) (end 1.266278 -1.081674) (width 0.2))
        (gr_line (start 1.279127 -0.250195) (end 1.279127 -1.083663) (width 0.2))
        (gr_line (start -0.250195 1.279127) (end -1.083663 1.279127) (width 0.2))
      ))
    (pad "" smd custom (at -1.709 1.7 90) (size 0.62 0.62) (layers "F.Paste")
      (options (clearance outline) (anchor circle))
      (primitives
        (gr_arc (start -0.250195 1.279127) (mid 0.285453 0.294389) (end 1.266786 -0.24747) (width 0.2))
        (gr_arc (start -0.34334 1.279127) (mid 0.221018 0.229971) (end 1.266737 -0.340731) (width 0.2))
        (gr_arc (start -0.436309 1.279127) (mid 0.15516 0.166988) (end 1.262733 -0.432988) (width 0.2))
        (gr_arc (start -0.529126 1.279127) (mid 0.093127 0.100154) (end 1.269368 -0.527248) (width 0.2))
        (gr_arc (start -0.621807 1.279127) (mid 0.0309 0.033527) (end 1.275473 -0.621136) (width 0.2))
        (gr_arc (start -0.71437 1.279127) (mid -0.037758 -0.026651) (end 1.263665 -0.711602) (width 0.2))
        (gr_arc (start -0.806826 1.279127) (mid -0.105832 -0.087398) (end 1.253445 -0.802344) (width 0.2))
        (gr_arc (start -0.899187 1.279127) (mid -0.163611 -0.158516) (end 1.272017 -0.898016) (width 0.2))
        (gr_arc (start -0.991463 1.279127) (mid -0.228522 -0.222449) (end 1.270645 -0.990112) (width 0.2))
        (gr_arc (start -1.083663 1.279127) (mid -0.294507 -0.285313) (end 1.266278 -1.081674) (width 0.2))
        (gr_line (start 1.279127 -0.250195) (end 1.279127 -1.083663) (width 0.2))
        (gr_line (start -0.250195 1.279127) (end -1.083663 1.279127) (width 0.2))
      ))
    (pad "" smd custom (at 1.7 -1.709 270) (size 0.62 0.62) (layers "F.Paste")
      (options (clearance outline) (anchor circle))
      (primitives
        (gr_arc (start -0.250195 1.279127) (mid 0.285453 0.294389) (end 1.266786 -0.24747) (width 0.2))
        (gr_arc (start -0.34334 1.279127) (mid 0.221018 0.229971) (end 1.266737 -0.340731) (width 0.2))
        (gr_arc (start -0.436309 1.279127) (mid 0.15516 0.166988) (end 1.262733 -0.432988) (width 0.2))
        (gr_arc (start -0.529126 1.279127) (mid 0.093127 0.100154) (end 1.269368 -0.527248) (width 0.2))
        (gr_arc (start -0.621807 1.279127) (mid 0.0309 0.033527) (end 1.275473 -0.621136) (width 0.2))
        (gr_arc (start -0.71437 1.279127) (mid -0.037758 -0.026651) (end 1.263665 -0.711602) (width 0.2))
        (gr_arc (start -0.806826 1.279127) (mid -0.105832 -0.087398) (end 1.253445 -0.802344) (width 0.2))
        (gr_arc (start -0.899187 1.279127) (mid -0.163611 -0.158516) (end 1.272017 -0.898016) (width 0.2))
        (gr_arc (start -0.991463 1.279127) (mid -0.228522 -0.222449) (end 1.270645 -0.990112) (width 0.2))
        (gr_arc (start -1.083663 1.279127) (mid -0.294507 -0.285313) (end 1.266278 -1.081674) (width 0.2))
        (gr_line (start 1.279127 -0.250195) (end 1.279127 -1.083663) (width 0.2))
        (gr_line (start -0.250195 1.279127) (end -1.083663 1.279127) (width 0.2))
      ))
    (pad "" smd custom (at 1.7 1.7 180) (size 0.62 0.62) (layers "F.Paste")
      (options (clearance outline) (anchor circle))
      (primitives
        (gr_arc (start -0.250195 1.279127) (mid 0.285453 0.294389) (end 1.266786 -0.24747) (width 0.2))
        (gr_arc (start -0.34334 1.279127) (mid 0.221018 0.229971) (end 1.266737 -0.340731) (width 0.2))
        (gr_arc (start -0.436309 1.279127) (mid 0.15516 0.166988) (end 1.262733 -0.432988) (width 0.2))
        (gr_arc (start -0.529126 1.279127) (mid 0.093127 0.100154) (end 1.269368 -0.527248) (width 0.2))
        (gr_arc (start -0.621807 1.279127) (mid 0.0309 0.033527) (end 1.275473 -0.621136) (width 0.2))
        (gr_arc (start -0.71437 1.279127) (mid -0.037758 -0.026651) (end 1.263665 -0.711602) (width 0.2))
        (gr_arc (start -0.806826 1.279127) (mid -0.105832 -0.087398) (end 1.253445 -0.802344) (width 0.2))
        (gr_arc (start -0.899187 1.279127) (mid -0.163611 -0.158516) (end 1.272017 -0.898016) (width 0.2))
        (gr_arc (start -0.991463 1.279127) (mid -0.228522 -0.222449) (end 1.270645 -0.990112) (width 0.2))
        (gr_arc (start -1.083663 1.279127) (mid -0.294507 -0.285313) (end 1.266278 -1.081674) (width 0.2))
        (gr_line (start 1.279127 -0.250195) (end 1.279127 -1.083663) (width 0.2))
        (gr_line (start -0.250195 1.279127) (end -1.083663 1.279127) (width 0.2))
      ))
    (pad "1" thru_hole circle (at 0 0) (size 6 6) (drill 3.7) (layers "*.Cu" "*.Mask")
      (net 219 "unconnected-(SP4-Pad1)") (pintype "passive+no_connect") (solder_paste_margin -1.2))
  )

  (footprint "scalenode-cm4-baseboard-footprints:Spacer_Drill3.7mm_H3mm_9774030151R" (layer "F.Cu")
    (at 193.488 60.2)
    (property "Author" "Antmicro")
    (property "License" "Apache-2.0")
    (property "MPN" "9774030151R")
    (property "Manufacturer" "Würth Elektronik")
    (property "Sheetfile" "compute-module.kicad_sch")
    (property "Sheetname" "Compute module")
    (property "ki_description" "Spacer, SMT,  Steel, Swage Round, 5.1mmx3mm, M3 Thread, WA-SMSI Series")
    (property "ki_keywords" "SPACER")
    (attr through_hole)
    (fp_text reference "SP3" (at -0.052 4.225) (layer "F.SilkS")
        (effects (font (size 0.7 0.7) (thickness 0.15)) (justify left bottom))
    )
    (fp_text value "Spacer_Drill3.7mm_H3mm_9774030151R" (at -0.102 4.398) (layer "F.Fab")
        (effects (font (size 0.7 0.7) (thickness 0.15)) (justify left bottom))
    )
    (fp_text user "${REFERENCE}" (at -2.601 6.398) (layer "F.Fab") hide
        (effects (font (size 0.7 0.7) (thickness 0.15)) (justify left bottom))
    )
    (fp_text user "License: Apache-2.0" (at -2.601 8.8) (layer "F.Fab") hide
        (effects (font (size 0.7 0.7) (thickness 0.15)) (justify left bottom))
    )
    (fp_text user "Author: Antmicro" (at -2.601 7.599) (layer "F.Fab") hide
        (effects (font (size 0.7 0.7) (thickness 0.15)) (justify left bottom))
    )
    (fp_circle (center 0 0) (end 3.1 0)
      (stroke (width 0.12) (type solid)) (fill none) (layer "F.SilkS"))
    (fp_circle (center 0 0) (end 3.15 0)
      (stroke (width 0.05) (type solid)) (fill none) (layer "F.CrtYd"))
    (pad "" smd custom (at -1.709 -1.709) (size 0.62 0.62) (layers "F.Paste")
      (options (clearance outline) (anchor circle))
      (primitives
        (gr_arc (start -0.250195 1.279127) (mid 0.285453 0.294389) (end 1.266786 -0.24747) (width 0.2))
        (gr_arc (start -0.34334 1.279127) (mid 0.221018 0.229971) (end 1.266737 -0.340731) (width 0.2))
        (gr_arc (start -0.436309 1.279127) (mid 0.15516 0.166988) (end 1.262733 -0.432988) (width 0.2))
        (gr_arc (start -0.529126 1.279127) (mid 0.093127 0.100154) (end 1.269368 -0.527248) (width 0.2))
        (gr_arc (start -0.621807 1.279127) (mid 0.0309 0.033527) (end 1.275473 -0.621136) (width 0.2))
        (gr_arc (start -0.71437 1.279127) (mid -0.037758 -0.026651) (end 1.263665 -0.711602) (width 0.2))
        (gr_arc (start -0.806826 1.279127) (mid -0.105832 -0.087398) (end 1.253445 -0.802344) (width 0.2))
        (gr_arc (start -0.899187 1.279127) (mid -0.163611 -0.158516) (end 1.272017 -0.898016) (width 0.2))
        (gr_arc (start -0.991463 1.279127) (mid -0.228522 -0.222449) (end 1.270645 -0.990112) (width 0.2))
        (gr_arc (start -1.083663 1.279127) (mid -0.294507 -0.285313) (end 1.266278 -1.081674) (width 0.2))
        (gr_line (start 1.279127 -0.250195) (end 1.279127 -1.083663) (width 0.2))
        (gr_line (start -0.250195 1.279127) (end -1.083663 1.279127) (width 0.2))
      ))
    (pad "" smd custom (at -1.709 1.7 90) (size 0.62 0.62) (layers "F.Paste")
      (options (clearance outline) (anchor circle))
      (primitives
        (gr_arc (start -0.250195 1.279127) (mid 0.285453 0.294389) (end 1.266786 -0.24747) (width 0.2))
        (gr_arc (start -0.34334 1.279127) (mid 0.221018 0.229971) (end 1.266737 -0.340731) (width 0.2))
        (gr_arc (start -0.436309 1.279127) (mid 0.15516 0.166988) (end 1.262733 -0.432988) (width 0.2))
        (gr_arc (start -0.529126 1.279127) (mid 0.093127 0.100154) (end 1.269368 -0.527248) (width 0.2))
        (gr_arc (start -0.621807 1.279127) (mid 0.0309 0.033527) (end 1.275473 -0.621136) (width 0.2))
        (gr_arc (start -0.71437 1.279127) (mid -0.037758 -0.026651) (end 1.263665 -0.711602) (width 0.2))
        (gr_arc (start -0.806826 1.279127) (mid -0.105832 -0.087398) (end 1.253445 -0.802344) (width 0.2))
        (gr_arc (start -0.899187 1.279127) (mid -0.163611 -0.158516) (end 1.272017 -0.898016) (width 0.2))
        (gr_arc (start -0.991463 1.279127) (mid -0.228522 -0.222449) (end 1.270645 -0.990112) (width 0.2))
        (gr_arc (start -1.083663 1.279127) (mid -0.294507 -0.285313) (end 1.266278 -1.081674) (width 0.2))
        (gr_line (start 1.279127 -0.250195) (end 1.279127 -1.083663) (width 0.2))
        (gr_line (start -0.250195 1.279127) (end -1.083663 1.279127) (width 0.2))
      ))
    (pad "" smd custom (at 1.7 -1.709 270) (size 0.62 0.62) (layers "F.Paste")
      (options (clearance outline) (anchor circle))
      (primitives
        (gr_arc (start -0.250195 1.279127) (mid 0.285453 0.294389) (end 1.266786 -0.24747) (width 0.2))
        (gr_arc (start -0.34334 1.279127) (mid 0.221018 0.229971) (end 1.266737 -0.340731) (width 0.2))
        (gr_arc (start -0.436309 1.279127) (mid 0.15516 0.166988) (end 1.262733 -0.432988) (width 0.2))
        (gr_arc (start -0.529126 1.279127) (mid 0.093127 0.100154) (end 1.269368 -0.527248) (width 0.2))
        (gr_arc (start -0.621807 1.279127) (mid 0.0309 0.033527) (end 1.275473 -0.621136) (width 0.2))
        (gr_arc (start -0.71437 1.279127) (mid -0.037758 -0.026651) (end 1.263665 -0.711602) (width 0.2))
        (gr_arc (start -0.806826 1.279127) (mid -0.105832 -0.087398) (end 1.253445 -0.802344) (width 0.2))
        (gr_arc (start -0.899187 1.279127) (mid -0.163611 -0.158516) (end 1.272017 -0.898016) (width 0.2))
        (gr_arc (start -0.991463 1.279127) (mid -0.228522 -0.222449) (end 1.270645 -0.990112) (width 0.2))
        (gr_arc (start -1.083663 1.279127) (mid -0.294507 -0.285313) (end 1.266278 -1.081674) (width 0.2))
        (gr_line (start 1.279127 -0.250195) (end 1.279127 -1.083663) (width 0.2))
        (gr_line (start -0.250195 1.279127) (end -1.083663 1.279127) (width 0.2))
      ))
    (pad "" smd custom (at 1.7 1.7 180) (size 0.62 0.62) (layers "F.Paste")
      (options (clearance outline) (anchor circle))
      (primitives
        (gr_arc (start -0.250195 1.279127) (mid 0.285453 0.294389) (end 1.266786 -0.24747) (width 0.2))
        (gr_arc (start -0.34334 1.279127) (mid 0.221018 0.229971) (end 1.266737 -0.340731) (width 0.2))
        (gr_arc (start -0.436309 1.279127) (mid 0.15516 0.166988) (end 1.262733 -0.432988) (width 0.2))
        (gr_arc (start -0.529126 1.279127) (mid 0.093127 0.100154) (end 1.269368 -0.527248) (width 0.2))
        (gr_arc (start -0.621807 1.279127) (mid 0.0309 0.033527) (end 1.275473 -0.621136) (width 0.2))
        (gr_arc (start -0.71437 1.279127) (mid -0.037758 -0.026651) (end 1.263665 -0.711602) (width 0.2))
        (gr_arc (start -0.806826 1.279127) (mid -0.105832 -0.087398) (end 1.253445 -0.802344) (width 0.2))
        (gr_arc (start -0.899187 1.279127) (mid -0.163611 -0.158516) (end 1.272017 -0.898016) (width 0.2))
        (gr_arc (start -0.991463 1.279127) (mid -0.228522 -0.222449) (end 1.270645 -0.990112) (width 0.2))
        (gr_arc (start -1.083663 1.279127) (mid -0.294507 -0.285313) (end 1.266278 -1.081674) (width 0.2))
        (gr_line (start 1.279127 -0.250195) (end 1.279127 -1.083663) (width 0.2))
        (gr_line (start -0.250195 1.279127) (end -1.083663 1.279127) (width 0.2))
      ))
    (pad "1" thru_hole circle (at 0 0) (size 6 6) (drill 3.7) (layers "*.Cu" "*.Mask")
      (net 218 "unconnected-(SP3-Pad1)") (pintype "passive+no_connect") (solder_paste_margin -1.2))
  )

  (footprint "scalenode-cm4-baseboard-footprints:Spacer_Drill3.7mm_H3mm_9774030151R" (layer "F.Cu")
    (at 145.488 60.2)
    (property "Author" "Antmicro")
    (property "License" "Apache-2.0")
    (property "MPN" "9774030151R")
    (property "Manufacturer" "Würth Elektronik")
    (property "Sheetfile" "compute-module.kicad_sch")
    (property "Sheetname" "Compute module")
    (property "ki_description" "Spacer, SMT,  Steel, Swage Round, 5.1mmx3mm, M3 Thread, WA-SMSI Series")
    (property "ki_keywords" "SPACER")
    (attr through_hole)
    (fp_text reference "SP2" (at -0.713 4.225) (layer "F.SilkS")
        (effects (font (size 0.7 0.7) (thickness 0.15)) (justify left bottom))
    )
    (fp_text value "Spacer_Drill3.7mm_H3mm_9774030151R" (at -0.102 4.398) (layer "F.Fab")
        (effects (font (size 0.7 0.7) (thickness 0.15)) (justify left bottom))
    )
    (fp_text user "${REFERENCE}" (at -2.601 6.398) (layer "F.Fab") hide
        (effects (font (size 0.7 0.7) (thickness 0.15)) (justify left bottom))
    )
    (fp_text user "Author: Antmicro" (at -2.601 7.599) (layer "F.Fab") hide
        (effects (font (size 0.7 0.7) (thickness 0.15)) (justify left bottom))
    )
    (fp_text user "License: Apache-2.0" (at -2.601 8.8) (layer "F.Fab") hide
        (effects (font (size 0.7 0.7) (thickness 0.15)) (justify left bottom))
    )
    (fp_circle (center 0 0) (end 3.1 0)
      (stroke (width 0.12) (type solid)) (fill none) (layer "F.SilkS"))
    (fp_circle (center 0 0) (end 3.15 0)
      (stroke (width 0.05) (type solid)) (fill none) (layer "F.CrtYd"))
    (pad "" smd custom (at -1.709 -1.709) (size 0.62 0.62) (layers "F.Paste")
      (options (clearance outline) (anchor circle))
      (primitives
        (gr_arc (start -0.250195 1.279127) (mid 0.285453 0.294389) (end 1.266786 -0.24747) (width 0.2))
        (gr_arc (start -0.34334 1.279127) (mid 0.221018 0.229971) (end 1.266737 -0.340731) (width 0.2))
        (gr_arc (start -0.436309 1.279127) (mid 0.15516 0.166988) (end 1.262733 -0.432988) (width 0.2))
        (gr_arc (start -0.529126 1.279127) (mid 0.093127 0.100154) (end 1.269368 -0.527248) (width 0.2))
        (gr_arc (start -0.621807 1.279127) (mid 0.0309 0.033527) (end 1.275473 -0.621136) (width 0.2))
        (gr_arc (start -0.71437 1.279127) (mid -0.037758 -0.026651) (end 1.263665 -0.711602) (width 0.2))
        (gr_arc (start -0.806826 1.279127) (mid -0.105832 -0.087398) (end 1.253445 -0.802344) (width 0.2))
        (gr_arc (start -0.899187 1.279127) (mid -0.163611 -0.158516) (end 1.272017 -0.898016) (width 0.2))
        (gr_arc (start -0.991463 1.279127) (mid -0.228522 -0.222449) (end 1.270645 -0.990112) (width 0.2))
        (gr_arc (start -1.083663 1.279127) (mid -0.294507 -0.285313) (end 1.266278 -1.081674) (width 0.2))
        (gr_line (start 1.279127 -0.250195) (end 1.279127 -1.083663) (width 0.2))
        (gr_line (start -0.250195 1.279127) (end -1.083663 1.279127) (width 0.2))
      ))
    (pad "" smd custom (at -1.709 1.7 90) (size 0.62 0.62) (layers "F.Paste")
      (options (clearance outline) (anchor circle))
      (primitives
        (gr_arc (start -0.250195 1.279127) (mid 0.285453 0.294389) (end 1.266786 -0.24747) (width 0.2))
        (gr_arc (start -0.34334 1.279127) (mid 0.221018 0.229971) (end 1.266737 -0.340731) (width 0.2))
        (gr_arc (start -0.436309 1.279127) (mid 0.15516 0.166988) (end 1.262733 -0.432988) (width 0.2))
        (gr_arc (start -0.529126 1.279127) (mid 0.093127 0.100154) (end 1.269368 -0.527248) (width 0.2))
        (gr_arc (start -0.621807 1.279127) (mid 0.0309 0.033527) (end 1.275473 -0.621136) (width 0.2))
        (gr_arc (start -0.71437 1.279127) (mid -0.037758 -0.026651) (end 1.263665 -0.711602) (width 0.2))
        (gr_arc (start -0.806826 1.279127) (mid -0.105832 -0.087398) (end 1.253445 -0.802344) (width 0.2))
        (gr_arc (start -0.899187 1.279127) (mid -0.163611 -0.158516) (end 1.272017 -0.898016) (width 0.2))
        (gr_arc (start -0.991463 1.279127) (mid -0.228522 -0.222449) (end 1.270645 -0.990112) (width 0.2))
        (gr_arc (start -1.083663 1.279127) (mid -0.294507 -0.285313) (end 1.266278 -1.081674) (width 0.2))
        (gr_line (start 1.279127 -0.250195) (end 1.279127 -1.083663) (width 0.2))
        (gr_line (start -0.250195 1.279127) (end -1.083663 1.279127) (width 0.2))
      ))
    (pad "" smd custom (at 1.7 -1.709 270) (size 0.62 0.62) (layers "F.Paste")
      (options (clearance outline) (anchor circle))
      (primitives
        (gr_arc (start -0.250195 1.279127) (mid 0.285453 0.294389) (end 1.266786 -0.24747) (width 0.2))
        (gr_arc (start -0.34334 1.279127) (mid 0.221018 0.229971) (end 1.266737 -0.340731) (width 0.2))
        (gr_arc (start -0.436309 1.279127) (mid 0.15516 0.166988) (end 1.262733 -0.432988) (width 0.2))
        (gr_arc (start -0.529126 1.279127) (mid 0.093127 0.100154) (end 1.269368 -0.527248) (width 0.2))
        (gr_arc (start -0.621807 1.279127) (mid 0.0309 0.033527) (end 1.275473 -0.621136) (width 0.2))
        (gr_arc (start -0.71437 1.279127) (mid -0.037758 -0.026651) (end 1.263665 -0.711602) (width 0.2))
        (gr_arc (start -0.806826 1.279127) (mid -0.105832 -0.087398) (end 1.253445 -0.802344) (width 0.2))
        (gr_arc (start -0.899187 1.279127) (mid -0.163611 -0.158516) (end 1.272017 -0.898016) (width 0.2))
        (gr_arc (start -0.991463 1.279127) (mid -0.228522 -0.222449) (end 1.270645 -0.990112) (width 0.2))
        (gr_arc (start -1.083663 1.279127) (mid -0.294507 -0.285313) (end 1.266278 -1.081674) (width 0.2))
        (gr_line (start 1.279127 -0.250195) (end 1.279127 -1.083663) (width 0.2))
        (gr_line (start -0.250195 1.279127) (end -1.083663 1.279127) (width 0.2))
      ))
    (pad "" smd custom (at 1.7 1.7 180) (size 0.62 0.62) (layers "F.Paste")
      (options (clearance outline) (anchor circle))
      (primitives
        (gr_arc (start -0.250195 1.279127) (mid 0.285453 0.294389) (end 1.266786 -0.24747) (width 0.2))
        (gr_arc (start -0.34334 1.279127) (mid 0.221018 0.229971) (end 1.266737 -0.340731) (width 0.2))
        (gr_arc (start -0.436309 1.279127) (mid 0.15516 0.166988) (end 1.262733 -0.432988) (width 0.2))
        (gr_arc (start -0.529126 1.279127) (mid 0.093127 0.100154) (end 1.269368 -0.527248) (width 0.2))
        (gr_arc (start -0.621807 1.279127) (mid 0.0309 0.033527) (end 1.275473 -0.621136) (width 0.2))
        (gr_arc (start -0.71437 1.279127) (mid -0.037758 -0.026651) (end 1.263665 -0.711602) (width 0.2))
        (gr_arc (start -0.806826 1.279127) (mid -0.105832 -0.087398) (end 1.253445 -0.802344) (width 0.2))
        (gr_arc (start -0.899187 1.279127) (mid -0.163611 -0.158516) (end 1.272017 -0.898016) (width 0.2))
        (gr_arc (start -0.991463 1.279127) (mid -0.228522 -0.222449) (end 1.270645 -0.990112) (width 0.2))
        (gr_arc (start -1.083663 1.279127) (mid -0.294507 -0.285313) (end 1.266278 -1.081674) (width 0.2))
        (gr_line (start 1.279127 -0.250195) (end 1.279127 -1.083663) (width 0.2))
        (gr_line (start -0.250195 1.279127) (end -1.083663 1.279127) (width 0.2))
      ))
    (pad "1" thru_hole circle (at 0 0) (size 6 6) (drill 3.7) (layers "*.Cu" "*.Mask")
      (net 217 "unconnected-(SP2-Pad1)") (pintype "passive+no_connect") (solder_paste_margin -1.2))
  )

  (footprint "scalenode-cm4-baseboard-footprints:R_0402_1005Metric" (layer "F.Cu")
    (at 159.99 74.67 -90)
    (descr "Resistor SMD 0402")
    (tags "resistor SMD 0402")
    (property "Author" "Antmicro")
    (property "License" "Apache-2.0")
    (property "MPN" "CR0402-FX-2201GLF")
    (property "Manufacturer" "Bourns")
    (property "Sheetfile" "interfaces.kicad_sch")
    (property "Sheetname" "Interfaces")
    (property "Tolerance" "1%")
    (property "Val" "2k2")
    (property "ki_description" "2k2 resistor in 0402 package with 1% tolerance")
    (attr smd)
    (fp_text reference "R15" (at 1.1 -1.41 90) (layer "F.SilkS")
        (effects (font (size 0.7 0.7) (thickness 0.15)) (justify left bottom))
    )
    (fp_text value "R_2k2_0402" (at 0 1.4 -90) (layer "F.Fab")
        (effects (font (size 0.7 0.7) (thickness 0.15)) (justify left bottom))
    )
    (fp_text user "Author: Antmicro" (at -0.95 4.169 -90) (layer "F.Fab") hide
        (effects (font (size 0.7 0.7) (thickness 0.15)) (justify left bottom))
    )
    (fp_text user "License: Apache-2.0" (at -0.95 5.169 -90) (layer "F.Fab") hide
        (effects (font (size 0.7 0.7) (thickness 0.15)) (justify left bottom))
    )
    (fp_text user "${REFERENCE}" (at -0.95 3.168 -90) (layer "F.Fab") hide
        (effects (font (size 0.7 0.7) (thickness 0.15)) (justify left bottom))
    )
    (fp_rect (start -0.95 -0.48) (end 0.95 0.48)
      (stroke (width 0.05) (type solid)) (fill none) (layer "F.CrtYd"))
    (fp_rect (start -0.5 -0.25) (end 0.5 0.25)
      (stroke (width 0.15) (type solid)) (fill none) (layer "F.Fab"))
    (pad "1" smd roundrect (at -0.485 0 270) (size 0.59 0.64) (layers "F.Cu" "F.Paste" "F.Mask") (roundrect_rratio 0.25)
      (net 11 "GND") (pintype "passive"))
    (pad "2" smd roundrect (at 0.485 0 270) (size 0.59 0.64) (layers "F.Cu" "F.Paste" "F.Mask") (roundrect_rratio 0.25)
      (net 95 "USBOTG_ID") (pintype "passive"))
  )

  (footprint "scalenode-cm4-baseboard-footprints:C_0402_1005Metric" (layer "F.Cu")
    (at 174.7652 83.7128)
    (descr "Capacitor SMD 0402")
    (tags "capacitor SMD 0402")
    (property "Author" "Antmicro")
    (property "Dielectric" "")
    (property "License" "Apache-2.0")
    (property "MPN" "C1005X6S1A105K050BC")
    (property "Manufacturer" "TDK")
    (property "Sheetfile" "interfaces.kicad_sch")
    (property "Sheetname" "Interfaces")
    (property "Val" "1u")
    (property "Voltage" "")
    (property "ki_description" " ")
    (attr smd)
    (fp_text reference "C14" (at 0.8848 0.3122) (layer "F.SilkS")
        (effects (font (size 0.7 0.7) (thickness 0.15)) (justify left bottom))
    )
    (fp_text value "C_1u_0402" (at 0 1.4) (layer "F.Fab")
        (effects (font (size 0.7 0.7) (thickness 0.15)) (justify left bottom))
    )
    (fp_text user "Author: Antmicro" (at -0.932 4.17) (layer "F.Fab") hide
        (effects (font (size 0.7 0.7) (thickness 0.15)) (justify left bottom))
    )
    (fp_text user "${REFERENCE}" (at -0.932 3.168) (layer "F.Fab") hide
        (effects (font (size 0.7 0.7) (thickness 0.15)) (justify left bottom))
    )
    (fp_text user "License: Apache-2.0" (at -0.932 5.17) (layer "F.Fab") hide
        (effects (font (size 0.7 0.7) (thickness 0.15)) (justify left bottom))
    )
    (fp_rect (start -0.94 -0.47) (end 0.94 0.47)
      (stroke (width 0.05) (type solid)) (fill none) (layer "F.CrtYd"))
    (fp_rect (start -0.499 -0.249) (end 0.499 0.249)
      (stroke (width 0.15) (type solid)) (fill none) (layer "F.Fab"))
    (pad "1" smd roundrect (at -0.484 0) (size 0.59 0.64) (layers "F.Cu" "F.Paste" "F.Mask") (roundrect_rratio 0.25)
      (net 232 "3V3_RPi") (pintype "passive"))
    (pad "2" smd roundrect (at 0.484 0) (size 0.59 0.64) (layers "F.Cu" "F.Paste" "F.Mask") (roundrect_rratio 0.25)
      (net 11 "GND") (pintype "passive"))
  )

  (footprint "scalenode-cm4-baseboard-footprints:C_0402_1005Metric" (layer "F.Cu")
    (at 174.7652 82.6968)
    (descr "Capacitor SMD 0402")
    (tags "capacitor SMD 0402")
    (property "Author" "Antmicro")
    (property "Dielectric" "X5R")
    (property "License" "Apache-2.0")
    (property "MPN" "GRM155R61H104KE14D")
    (property "Manufacturer" "Murata")
    (property "Sheetfile" "interfaces.kicad_sch")
    (property "Sheetname" "Interfaces")
    (property "Val" "100n")
    (property "Voltage" "50V")
    (property "ki_description" " ")
    (attr smd)
    (fp_text reference "C13" (at 0.8848 0.3532) (layer "F.SilkS")
        (effects (font (size 0.7 0.7) (thickness 0.15)) (justify left bottom))
    )
    (fp_text value "C_100n_0402" (at 0 1.4) (layer "F.Fab")
        (effects (font (size 0.7 0.7) (thickness 0.15)) (justify left bottom))
    )
    (fp_text user "Author: Antmicro" (at -0.932 4.17) (layer "F.Fab") hide
        (effects (font (size 0.7 0.7) (thickness 0.15)) (justify left bottom))
    )
    (fp_text user "${REFERENCE}" (at -0.932 3.168) (layer "F.Fab") hide
        (effects (font (size 0.7 0.7) (thickness 0.15)) (justify left bottom))
    )
    (fp_text user "License: Apache-2.0" (at -0.932 5.17) (layer "F.Fab") hide
        (effects (font (size 0.7 0.7) (thickness 0.15)) (justify left bottom))
    )
    (fp_rect (start -0.94 -0.47) (end 0.94 0.47)
      (stroke (width 0.05) (type solid)) (fill none) (layer "F.CrtYd"))
    (fp_rect (start -0.499 -0.249) (end 0.499 0.249)
      (stroke (width 0.15) (type solid)) (fill none) (layer "F.Fab"))
    (pad "1" smd roundrect (at -0.484 0) (size 0.59 0.64) (layers "F.Cu" "F.Paste" "F.Mask") (roundrect_rratio 0.25)
      (net 232 "3V3_RPi") (pintype "passive"))
    (pad "2" smd roundrect (at 0.484 0) (size 0.59 0.64) (layers "F.Cu" "F.Paste" "F.Mask") (roundrect_rratio 0.25)
      (net 11 "GND") (pintype "passive"))
  )

  (footprint "scalenode-cm4-baseboard-footprints:R_0402_1005Metric" (layer "F.Cu")
    (at 93.29 58.106 180)
    (descr "Resistor SMD 0402")
    (tags "resistor SMD 0402")
    (property "Author" "Antmicro")
    (property "License" "Apache-2.0")
    (property "MPN" "CR0402-FX-2200GLF")
    (property "Manufacturer" "Bourns")
    (property "Sheetfile" "poe.kicad_sch")
    (property "Sheetname" "PoE")
    (property "Tolerance" "1%")
    (property "Val" "220R")
    (property "ki_description" "220R resistor in 0402 package with 1% tolerance")
    (attr smd)
    (fp_text reference "R22" (at 0.815 0.531 180) (layer "F.SilkS")
        (effects (font (size 0.7 0.7) (thickness 0.15)) (justify left bottom))
    )
    (fp_text value "R_220R_0402" (at 4.39 -2.094 180) (layer "F.Fab")
        (effects (font (size 0.7 0.7) (thickness 0.15)) (justify left bottom))
    )
    (fp_text user "${REFERENCE}" (at -0.95 3.168 180) (layer "F.Fab") hide
        (effects (font (size 0.7 0.7) (thickness 0.15)) (justify left bottom))
    )
    (fp_text user "License: Apache-2.0" (at -0.95 5.169 180) (layer "F.Fab") hide
        (effects (font (size 0.7 0.7) (thickness 0.15)) (justify left bottom))
    )
    (fp_text user "Author: Antmicro" (at -0.95 4.169 180) (layer "F.Fab") hide
        (effects (font (size 0.7 0.7) (thickness 0.15)) (justify left bottom))
    )
    (fp_rect (start -0.95 -0.48) (end 0.95 0.48)
      (stroke (width 0.05) (type solid)) (fill none) (layer "F.CrtYd"))
    (fp_rect (start -0.5 -0.25) (end 0.5 0.25)
      (stroke (width 0.15) (type solid)) (fill none) (layer "F.Fab"))
    (pad "1" smd roundrect (at -0.485 0 180) (size 0.59 0.64) (layers "F.Cu" "F.Paste" "F.Mask") (roundrect_rratio 0.25)
      (net 226 "Net-(J6-Pad12)") (pintype "passive"))
    (pad "2" smd roundrect (at 0.485 0 180) (size 0.59 0.64) (layers "F.Cu" "F.Paste" "F.Mask") (roundrect_rratio 0.25)
      (net 232 "3V3_RPi") (pintype "passive"))
  )

  (footprint "scalenode-cm4-baseboard-footprints:R_0402_1005Metric" (layer "F.Cu")
    (at 91.25 58.106)
    (descr "Resistor SMD 0402")
    (tags "resistor SMD 0402")
    (property "Author" "Antmicro")
    (property "License" "Apache-2.0")
    (property "MPN" "CR0402-FX-2200GLF")
    (property "Manufacturer" "Bourns")
    (property "Sheetfile" "poe.kicad_sch")
    (property "Sheetname" "PoE")
    (property "Tolerance" "1%")
    (property "Val" "220R")
    (property "ki_description" "220R resistor in 0402 package with 1% tolerance")
    (attr smd)
    (fp_text reference "R21" (at -1.5 -0.531) (layer "F.SilkS")
        (effects (font (size 0.7 0.7) (thickness 0.15)) (justify left bottom))
    )
    (fp_text value "R_220R_0402" (at 0 1.4) (layer "F.Fab")
        (effects (font (size 0.7 0.7) (thickness 0.15)) (justify left bottom))
    )
    (fp_text user "License: Apache-2.0" (at -0.95 5.169) (layer "F.Fab") hide
        (effects (font (size 0.7 0.7) (thickness 0.15)) (justify left bottom))
    )
    (fp_text user "Author: Antmicro" (at -0.95 4.169) (layer "F.Fab") hide
        (effects (font (size 0.7 0.7) (thickness 0.15)) (justify left bottom))
    )
    (fp_text user "${REFERENCE}" (at -0.95 3.168) (layer "F.Fab") hide
        (effects (font (size 0.7 0.7) (thickness 0.15)) (justify left bottom))
    )
    (fp_rect (start -0.95 -0.48) (end 0.95 0.48)
      (stroke (width 0.05) (type solid)) (fill none) (layer "F.CrtYd"))
    (fp_rect (start -0.5 -0.25) (end 0.5 0.25)
      (stroke (width 0.15) (type solid)) (fill none) (layer "F.Fab"))
    (pad "1" smd roundrect (at -0.485 0) (size 0.59 0.64) (layers "F.Cu" "F.Paste" "F.Mask") (roundrect_rratio 0.25)
      (net 225 "Net-(J6-Pad10)") (pintype "passive"))
    (pad "2" smd roundrect (at 0.485 0) (size 0.59 0.64) (layers "F.Cu" "F.Paste" "F.Mask") (roundrect_rratio 0.25)
      (net 232 "3V3_RPi") (pintype "passive"))
  )

  (footprint "scalenode-cm4-baseboard-footprints:Conn_Socket_Hirose_DF40_2x50_DF40HC-3.0-100DS-0.4V" (layer "F.Cu")
    (at 167.17772 59.80168 180)
    (property "Author" "Antmicro")
    (property "License" "Apache-2.0")
    (property "MPN" "DF40HC(3.0)-100DS-0.4V(51)")
    (property "Manufacturer" "Hirose Electric")
    (property "Pitch" "0.4 mm")
    (property "Sheetfile" "compute-module.kicad_sch")
    (property "Sheetname" "Compute module")
    (property "ki_description" "100 Position Connector Receptacle, Center Strip Contacts Surface Mount Gold")
    (property "ki_keywords" "CONNECTOR, B2B, SOCKET")
    (attr smd)
    (fp_text reference "J7" (at -12.87 0.119) (layer "F.SilkS")
        (effects (font (size 0.7 0.7) (thickness 0.15)) (justify left bottom))
    )
    (fp_text value "Socket_Hirose_DF40_2x50_DF40HC-3.0-100DS-0.4V" (at 0.57772 0.90168) (layer "F.Fab")
        (effects (font (size 0.7 0.7) (thickness 0.15)) (justify left bottom))
    )
    (fp_text user "${REFERENCE}" (at -12.87 7.4 180) (layer "F.Fab") hide
        (effects (font (size 0.7 0.7) (thickness 0.15)) (justify left bottom))
    )
    (fp_text user "License: Apache-2.0" (at -12.87 4.999 180) (layer "F.Fab") hide
        (effects (font (size 0.7 0.7) (thickness 0.15)) (justify left bottom))
    )
    (fp_text user "Author: Antmicro" (at -12.87 6.2 180) (layer "F.Fab") hide
        (effects (font (size 0.7 0.7) (thickness 0.15)) (justify left bottom))
    )
    (fp_line (start -11.301 -1.44) (end -10.08 -1.44)
      (stroke (width 0.15) (type solid)) (layer "F.SilkS"))
    (fp_line (start -11.301 1.439) (end -11.301 -1.44)
      (stroke (width 0.15) (type solid)) (layer "F.SilkS"))
    (fp_line (start -11.301 1.439) (end -10.08 1.439)
      (stroke (width 0.15) (type solid)) (layer "F.SilkS"))
    (fp_line (start -10.15 2.534) (end -10.15 2.539)
      (stroke (width 0.15) (type solid)) (layer "F.SilkS"))
    (fp_line (start 11.3 -1.44) (end 10.079 -1.44)
      (stroke (width 0.15) (type solid)) (layer "F.SilkS"))
    (fp_line (start 11.3 -1.44) (end 11.3 1.439)
      (stroke (width 0.15) (type solid)) (layer "F.SilkS"))
    (fp_line (start 11.3 1.439) (end 10.079 1.439)
      (stroke (width 0.15) (type solid)) (layer "F.SilkS"))
    (fp_circle (center -12.051 1.54) (end -12 1.54)
      (stroke (width 0.15) (type solid)) (fill solid) (layer "F.SilkS"))
    (fp_line (start -11.75 -1.75) (end -11.75 1.74)
      (stroke (width 0.05) (type solid)) (layer "F.CrtYd"))
    (fp_line (start -11.75 1.74) (end -10.25 1.74)
      (stroke (width 0.05) (type solid)) (layer "F.CrtYd"))
    (fp_line (start -10.25 -2.25) (end -10.25 -1.75)
      (stroke (width 0.05) (type solid)) (layer "F.CrtYd"))
    (fp_line (start -10.25 -1.75) (end -11.75 -1.75)
      (stroke (width 0.05) (type solid)) (layer "F.CrtYd"))
    (fp_line (start -10.25 1.74) (end -10.25 2.24)
      (stroke (width 0.05) (type solid)) (layer "F.CrtYd"))
    (fp_line (start -10.25 2.24) (end 10.24 2.24)
      (stroke (width 0.05) (type solid)) (layer "F.CrtYd"))
    (fp_line (start 10.24 -2.25) (end -10.25 -2.25)
      (stroke (width 0.05) (type solid)) (layer "F.CrtYd"))
    (fp_line (start 10.24 -1.75) (end 10.24 -2.25)
      (stroke (width 0.05) (type solid)) (layer "F.CrtYd"))
    (fp_line (start 10.24 1.74) (end 11.74 1.74)
      (stroke (width 0.05) (type solid)) (layer "F.CrtYd"))
    (fp_line (start 10.24 2.24) (end 10.24 1.74)
      (stroke (width 0.05) (type solid)) (layer "F.CrtYd"))
    (fp_line (start 11.74 -1.75) (end 10.24 -1.75)
      (stroke (width 0.05) (type solid)) (layer "F.CrtYd"))
    (fp_line (start 11.74 1.74) (end 11.74 -1.75)
      (stroke (width 0.05) (type solid)) (layer "F.CrtYd"))
    (fp_poly
      (pts
        (xy -9.92 -1.19)
        (xy -9.7 -1.19)
        (xy -9.7 -0.76)
        (xy -9.92 -0.76)
      )

      (stroke (width 0.05) (type solid)) (fill solid) (layer "F.CrtYd"))
    (fp_poly
      (pts
        (xy -9.92 0.74)
        (xy -9.7 0.74)
        (xy -9.7 1.19)
        (xy -9.92 1.19)
      )

      (stroke (width 0.05) (type solid)) (fill solid) (layer "F.CrtYd"))
    (fp_poly
      (pts
        (xy -9.53 -1.19)
        (xy -9.31 -1.19)
        (xy -9.31 -0.76)
        (xy -9.53 -0.76)
      )

      (stroke (width 0.05) (type solid)) (fill solid) (layer "F.CrtYd"))
    (fp_poly
      (pts
        (xy -9.52 0.74)
        (xy -9.31 0.74)
        (xy -9.31 1.19)
        (xy -9.52 1.19)
      )

      (stroke (width 0.05) (type solid)) (fill solid) (layer "F.CrtYd"))
    (fp_poly
      (pts
        (xy -9.13 -1.19)
        (xy -8.91 -1.19)
        (xy -8.91 -0.76)
        (xy -9.13 -0.76)
      )

      (stroke (width 0.05) (type solid)) (fill solid) (layer "F.CrtYd"))
    (fp_poly
      (pts
        (xy -9.13 0.74)
        (xy -8.91 0.74)
        (xy -8.91 1.19)
        (xy -9.13 1.19)
      )

      (stroke (width 0.05) (type solid)) (fill solid) (layer "F.CrtYd"))
    (fp_poly
      (pts
        (xy -8.72 -1.19)
        (xy -8.5 -1.19)
        (xy -8.5 -0.76)
        (xy -8.72 -0.76)
      )

      (stroke (width 0.05) (type solid)) (fill solid) (layer "F.CrtYd"))
    (fp_poly
      (pts
        (xy -8.72 0.74)
        (xy -8.5 0.74)
        (xy -8.5 1.19)
        (xy -8.72 1.19)
      )

      (stroke (width 0.05) (type solid)) (fill solid) (layer "F.CrtYd"))
    (fp_poly
      (pts
        (xy -8.32 -1.19)
        (xy -8.1 -1.19)
        (xy -8.1 -0.76)
        (xy -8.32 -0.76)
      )

      (stroke (width 0.05) (type solid)) (fill solid) (layer "F.CrtYd"))
    (fp_poly
      (pts
        (xy -8.32 0.74)
        (xy -8.1 0.74)
        (xy -8.1 1.19)
        (xy -8.32 1.19)
      )

      (stroke (width 0.05) (type solid)) (fill solid) (layer "F.CrtYd"))
    (fp_poly
      (pts
        (xy -7.92 -1.19)
        (xy -7.71 -1.19)
        (xy -7.71 -0.76)
        (xy -7.92 -0.76)
      )

      (stroke (width 0.05) (type solid)) (fill solid) (layer "F.CrtYd"))
    (fp_poly
      (pts
        (xy -7.92 0.74)
        (xy -7.71 0.74)
        (xy -7.71 1.19)
        (xy -7.92 1.19)
      )

      (stroke (width 0.05) (type solid)) (fill solid) (layer "F.CrtYd"))
    (fp_poly
      (pts
        (xy -7.52 -1.19)
        (xy -7.3 -1.19)
        (xy -7.3 -0.76)
        (xy -7.52 -0.76)
      )

      (stroke (width 0.05) (type solid)) (fill solid) (layer "F.CrtYd"))
    (fp_poly
      (pts
        (xy -7.52 0.74)
        (xy -7.3 0.74)
        (xy -7.3 1.19)
        (xy -7.52 1.19)
      )

      (stroke (width 0.05) (type solid)) (fill solid) (layer "F.CrtYd"))
    (fp_poly
      (pts
        (xy -7.12 -1.19)
        (xy -6.91 -1.19)
        (xy -6.91 -0.76)
        (xy -7.12 -0.76)
      )

      (stroke (width 0.05) (type solid)) (fill solid) (layer "F.CrtYd"))
    (fp_poly
      (pts
        (xy -7.12 0.74)
        (xy -6.91 0.74)
        (xy -6.91 1.19)
        (xy -7.12 1.19)
      )

      (stroke (width 0.05) (type solid)) (fill solid) (layer "F.CrtYd"))
    (fp_poly
      (pts
        (xy -6.72 -1.19)
        (xy -6.5 -1.19)
        (xy -6.5 -0.76)
        (xy -6.72 -0.76)
      )

      (stroke (width 0.05) (type solid)) (fill solid) (layer "F.CrtYd"))
    (fp_poly
      (pts
        (xy -6.71 0.74)
        (xy -6.5 0.74)
        (xy -6.5 1.19)
        (xy -6.71 1.19)
      )

      (stroke (width 0.05) (type solid)) (fill solid) (layer "F.CrtYd"))
    (fp_poly
      (pts
        (xy -6.32 -1.19)
        (xy -6.1 -1.19)
        (xy -6.1 -0.76)
        (xy -6.32 -0.76)
      )

      (stroke (width 0.05) (type solid)) (fill solid) (layer "F.CrtYd"))
    (fp_poly
      (pts
        (xy -6.32 0.74)
        (xy -6.1 0.74)
        (xy -6.1 1.19)
        (xy -6.32 1.19)
      )

      (stroke (width 0.05) (type solid)) (fill solid) (layer "F.CrtYd"))
    (fp_poly
      (pts
        (xy -5.92 -1.19)
        (xy -5.71 -1.19)
        (xy -5.71 -0.76)
        (xy -5.92 -0.76)
      )

      (stroke (width 0.05) (type solid)) (fill solid) (layer "F.CrtYd"))
    (fp_poly
      (pts
        (xy -5.91 0.74)
        (xy -5.71 0.74)
        (xy -5.71 1.19)
        (xy -5.91 1.19)
      )

      (stroke (width 0.05) (type solid)) (fill solid) (layer "F.CrtYd"))
    (fp_poly
      (pts
        (xy -5.52 -1.19)
        (xy -5.3 -1.19)
        (xy -5.3 -0.76)
        (xy -5.52 -0.76)
      )

      (stroke (width 0.05) (type solid)) (fill solid) (layer "F.CrtYd"))
    (fp_poly
      (pts
        (xy -5.52 0.74)
        (xy -5.3 0.74)
        (xy -5.3 1.19)
        (xy -5.52 1.19)
      )

      (stroke (width 0.05) (type solid)) (fill solid) (layer "F.CrtYd"))
    (fp_poly
      (pts
        (xy -5.11 -1.19)
        (xy -4.91 -1.19)
        (xy -4.91 -0.76)
        (xy -5.11 -0.76)
      )

      (stroke (width 0.05) (type solid)) (fill solid) (layer "F.CrtYd"))
    (fp_poly
      (pts
        (xy -5.11 0.74)
        (xy -4.91 0.74)
        (xy -4.91 1.19)
        (xy -5.11 1.19)
      )

      (stroke (width 0.05) (type solid)) (fill solid) (layer "F.CrtYd"))
    (fp_poly
      (pts
        (xy -4.71 -1.19)
        (xy -4.5 -1.19)
        (xy -4.5 -0.76)
        (xy -4.71 -0.76)
      )

      (stroke (width 0.05) (type solid)) (fill solid) (layer "F.CrtYd"))
    (fp_poly
      (pts
        (xy -4.71 0.74)
        (xy -4.5 0.74)
        (xy -4.5 1.19)
        (xy -4.71 1.19)
      )

      (stroke (width 0.05) (type solid)) (fill solid) (layer "F.CrtYd"))
    (fp_poly
      (pts
        (xy -4.32 -1.19)
        (xy -4.1 -1.19)
        (xy -4.1 -0.76)
        (xy -4.32 -0.76)
      )

      (stroke (width 0.05) (type solid)) (fill solid) (layer "F.CrtYd"))
    (fp_poly
      (pts
        (xy -4.32 0.74)
        (xy -4.1 0.74)
        (xy -4.1 1.19)
        (xy -4.32 1.19)
      )

      (stroke (width 0.05) (type solid)) (fill solid) (layer "F.CrtYd"))
    (fp_poly
      (pts
        (xy -3.92 -1.19)
        (xy -3.71 -1.19)
        (xy -3.71 -0.76)
        (xy -3.92 -0.76)
      )

      (stroke (width 0.05) (type solid)) (fill solid) (layer "F.CrtYd"))
    (fp_poly
      (pts
        (xy -3.91 0.74)
        (xy -3.71 0.74)
        (xy -3.71 1.19)
        (xy -3.91 1.19)
      )

      (stroke (width 0.05) (type solid)) (fill solid) (layer "F.CrtYd"))
    (fp_poly
      (pts
        (xy -3.51 -1.19)
        (xy -3.3 -1.19)
        (xy -3.3 -0.76)
        (xy -3.51 -0.76)
      )

      (stroke (width 0.05) (type solid)) (fill solid) (layer "F.CrtYd"))
    (fp_poly
      (pts
        (xy -3.51 0.74)
        (xy -3.3 0.74)
        (xy -3.3 1.19)
        (xy -3.51 1.19)
      )

      (stroke (width 0.05) (type solid)) (fill solid) (layer "F.CrtYd"))
    (fp_poly
      (pts
        (xy -3.11 -1.19)
        (xy -2.9 -1.19)
        (xy -2.9 -0.76)
        (xy -3.11 -0.76)
      )

      (stroke (width 0.05) (type solid)) (fill solid) (layer "F.CrtYd"))
    (fp_poly
      (pts
        (xy -3.11 0.74)
        (xy -2.9 0.74)
        (xy -2.9 1.19)
        (xy -3.11 1.19)
      )

      (stroke (width 0.05) (type solid)) (fill solid) (layer "F.CrtYd"))
    (fp_poly
      (pts
        (xy -2.71 -1.19)
        (xy -2.5 -1.19)
        (xy -2.5 -0.76)
        (xy -2.71 -0.76)
      )

      (stroke (width 0.05) (type solid)) (fill solid) (layer "F.CrtYd"))
    (fp_poly
      (pts
        (xy -2.71 0.74)
        (xy -2.5 0.74)
        (xy -2.5 1.19)
        (xy -2.71 1.19)
      )

      (stroke (width 0.05) (type solid)) (fill solid) (layer "F.CrtYd"))
    (fp_poly
      (pts
        (xy -2.31 -1.19)
        (xy -2.11 -1.19)
        (xy -2.11 -0.76)
        (xy -2.31 -0.76)
      )

      (stroke (width 0.05) (type solid)) (fill solid) (layer "F.CrtYd"))
    (fp_poly
      (pts
        (xy -2.31 0.74)
        (xy -2.11 0.74)
        (xy -2.11 1.19)
        (xy -2.31 1.19)
      )

      (stroke (width 0.05) (type solid)) (fill solid) (layer "F.CrtYd"))
    (fp_poly
      (pts
        (xy -1.91 -1.19)
        (xy -1.7 -1.19)
        (xy -1.7 -0.76)
        (xy -1.91 -0.76)
      )

      (stroke (width 0.05) (type solid)) (fill solid) (layer "F.CrtYd"))
    (fp_poly
      (pts
        (xy -1.91 0.74)
        (xy -1.7 0.74)
        (xy -1.7 1.19)
        (xy -1.91 1.19)
      )

      (stroke (width 0.05) (type solid)) (fill solid) (layer "F.CrtYd"))
    (fp_poly
      (pts
        (xy -1.51 -1.19)
        (xy -1.31 -1.19)
        (xy -1.31 -0.76)
        (xy -1.51 -0.76)
      )

      (stroke (width 0.05) (type solid)) (fill solid) (layer "F.CrtYd"))
    (fp_poly
      (pts
        (xy -1.51 0.74)
        (xy -1.31 0.74)
        (xy -1.31 1.19)
        (xy -1.51 1.19)
      )

      (stroke (width 0.05) (type solid)) (fill solid) (layer "F.CrtYd"))
    (fp_poly
      (pts
        (xy -1.11 -1.19)
        (xy -0.91 -1.19)
        (xy -0.91 -0.76)
        (xy -1.11 -0.76)
      )

      (stroke (width 0.05) (type solid)) (fill solid) (layer "F.CrtYd"))
    (fp_poly
      (pts
        (xy -1.11 0.74)
        (xy -0.91 0.74)
        (xy -0.91 1.19)
        (xy -1.11 1.19)
      )

      (stroke (width 0.05) (type solid)) (fill solid) (layer "F.CrtYd"))
    (fp_poly
      (pts
        (xy -0.71 -1.19)
        (xy -0.5 -1.19)
        (xy -0.5 -0.76)
        (xy -0.71 -0.76)
      )

      (stroke (width 0.05) (type solid)) (fill solid) (layer "F.CrtYd"))
    (fp_poly
      (pts
        (xy -0.71 0.74)
        (xy -0.5 0.74)
        (xy -0.5 1.19)
        (xy -0.71 1.19)
      )

      (stroke (width 0.05) (type solid)) (fill solid) (layer "F.CrtYd"))
    (fp_poly
      (pts
        (xy -0.31 -1.19)
        (xy -0.11 -1.19)
        (xy -0.11 -0.76)
        (xy -0.31 -0.76)
      )

      (stroke (width 0.05) (type solid)) (fill solid) (layer "F.CrtYd"))
    (fp_poly
      (pts
        (xy -0.31 0.74)
        (xy -0.11 0.74)
        (xy -0.11 1.19)
        (xy -0.31 1.19)
      )

      (stroke (width 0.05) (type solid)) (fill solid) (layer "F.CrtYd"))
    (fp_poly
      (pts
        (xy 0.1 -1.19)
        (xy 0.29 -1.19)
        (xy 0.29 -0.76)
        (xy 0.1 -0.76)
      )

      (stroke (width 0.05) (type solid)) (fill solid) (layer "F.CrtYd"))
    (fp_poly
      (pts
        (xy 0.1 0.74)
        (xy 0.29 0.74)
        (xy 0.29 1.19)
        (xy 0.1 1.19)
      )

      (stroke (width 0.05) (type solid)) (fill solid) (layer "F.CrtYd"))
    (fp_poly
      (pts
        (xy 0.5 -1.19)
        (xy 0.69 -1.19)
        (xy 0.69 -0.76)
        (xy 0.5 -0.76)
      )

      (stroke (width 0.05) (type solid)) (fill solid) (layer "F.CrtYd"))
    (fp_poly
      (pts
        (xy 0.5 0.74)
        (xy 0.69 0.74)
        (xy 0.69 1.19)
        (xy 0.5 1.19)
      )

      (stroke (width 0.05) (type solid)) (fill solid) (layer "F.CrtYd"))
    (fp_poly
      (pts
        (xy 0.9 -1.19)
        (xy 1.1 -1.19)
        (xy 1.1 -0.76)
        (xy 0.9 -0.76)
      )

      (stroke (width 0.05) (type solid)) (fill solid) (layer "F.CrtYd"))
    (fp_poly
      (pts
        (xy 0.9 0.74)
        (xy 1.1 0.74)
        (xy 1.1 1.19)
        (xy 0.9 1.19)
      )

      (stroke (width 0.05) (type solid)) (fill solid) (layer "F.CrtYd"))
    (fp_poly
      (pts
        (xy 1.3 -1.19)
        (xy 1.49 -1.19)
        (xy 1.49 -0.76)
        (xy 1.3 -0.76)
      )

      (stroke (width 0.05) (type solid)) (fill solid) (layer "F.CrtYd"))
    (fp_poly
      (pts
        (xy 1.3 0.74)
        (xy 1.49 0.74)
        (xy 1.49 1.19)
        (xy 1.3 1.19)
      )

      (stroke (width 0.05) (type solid)) (fill solid) (layer "F.CrtYd"))
    (fp_poly
      (pts
        (xy 1.7 -1.19)
        (xy 1.89 -1.19)
        (xy 1.89 -0.76)
        (xy 1.7 -0.76)
      )

      (stroke (width 0.05) (type solid)) (fill solid) (layer "F.CrtYd"))
    (fp_poly
      (pts
        (xy 1.7 0.74)
        (xy 1.89 0.74)
        (xy 1.89 1.19)
        (xy 1.7 1.19)
      )

      (stroke (width 0.05) (type solid)) (fill solid) (layer "F.CrtYd"))
    (fp_poly
      (pts
        (xy 2.1 -1.19)
        (xy 2.29 -1.19)
        (xy 2.29 -0.76)
        (xy 2.1 -0.76)
      )

      (stroke (width 0.05) (type solid)) (fill solid) (layer "F.CrtYd"))
    (fp_poly
      (pts
        (xy 2.1 0.74)
        (xy 2.29 0.74)
        (xy 2.29 1.19)
        (xy 2.1 1.19)
      )

      (stroke (width 0.05) (type solid)) (fill solid) (layer "F.CrtYd"))
    (fp_poly
      (pts
        (xy 2.5 -1.19)
        (xy 2.7 -1.19)
        (xy 2.7 -0.76)
        (xy 2.5 -0.76)
      )

      (stroke (width 0.05) (type solid)) (fill solid) (layer "F.CrtYd"))
    (fp_poly
      (pts
        (xy 2.5 0.74)
        (xy 2.7 0.74)
        (xy 2.7 1.19)
        (xy 2.5 1.19)
      )

      (stroke (width 0.05) (type solid)) (fill solid) (layer "F.CrtYd"))
    (fp_poly
      (pts
        (xy 2.9 -1.19)
        (xy 3.1 -1.19)
        (xy 3.1 -0.76)
        (xy 2.9 -0.76)
      )

      (stroke (width 0.05) (type solid)) (fill solid) (layer "F.CrtYd"))
    (fp_poly
      (pts
        (xy 2.9 0.74)
        (xy 3.1 0.74)
        (xy 3.1 1.19)
        (xy 2.9 1.19)
      )

      (stroke (width 0.05) (type solid)) (fill solid) (layer "F.CrtYd"))
    (fp_poly
      (pts
        (xy 3.3 -1.19)
        (xy 3.49 -1.19)
        (xy 3.49 -0.76)
        (xy 3.3 -0.76)
      )

      (stroke (width 0.05) (type solid)) (fill solid) (layer "F.CrtYd"))
    (fp_poly
      (pts
        (xy 3.3 0.74)
        (xy 3.49 0.74)
        (xy 3.49 1.19)
        (xy 3.3 1.19)
      )

      (stroke (width 0.05) (type solid)) (fill solid) (layer "F.CrtYd"))
    (fp_poly
      (pts
        (xy 3.7 -1.19)
        (xy 3.89 -1.19)
        (xy 3.89 -0.76)
        (xy 3.7 -0.76)
      )

      (stroke (width 0.05) (type solid)) (fill solid) (layer "F.CrtYd"))
    (fp_poly
      (pts
        (xy 3.71 0.74)
        (xy 3.89 0.74)
        (xy 3.89 1.19)
        (xy 3.71 1.19)
      )

      (stroke (width 0.05) (type solid)) (fill solid) (layer "F.CrtYd"))
    (fp_poly
      (pts
        (xy 4.1 0.74)
        (xy 4.29 0.74)
        (xy 4.29 1.19)
        (xy 4.1 1.19)
      )

      (stroke (width 0.05) (type solid)) (fill solid) (layer "F.CrtYd"))
    (fp_poly
      (pts
        (xy 4.11 -1.19)
        (xy 4.29 -1.19)
        (xy 4.29 -0.76)
        (xy 4.11 -0.76)
      )

      (stroke (width 0.05) (type solid)) (fill solid) (layer "F.CrtYd"))
    (fp_poly
      (pts
        (xy 4.5 0.74)
        (xy 4.7 0.74)
        (xy 4.7 1.19)
        (xy 4.5 1.19)
      )

      (stroke (width 0.05) (type solid)) (fill solid) (layer "F.CrtYd"))
    (fp_poly
      (pts
        (xy 4.51 -1.19)
        (xy 4.7 -1.19)
        (xy 4.7 -0.76)
        (xy 4.51 -0.76)
      )

      (stroke (width 0.05) (type solid)) (fill solid) (layer "F.CrtYd"))
    (fp_poly
      (pts
        (xy 4.9 -1.19)
        (xy 5.09 -1.19)
        (xy 5.09 -0.76)
        (xy 4.9 -0.76)
      )

      (stroke (width 0.05) (type solid)) (fill solid) (layer "F.CrtYd"))
    (fp_poly
      (pts
        (xy 4.9 0.74)
        (xy 5.09 0.74)
        (xy 5.09 1.19)
        (xy 4.9 1.19)
      )

      (stroke (width 0.05) (type solid)) (fill solid) (layer "F.CrtYd"))
    (fp_poly
      (pts
        (xy 5.3 0.74)
        (xy 5.49 0.74)
        (xy 5.49 1.19)
        (xy 5.3 1.19)
      )

      (stroke (width 0.05) (type solid)) (fill solid) (layer "F.CrtYd"))
    (fp_poly
      (pts
        (xy 5.31 -1.19)
        (xy 5.49 -1.19)
        (xy 5.49 -0.76)
        (xy 5.31 -0.76)
      )

      (stroke (width 0.05) (type solid)) (fill solid) (layer "F.CrtYd"))
    (fp_poly
      (pts
        (xy 5.7 0.74)
        (xy 5.9 0.74)
        (xy 5.9 1.19)
        (xy 5.7 1.19)
      )

      (stroke (width 0.05) (type solid)) (fill solid) (layer "F.CrtYd"))
    (fp_poly
      (pts
        (xy 5.71 -1.19)
        (xy 5.9 -1.19)
        (xy 5.9 -0.76)
        (xy 5.71 -0.76)
      )

      (stroke (width 0.05) (type solid)) (fill solid) (layer "F.CrtYd"))
    (fp_poly
      (pts
        (xy 6.1 -1.19)
        (xy 6.29 -1.19)
        (xy 6.29 -0.76)
        (xy 6.1 -0.76)
      )

      (stroke (width 0.05) (type solid)) (fill solid) (layer "F.CrtYd"))
    (fp_poly
      (pts
        (xy 6.11 0.74)
        (xy 6.29 0.74)
        (xy 6.29 1.19)
        (xy 6.11 1.19)
      )

      (stroke (width 0.05) (type solid)) (fill solid) (layer "F.CrtYd"))
    (fp_poly
      (pts
        (xy 6.5 0.74)
        (xy 6.7 0.74)
        (xy 6.7 1.19)
        (xy 6.5 1.19)
      )

      (stroke (width 0.05) (type solid)) (fill solid) (layer "F.CrtYd"))
    (fp_poly
      (pts
        (xy 6.52 -1.19)
        (xy 6.7 -1.19)
        (xy 6.7 -0.76)
        (xy 6.52 -0.76)
      )

      (stroke (width 0.05) (type solid)) (fill solid) (layer "F.CrtYd"))
    (fp_poly
      (pts
        (xy 6.9 -1.19)
        (xy 7.09 -1.19)
        (xy 7.09 -0.76)
        (xy 6.9 -0.76)
      )

      (stroke (width 0.05) (type solid)) (fill solid) (layer "F.CrtYd"))
    (fp_poly
      (pts
        (xy 6.91 0.74)
        (xy 7.09 0.74)
        (xy 7.09 1.19)
        (xy 6.91 1.19)
      )

      (stroke (width 0.05) (type solid)) (fill solid) (layer "F.CrtYd"))
    (fp_poly
      (pts
        (xy 7.31 -1.19)
        (xy 7.49 -1.19)
        (xy 7.49 -0.76)
        (xy 7.31 -0.76)
      )

      (stroke (width 0.05) (type solid)) (fill solid) (layer "F.CrtYd"))
    (fp_poly
      (pts
        (xy 7.31 0.74)
        (xy 7.49 0.74)
        (xy 7.49 1.19)
        (xy 7.31 1.19)
      )

      (stroke (width 0.05) (type solid)) (fill solid) (layer "F.CrtYd"))
    (fp_poly
      (pts
        (xy 7.71 -1.19)
        (xy 7.9 -1.19)
        (xy 7.9 -0.76)
        (xy 7.71 -0.76)
      )

      (stroke (width 0.05) (type solid)) (fill solid) (layer "F.CrtYd"))
    (fp_poly
      (pts
        (xy 7.71 0.74)
        (xy 7.9 0.74)
        (xy 7.9 1.19)
        (xy 7.71 1.19)
      )

      (stroke (width 0.05) (type solid)) (fill solid) (layer "F.CrtYd"))
    (fp_poly
      (pts
        (xy 8.11 -1.19)
        (xy 8.3 -1.19)
        (xy 8.3 -0.76)
        (xy 8.11 -0.76)
      )

      (stroke (width 0.05) (type solid)) (fill solid) (layer "F.CrtYd"))
    (fp_poly
      (pts
        (xy 8.12 0.74)
        (xy 8.3 0.74)
        (xy 8.3 1.19)
        (xy 8.12 1.19)
      )

      (stroke (width 0.05) (type solid)) (fill solid) (layer "F.CrtYd"))
    (fp_poly
      (pts
        (xy 8.5 -1.19)
        (xy 8.69 -1.19)
        (xy 8.69 -0.76)
        (xy 8.5 -0.76)
      )

      (stroke (width 0.05) (type solid)) (fill solid) (layer "F.CrtYd"))
    (fp_poly
      (pts
        (xy 8.53 0.74)
        (xy 8.69 0.74)
        (xy 8.69 1.19)
        (xy 8.53 1.19)
      )

      (stroke (width 0.05) (type solid)) (fill solid) (layer "F.CrtYd"))
    (fp_poly
      (pts
        (xy 8.9 -1.19)
        (xy 9.09 -1.19)
        (xy 9.09 -0.76)
        (xy 8.9 -0.76)
      )

      (stroke (width 0.05) (type solid)) (fill solid) (layer "F.CrtYd"))
    (fp_poly
      (pts
        (xy 8.91 0.74)
        (xy 9.09 0.74)
        (xy 9.09 1.19)
        (xy 8.91 1.19)
      )

      (stroke (width 0.05) (type solid)) (fill solid) (layer "F.CrtYd"))
    (fp_poly
      (pts
        (xy 9.3 0.74)
        (xy 9.49 0.74)
        (xy 9.49 1.19)
        (xy 9.3 1.19)
      )

      (stroke (width 0.05) (type solid)) (fill solid) (layer "F.CrtYd"))
    (fp_poly
      (pts
        (xy 9.32 -1.19)
        (xy 9.49 -1.19)
        (xy 9.49 -0.76)
        (xy 9.32 -0.76)
      )

      (stroke (width 0.05) (type solid)) (fill solid) (layer "F.CrtYd"))
    (fp_poly
      (pts
        (xy 9.73 -1.19)
        (xy 9.9 -1.19)
        (xy 9.9 -0.76)
        (xy 9.73 -0.76)
      )

      (stroke (width 0.05) (type solid)) (fill solid) (layer "F.CrtYd"))
    (fp_poly
      (pts
        (xy 9.73 0.74)
        (xy 9.9 0.74)
        (xy 9.9 1.19)
        (xy 9.73 1.19)
      )

      (stroke (width 0.05) (type solid)) (fill solid) (layer "F.CrtYd"))
    (fp_line (start -11.301 -1.44) (end -10.08 -1.44)
      (stroke (width 0.15) (type solid)) (layer "F.Fab"))
    (fp_line (start -11.301 1.439) (end -11.301 -1.44)
      (stroke (width 0.15) (type solid)) (layer "F.Fab"))
    (fp_line (start -10.16 2.539) (end -10.15 2.539)
      (stroke (width 0.15) (type solid)) (layer "F.Fab"))
    (fp_line (start -10.08 -1.44) (end 10.079 -1.44)
      (stroke (width 0.15) (type solid)) (layer "F.Fab"))
    (fp_line (start -10.08 1.439) (end -11.301 1.439)
      (stroke (width 0.15) (type solid)) (layer "F.Fab"))
    (fp_line (start 10.079 -1.44) (end 11.3 -1.44)
      (stroke (width 0.15) (type solid)) (layer "F.Fab"))
    (fp_line (start 10.079 1.439) (end -10.061 1.439)
      (stroke (width 0.15) (type solid)) (layer "F.Fab"))
    (fp_line (start 11.3 -1.44) (end 11.3 1.439)
      (stroke (width 0.15) (type solid)) (layer "F.Fab"))
    (fp_line (start 11.3 1.439) (end 10.079 1.439)
      (stroke (width 0.15) (type solid)) (layer "F.Fab"))
    (pad "1" smd rect (at -9.801 1.54 180) (size 0.2 0.7) (layers "F.Cu" "F.Paste" "F.Mask")
      (net 11 "GND") (pintype "passive"))
    (pad "2" smd rect (at -9.801 -1.541 180) (size 0.2 0.7) (layers "F.Cu" "F.Paste" "F.Mask")
      (net 11 "GND") (pintype "passive"))
    (pad "3" smd rect (at -9.401 1.54 180) (size 0.2 0.7) (layers "F.Cu" "F.Paste" "F.Mask")
      (net 94 "TRD3_P") (pintype "passive"))
    (pad "4" smd rect (at -9.401 -1.541 180) (size 0.2 0.7) (layers "F.Cu" "F.Paste" "F.Mask")
      (net 93 "TRD1_P") (pintype "passive"))
    (pad "5" smd rect (at -9 1.54 180) (size 0.2 0.7) (layers "F.Cu" "F.Paste" "F.Mask")
      (net 92 "TRD3_N") (pintype "passive"))
    (pad "6" smd rect (at -9 -1.541 180) (size 0.2 0.7) (layers "F.Cu" "F.Paste" "F.Mask")
      (net 91 "TRD1_N") (pintype "passive"))
    (pad "7" smd rect (at -8.6 1.54 180) (size 0.2 0.7) (layers "F.Cu" "F.Paste" "F.Mask")
      (net 11 "GND") (pintype "passive"))
    (pad "8" smd rect (at -8.6 -1.541 180) (size 0.2 0.7) (layers "F.Cu" "F.Paste" "F.Mask")
      (net 11 "GND") (pintype "passive"))
    (pad "9" smd rect (at -8.2 1.54 180) (size 0.2 0.7) (layers "F.Cu" "F.Paste" "F.Mask")
      (net 90 "TRD2_N") (pintype "passive"))
    (pad "10" smd rect (at -8.2 -1.541 180) (size 0.2 0.7) (layers "F.Cu" "F.Paste" "F.Mask")
      (net 89 "TRD0_N") (pintype "passive"))
    (pad "11" smd rect (at -7.8 1.54 180) (size 0.2 0.7) (layers "F.Cu" "F.Paste" "F.Mask")
      (net 88 "TRD2_P") (pintype "passive"))
    (pad "12" smd rect (at -7.8 -1.541 180) (size 0.2 0.7) (layers "F.Cu" "F.Paste" "F.Mask")
      (net 87 "TRD0_P") (pintype "passive"))
    (pad "13" smd rect (at -7.401 1.54 180) (size 0.2 0.7) (layers "F.Cu" "F.Paste" "F.Mask")
      (net 11 "GND") (pintype "passive"))
    (pad "14" smd rect (at -7.401 -1.541 180) (size 0.2 0.7) (layers "F.Cu" "F.Paste" "F.Mask")
      (net 11 "GND") (pintype "passive"))
    (pad "15" smd rect (at -7 1.54 180) (size 0.2 0.7) (layers "F.Cu" "F.Paste" "F.Mask")
      (net 84 "ETH_LEDG") (pintype "passive"))
    (pad "16" smd rect (at -7 -1.541 180) (size 0.2 0.7) (layers "F.Cu" "F.Paste" "F.Mask")
      (net 85 "SYNC_IN") (pintype "passive"))
    (pad "17" smd rect (at -6.6 1.54 180) (size 0.2 0.7) (layers "F.Cu" "F.Paste" "F.Mask")
      (net 86 "ETH_LEDY") (pintype "passive"))
    (pad "18" smd rect (at -6.6 -1.541 180) (size 0.2 0.7) (layers "F.Cu" "F.Paste" "F.Mask")
      (net 83 "SYNC_OUT") (pintype "passive"))
    (pad "19" smd rect (at -6.201 1.54 180) (size 0.2 0.7) (layers "F.Cu" "F.Paste" "F.Mask")
      (net 203 "unconnected-(J7-Pad19)") (pintype "passive+no_connect"))
    (pad "20" smd rect (at -6.201 -1.541 180) (size 0.2 0.7) (layers "F.Cu" "F.Paste" "F.Mask")
      (net 82 "EEPROM_nWP") (pintype "passive"))
    (pad "21" smd rect (at -5.8 1.54 180) (size 0.2 0.7) (layers "F.Cu" "F.Paste" "F.Mask")
      (net 227 "Net-(J7-Pad21)") (pintype "passive"))
    (pad "22" smd rect (at -5.8 -1.541 180) (size 0.2 0.7) (layers "F.Cu" "F.Paste" "F.Mask")
      (net 11 "GND") (pintype "passive"))
    (pad "23" smd rect (at -5.401 1.54 180) (size 0.2 0.7) (layers "F.Cu" "F.Paste" "F.Mask")
      (net 11 "GND") (pintype "passive"))
    (pad "24" smd rect (at -5.401 -1.541 180) (size 0.2 0.7) (layers "F.Cu" "F.Paste" "F.Mask")
      (net 80 "GPIO26") (pintype "passive"))
    (pad "25" smd rect (at -5 1.54 180) (size 0.2 0.7) (layers "F.Cu" "F.Paste" "F.Mask")
      (net 81 "GPIO21") (pintype "passive"))
    (pad "26" smd rect (at -5 -1.541 180) (size 0.2 0.7) (layers "F.Cu" "F.Paste" "F.Mask")
      (net 78 "GPIO19") (pintype "passive"))
    (pad "27" smd rect (at -4.6 1.54 180) (size 0.2 0.7) (layers "F.Cu" "F.Paste" "F.Mask")
      (net 79 "GPIO20") (pintype "passive"))
    (pad "28" smd rect (at -4.6 -1.541 180) (size 0.2 0.7) (layers "F.Cu" "F.Paste" "F.Mask")
      (net 76 "GPIO13") (pintype "passive"))
    (pad "29" smd rect (at -4.201 1.54 180) (size 0.2 0.7) (layers "F.Cu" "F.Paste" "F.Mask")
      (net 77 "GPIO16") (pintype "passive"))
    (pad "30" smd rect (at -4.201 -1.541 180) (size 0.2 0.7) (layers "F.Cu" "F.Paste" "F.Mask")
      (net 74 "GPIO6") (pintype "passive"))
    (pad "31" smd rect (at -3.8 1.54 180) (size 0.2 0.7) (layers "F.Cu" "F.Paste" "F.Mask")
      (net 75 "GPIO12") (pintype "passive"))
    (pad "32" smd rect (at -3.8 -1.541 180) (size 0.2 0.7) (layers "F.Cu" "F.Paste" "F.Mask")
      (net 11 "GND") (pintype "passive"))
    (pad "33" smd rect (at -3.4 1.54 180) (size 0.2 0.7) (layers "F.Cu" "F.Paste" "F.Mask")
      (net 11 "GND") (pintype "passive"))
    (pad "34" smd rect (at -3.4 -1.541 180) (size 0.2 0.7) (layers "F.Cu" "F.Paste" "F.Mask")
      (net 72 "GPIO5") (pintype "passive"))
    (pad "35" smd rect (at -3 1.54 180) (size 0.2 0.7) (layers "F.Cu" "F.Paste" "F.Mask")
      (net 73 "ID_SC") (pintype "passive"))
    (pad "36" smd rect (at -3 -1.541 180) (size 0.2 0.7) (layers "F.Cu" "F.Paste" "F.Mask")
      (net 70 "ID_SD") (pintype "passive"))
    (pad "37" smd rect (at -2.601 1.54 180) (size 0.2 0.7) (layers "F.Cu" "F.Paste" "F.Mask")
      (net 71 "GPIO7") (pintype "passive"))
    (pad "38" smd rect (at -2.601 -1.541 180) (size 0.2 0.7) (layers "F.Cu" "F.Paste" "F.Mask")
      (net 68 "GPIO11") (pintype "passive"))
    (pad "39" smd rect (at -2.201 1.54 180) (size 0.2 0.7) (layers "F.Cu" "F.Paste" "F.Mask")
      (net 69 "GPIO8") (pintype "passive"))
    (pad "40" smd rect (at -2.201 -1.541 180) (size 0.2 0.7) (layers "F.Cu" "F.Paste" "F.Mask")
      (net 66 "GPIO9") (pintype "passive"))
    (pad "41" smd rect (at -1.801 1.54 180) (size 0.2 0.7) (layers "F.Cu" "F.Paste" "F.Mask")
      (net 67 "GPIO25") (pintype "passive"))
    (pad "42" smd rect (at -1.801 -1.541 180) (size 0.2 0.7) (layers "F.Cu" "F.Paste" "F.Mask")
      (net 11 "GND") (pintype "passive"))
    (pad "43" smd rect (at -1.4 1.54 180) (size 0.2 0.7) (layers "F.Cu" "F.Paste" "F.Mask")
      (net 11 "GND") (pintype "passive"))
    (pad "44" smd rect (at -1.4 -1.541 180) (size 0.2 0.7) (layers "F.Cu" "F.Paste" "F.Mask")
      (net 64 "GPIO10") (pintype "passive"))
    (pad "45" smd rect (at -1 1.54 180) (size 0.2 0.7) (layers "F.Cu" "F.Paste" "F.Mask")
      (net 65 "GPIO24") (pintype "passive"))
    (pad "46" smd rect (at -1 -1.541 180) (size 0.2 0.7) (layers "F.Cu" "F.Paste" "F.Mask")
      (net 62 "GPIO22") (pintype "passive"))
    (pad "47" smd rect (at -0.6 1.54 180) (size 0.2 0.7) (layers "F.Cu" "F.Paste" "F.Mask")
      (net 63 "GPIO23") (pintype "passive"))
    (pad "48" smd rect (at -0.6 -1.541 180) (size 0.2 0.7) (layers "F.Cu" "F.Paste" "F.Mask")
      (net 60 "GPIO27") (pintype "passive"))
    (pad "49" smd rect (at -0.201 1.54 180) (size 0.2 0.7) (layers "F.Cu" "F.Paste" "F.Mask")
      (net 61 "GPIO18") (pintype "passive"))
    (pad "50" smd rect (at -0.201 -1.541 180) (size 0.2 0.7) (layers "F.Cu" "F.Paste" "F.Mask")
      (net 59 "GPIO17") (pintype "passive"))
    (pad "51" smd rect (at 0.2 1.54 180) (size 0.2 0.7) (layers "F.Cu" "F.Paste" "F.Mask")
      (net 241 "RPi_RXD") (pintype "passive"))
    (pad "52" smd rect (at 0.2 -1.541 180) (size 0.2 0.7) (layers "F.Cu" "F.Paste" "F.Mask")
      (net 11 "GND") (pintype "passive"))
    (pad "53" smd rect (at 0.599 1.54 180) (size 0.2 0.7) (layers "F.Cu" "F.Paste" "F.Mask")
      (net 11 "GND") (pintype "passive"))
    (pad "54" smd rect (at 0.599 -1.541 180) (size 0.2 0.7) (layers "F.Cu" "F.Paste" "F.Mask")
      (net 58 "GPIO4") (pintype "passive"))
    (pad "55" smd rect (at 0.999 1.54 180) (size 0.2 0.7) (layers "F.Cu" "F.Paste" "F.Mask")
      (net 242 "RPi_TXD") (pintype "passive"))
    (pad "56" smd rect (at 0.999 -1.541 180) (size 0.2 0.7) (layers "F.Cu" "F.Paste" "F.Mask")
      (net 57 "GPIO3") (pintype "passive"))
    (pad "57" smd rect (at 1.399 1.54 180) (size 0.2 0.7) (layers "F.Cu" "F.Paste" "F.Mask")
      (net 30 "SD_CLK") (pintype "passive"))
    (pad "58" smd rect (at 1.399 -1.541 180) (size 0.2 0.7) (layers "F.Cu" "F.Paste" "F.Mask")
      (net 56 "GPIO2") (pintype "passive"))
    (pad "59" smd rect (at 1.8 1.54 180) (size 0.2 0.7) (layers "F.Cu" "F.Paste" "F.Mask")
      (net 11 "GND") (pintype "passive"))
    (pad "60" smd rect (at 1.8 -1.541 180) (size 0.2 0.7) (layers "F.Cu" "F.Paste" "F.Mask")
      (net 11 "GND") (pintype "passive"))
    (pad "61" smd rect (at 2.2 1.54 180) (size 0.2 0.7) (layers "F.Cu" "F.Paste" "F.Mask")
      (net 32 "SD_DAT3") (pintype "passive"))
    (pad "62" smd rect (at 2.2 -1.541 180) (size 0.2 0.7) (layers "F.Cu" "F.Paste" "F.Mask")
      (net 31 "SD_CMD") (pintype "passive"))
    (pad "63" smd rect (at 2.6 1.54 180) (size 0.2 0.7) (layers "F.Cu" "F.Paste" "F.Mask")
      (net 29 "SD_DAT0") (pintype "passive"))
    (pad "64" smd rect (at 2.6 -1.541 180) (size 0.2 0.7) (layers "F.Cu" "F.Paste" "F.Mask")
      (net 204 "unconnected-(J7-Pad64)") (pintype "passive+no_connect"))
    (pad "65" smd rect (at 2.999 1.54 180) (size 0.2 0.7) (layers "F.Cu" "F.Paste" "F.Mask")
      (net 11 "GND") (pintype "passive"))
    (pad "66" smd rect (at 2.999 -1.541 180) (size 0.2 0.7) (layers "F.Cu" "F.Paste" "F.Mask")
      (net 11 "GND") (pintype "passive"))
    (pad "67" smd rect (at 3.399 1.54 180) (size 0.2 0.7) (layers "F.Cu" "F.Paste" "F.Mask")
      (net 28 "SD_DAT1") (pintype "passive"))
    (pad "68" smd rect (at 3.399 -1.541 180) (size 0.2 0.7) (layers "F.Cu" "F.Paste" "F.Mask")
      (net 205 "unconnected-(J7-Pad68)") (pintype "passive+no_connect"))
    (pad "69" smd rect (at 3.799 1.54 180) (size 0.2 0.7) (layers "F.Cu" "F.Paste" "F.Mask")
      (net 33 "SD_DAT2") (pintype "passive"))
    (pad "70" smd rect (at 3.799 -1.541 180) (size 0.2 0.7) (layers "F.Cu" "F.Paste" "F.Mask")
      (net 206 "unconnected-(J7-Pad70)") (pintype "passive+no_connect"))
    (pad "71" smd rect (at 4.2 1.54 180) (size 0.2 0.7) (layers "F.Cu" "F.Paste" "F.Mask")
      (net 11 "GND") (pintype "passive"))
    (pad "72" smd rect (at 4.2 -1.541 180) (size 0.2 0.7) (layers "F.Cu" "F.Paste" "F.Mask")
      (net 207 "unconnected-(J7-Pad72)") (pintype "passive+no_connect"))
    (pad "73" smd rect (at 4.599 1.54 180) (size 0.2 0.7) (layers "F.Cu" "F.Paste" "F.Mask")
      (net 208 "unconnected-(J7-Pad73)") (pintype "passive+no_connect"))
    (pad "74" smd rect (at 4.599 -1.541 180) (size 0.2 0.7) (layers "F.Cu" "F.Paste" "F.Mask")
      (net 11 "GND") (pintype "passive"))
    (pad "75" smd rect (at 4.999 1.54 180) (size 0.2 0.7) (layers "F.Cu" "F.Paste" "F.Mask")
      (net 55 "SD_PWR_ON") (pintype "passive"))
    (pad "76" smd rect (at 4.999 -1.541 180) (size 0.2 0.7) (layers "F.Cu" "F.Paste" "F.Mask")
      (net 54 "RESERVED") (pintype "passive"))
    (pad "77" smd rect (at 5.4 1.54 180) (size 0.2 0.7) (layers "F.Cu" "F.Paste" "F.Mask")
      (net 12 "VCC5V0") (pintype "passive"))
    (pad "78" smd rect (at 5.4 -1.541 180) (size 0.2 0.7) (layers "F.Cu" "F.Paste" "F.Mask")
      (net 232 "3V3_RPi") (pintype "passive"))
    (pad "79" smd rect (at 5.799 1.54 180) (size 0.2 0.7) (layers "F.Cu" "F.Paste" "F.Mask")
      (net 12 "VCC5V0") (pintype "passive"))
    (pad "80" smd rect (at 5.799 -1.541 180) (size 0.2 0.7) (layers "F.Cu" "F.Paste" "F.Mask")
      (net 53 "SCL0") (pintype "passive"))
    (pad "81" smd rect (at 6.2 1.54 180) (size 0.2 0.7) (layers "F.Cu" "F.Paste" "F.Mask")
      (net 12 "VCC5V0") (pintype "passive"))
    (pad "82" smd rect (at 6.2 -1.541 180) (size 0.2 0.7) (layers "F.Cu" "F.Paste" "F.Mask")
      (net 52 "SDA0") (pintype "passive"))
    (pad "83" smd rect (at 6.599 1.54 180) (size 0.2 0.7) (layers "F.Cu" "F.Paste" "F.Mask")
      (net 12 "VCC5V0") (pintype "passive"))
    (pad "84" smd rect (at 6.599 -1.541 180) (size 0.2 0.7) (layers "F.Cu" "F.Paste" "F.Mask")
      (net 232 "3V3_RPi") (pintype "passive"))
    (pad "85" smd rect (at 6.999 1.54 180) (size 0.2 0.7) (layers "F.Cu" "F.Paste" "F.Mask")
      (net 12 "VCC5V0") (pintype "passive"))
    (pad "86" smd rect (at 6.999 -1.541 180) (size 0.2 0.7) (layers "F.Cu" "F.Paste" "F.Mask")
      (net 232 "3V3_RPi") (pintype "passive"))
    (pad "87" smd rect (at 7.4 1.54 180) (size 0.2 0.7) (layers "F.Cu" "F.Paste" "F.Mask")
      (net 12 "VCC5V0") (pintype "passive"))
    (pad "88" smd rect (at 7.4 -1.541 180) (size 0.2 0.7) (layers "F.Cu" "F.Paste" "F.Mask")
      (net 50 "VCC1V8") (pintype "passive"))
    (pad "89" smd rect (at 7.799 1.54 180) (size 0.2 0.7) (layers "F.Cu" "F.Paste" "F.Mask")
      (net 51 "WL_nDis") (pintype "passive"))
    (pad "90" smd rect (at 7.799 -1.541 180) (size 0.2 0.7) (layers "F.Cu" "F.Paste" "F.Mask")
      (net 50 "VCC1V8") (pintype "passive"))
    (pad "91" smd rect (at 8.199 1.54 180) (size 0.2 0.7) (layers "F.Cu" "F.Paste" "F.Mask")
      (net 49 "BT_nDis") (pintype "passive"))
    (pad "92" smd rect (at 8.199 -1.541 180) (size 0.2 0.7) (layers "F.Cu" "F.Paste" "F.Mask")
      (net 48 "RUN_PG") (pintype "passive"))
    (pad "93" smd rect (at 8.599 1.54 180) (size 0.2 0.7) (layers "F.Cu" "F.Paste" "F.Mask")
      (net 243 "/Compute module/nRPi_BOOT") (pintype "passive"))
    (pad "94" smd rect (at 8.599 -1.541 180) (size 0.2 0.7) (layers "F.Cu" "F.Paste" "F.Mask")
      (net 47 "AIN1") (pintype "passive"))
    (pad "95" smd rect (at 8.999 1.54 180) (size 0.2 0.7) (layers "F.Cu" "F.Paste" "F.Mask")
      (net 46 "nPWR_LED") (pintype "passive"))
    (pad "96" smd rect (at 8.999 -1.541 180) (size 0.2 0.7) (layers "F.Cu" "F.Paste" "F.Mask")
      (net 45 "AIN0") (pintype "passive"))
    (pad "97" smd rect (at 9.4 1.54 180) (size 0.2 0.7) (layers "F.Cu" "F.Paste" "F.Mask")
      (net 44 "CAM_GPIO") (pintype "passive"))
    (pad "98" smd rect (at 9.4 -1.541 180) (size 0.2 0.7) (layers "F.Cu" "F.Paste" "F.Mask")
      (net 11 "GND") (pintype "passive"))
    (pad "99" smd rect (at 9.8 1.54 180) (size 0.2 0.7) (layers "F.Cu" "F.Paste" "F.Mask")
      (net 43 "GLOBAL_EN") (pintype "passive"))
    (pad "100" smd rect (at 9.8 -1.541 180) (size 0.2 0.7) (layers "F.Cu" "F.Paste" "F.Mask")
      (net 42 "nEXTRST") (pintype "passive"))
  )

  (footprint "scalenode-cm4-baseboard-footprints:Conn_Socket_Hirose_DF40_2x50_DF40HC-3.0-100DS-0.4V" (layer "F.Cu")
    (at 167.17772 93.80168 180)
    (property "Author" "Antmicro")
    (property "License" "Apache-2.0")
    (property "MPN" "DF40HC(3.0)-100DS-0.4V(51)")
    (property "Manufacturer" "Hirose Electric")
    (property "Pitch" "0.4 mm")
    (property "Sheetfile" "compute-module.kicad_sch")
    (property "Sheetname" "Compute module")
    (property "ki_description" "100 Position Connector Receptacle, Center Strip Contacts Surface Mount Gold")
    (property "ki_keywords" "CONNECTOR, B2B, SOCKET")
    (attr smd)
    (fp_text reference "J8" (at -12.87 0.119) (layer "F.SilkS")
        (effects (font (size 0.7 0.7) (thickness 0.15)) (justify left bottom))
    )
    (fp_text value "Socket_Hirose_DF40_2x50_DF40HC-3.0-100DS-0.4V" (at 0.109 2.999) (layer "F.Fab")
        (effects (font (size 0.7 0.7) (thickness 0.15)) (justify left bottom))
    )
    (fp_text user "Author: Antmicro" (at -12.87 6.2 180) (layer "F.Fab") hide
        (effects (font (size 0.7 0.7) (thickness 0.15)) (justify left bottom))
    )
    (fp_text user "${REFERENCE}" (at -12.87 7.4 180) (layer "F.Fab") hide
        (effects (font (size 0.7 0.7) (thickness 0.15)) (justify left bottom))
    )
    (fp_text user "License: Apache-2.0" (at -12.87 4.999 180) (layer "F.Fab") hide
        (effects (font (size 0.7 0.7) (thickness 0.15)) (justify left bottom))
    )
    (fp_line (start -11.301 -1.44) (end -10.08 -1.44)
      (stroke (width 0.15) (type solid)) (layer "F.SilkS"))
    (fp_line (start -11.301 1.439) (end -11.301 -1.44)
      (stroke (width 0.15) (type solid)) (layer "F.SilkS"))
    (fp_line (start -11.301 1.439) (end -10.08 1.439)
      (stroke (width 0.15) (type solid)) (layer "F.SilkS"))
    (fp_line (start -10.15 2.534) (end -10.15 2.539)
      (stroke (width 0.15) (type solid)) (layer "F.SilkS"))
    (fp_line (start 11.3 -1.44) (end 10.079 -1.44)
      (stroke (width 0.15) (type solid)) (layer "F.SilkS"))
    (fp_line (start 11.3 -1.44) (end 11.3 1.439)
      (stroke (width 0.15) (type solid)) (layer "F.SilkS"))
    (fp_line (start 11.3 1.439) (end 10.079 1.439)
      (stroke (width 0.15) (type solid)) (layer "F.SilkS"))
    (fp_circle (center -12.051 1.54) (end -12 1.54)
      (stroke (width 0.15) (type solid)) (fill solid) (layer "F.SilkS"))
    (fp_line (start -11.75 -1.75) (end -11.75 1.74)
      (stroke (width 0.05) (type solid)) (layer "F.CrtYd"))
    (fp_line (start -11.75 1.74) (end -10.25 1.74)
      (stroke (width 0.05) (type solid)) (layer "F.CrtYd"))
    (fp_line (start -10.25 -2.25) (end -10.25 -1.75)
      (stroke (width 0.05) (type solid)) (layer "F.CrtYd"))
    (fp_line (start -10.25 -1.75) (end -11.75 -1.75)
      (stroke (width 0.05) (type solid)) (layer "F.CrtYd"))
    (fp_line (start -10.25 1.74) (end -10.25 2.24)
      (stroke (width 0.05) (type solid)) (layer "F.CrtYd"))
    (fp_line (start -10.25 2.24) (end 10.24 2.24)
      (stroke (width 0.05) (type solid)) (layer "F.CrtYd"))
    (fp_line (start 10.24 -2.25) (end -10.25 -2.25)
      (stroke (width 0.05) (type solid)) (layer "F.CrtYd"))
    (fp_line (start 10.24 -1.75) (end 10.24 -2.25)
      (stroke (width 0.05) (type solid)) (layer "F.CrtYd"))
    (fp_line (start 10.24 1.74) (end 11.74 1.74)
      (stroke (width 0.05) (type solid)) (layer "F.CrtYd"))
    (fp_line (start 10.24 2.24) (end 10.24 1.74)
      (stroke (width 0.05) (type solid)) (layer "F.CrtYd"))
    (fp_line (start 11.74 -1.75) (end 10.24 -1.75)
      (stroke (width 0.05) (type solid)) (layer "F.CrtYd"))
    (fp_line (start 11.74 1.74) (end 11.74 -1.75)
      (stroke (width 0.05) (type solid)) (layer "F.CrtYd"))
    (fp_poly
      (pts
        (xy -9.92 -1.19)
        (xy -9.7 -1.19)
        (xy -9.7 -0.76)
        (xy -9.92 -0.76)
      )

      (stroke (width 0.05) (type solid)) (fill solid) (layer "F.CrtYd"))
    (fp_poly
      (pts
        (xy -9.92 0.74)
        (xy -9.7 0.74)
        (xy -9.7 1.19)
        (xy -9.92 1.19)
      )

      (stroke (width 0.05) (type solid)) (fill solid) (layer "F.CrtYd"))
    (fp_poly
      (pts
        (xy -9.53 -1.19)
        (xy -9.31 -1.19)
        (xy -9.31 -0.76)
        (xy -9.53 -0.76)
      )

      (stroke (width 0.05) (type solid)) (fill solid) (layer "F.CrtYd"))
    (fp_poly
      (pts
        (xy -9.52 0.74)
        (xy -9.31 0.74)
        (xy -9.31 1.19)
        (xy -9.52 1.19)
      )

      (stroke (width 0.05) (type solid)) (fill solid) (layer "F.CrtYd"))
    (fp_poly
      (pts
        (xy -9.13 -1.19)
        (xy -8.91 -1.19)
        (xy -8.91 -0.76)
        (xy -9.13 -0.76)
      )

      (stroke (width 0.05) (type solid)) (fill solid) (layer "F.CrtYd"))
    (fp_poly
      (pts
        (xy -9.13 0.74)
        (xy -8.91 0.74)
        (xy -8.91 1.19)
        (xy -9.13 1.19)
      )

      (stroke (width 0.05) (type solid)) (fill solid) (layer "F.CrtYd"))
    (fp_poly
      (pts
        (xy -8.72 -1.19)
        (xy -8.5 -1.19)
        (xy -8.5 -0.76)
        (xy -8.72 -0.76)
      )

      (stroke (width 0.05) (type solid)) (fill solid) (layer "F.CrtYd"))
    (fp_poly
      (pts
        (xy -8.72 0.74)
        (xy -8.5 0.74)
        (xy -8.5 1.19)
        (xy -8.72 1.19)
      )

      (stroke (width 0.05) (type solid)) (fill solid) (layer "F.CrtYd"))
    (fp_poly
      (pts
        (xy -8.32 -1.19)
        (xy -8.1 -1.19)
        (xy -8.1 -0.76)
        (xy -8.32 -0.76)
      )

      (stroke (width 0.05) (type solid)) (fill solid) (layer "F.CrtYd"))
    (fp_poly
      (pts
        (xy -8.32 0.74)
        (xy -8.1 0.74)
        (xy -8.1 1.19)
        (xy -8.32 1.19)
      )

      (stroke (width 0.05) (type solid)) (fill solid) (layer "F.CrtYd"))
    (fp_poly
      (pts
        (xy -7.92 -1.19)
        (xy -7.71 -1.19)
        (xy -7.71 -0.76)
        (xy -7.92 -0.76)
      )

      (stroke (width 0.05) (type solid)) (fill solid) (layer "F.CrtYd"))
    (fp_poly
      (pts
        (xy -7.92 0.74)
        (xy -7.71 0.74)
        (xy -7.71 1.19)
        (xy -7.92 1.19)
      )

      (stroke (width 0.05) (type solid)) (fill solid) (layer "F.CrtYd"))
    (fp_poly
      (pts
        (xy -7.52 -1.19)
        (xy -7.3 -1.19)
        (xy -7.3 -0.76)
        (xy -7.52 -0.76)
      )

      (stroke (width 0.05) (type solid)) (fill solid) (layer "F.CrtYd"))
    (fp_poly
      (pts
        (xy -7.52 0.74)
        (xy -7.3 0.74)
        (xy -7.3 1.19)
        (xy -7.52 1.19)
      )

      (stroke (width 0.05) (type solid)) (fill solid) (layer "F.CrtYd"))
    (fp_poly
      (pts
        (xy -7.12 -1.19)
        (xy -6.91 -1.19)
        (xy -6.91 -0.76)
        (xy -7.12 -0.76)
      )

      (stroke (width 0.05) (type solid)) (fill solid) (layer "F.CrtYd"))
    (fp_poly
      (pts
        (xy -7.12 0.74)
        (xy -6.91 0.74)
        (xy -6.91 1.19)
        (xy -7.12 1.19)
      )

      (stroke (width 0.05) (type solid)) (fill solid) (layer "F.CrtYd"))
    (fp_poly
      (pts
        (xy -6.72 -1.19)
        (xy -6.5 -1.19)
        (xy -6.5 -0.76)
        (xy -6.72 -0.76)
      )

      (stroke (width 0.05) (type solid)) (fill solid) (layer "F.CrtYd"))
    (fp_poly
      (pts
        (xy -6.71 0.74)
        (xy -6.5 0.74)
        (xy -6.5 1.19)
        (xy -6.71 1.19)
      )

      (stroke (width 0.05) (type solid)) (fill solid) (layer "F.CrtYd"))
    (fp_poly
      (pts
        (xy -6.32 -1.19)
        (xy -6.1 -1.19)
        (xy -6.1 -0.76)
        (xy -6.32 -0.76)
      )

      (stroke (width 0.05) (type solid)) (fill solid) (layer "F.CrtYd"))
    (fp_poly
      (pts
        (xy -6.32 0.74)
        (xy -6.1 0.74)
        (xy -6.1 1.19)
        (xy -6.32 1.19)
      )

      (stroke (width 0.05) (type solid)) (fill solid) (layer "F.CrtYd"))
    (fp_poly
      (pts
        (xy -5.92 -1.19)
        (xy -5.71 -1.19)
        (xy -5.71 -0.76)
        (xy -5.92 -0.76)
      )

      (stroke (width 0.05) (type solid)) (fill solid) (layer "F.CrtYd"))
    (fp_poly
      (pts
        (xy -5.91 0.74)
        (xy -5.71 0.74)
        (xy -5.71 1.19)
        (xy -5.91 1.19)
      )

      (stroke (width 0.05) (type solid)) (fill solid) (layer "F.CrtYd"))
    (fp_poly
      (pts
        (xy -5.52 -1.19)
        (xy -5.3 -1.19)
        (xy -5.3 -0.76)
        (xy -5.52 -0.76)
      )

      (stroke (width 0.05) (type solid)) (fill solid) (layer "F.CrtYd"))
    (fp_poly
      (pts
        (xy -5.52 0.74)
        (xy -5.3 0.74)
        (xy -5.3 1.19)
        (xy -5.52 1.19)
      )

      (stroke (width 0.05) (type solid)) (fill solid) (layer "F.CrtYd"))
    (fp_poly
      (pts
        (xy -5.11 -1.19)
        (xy -4.91 -1.19)
        (xy -4.91 -0.76)
        (xy -5.11 -0.76)
      )

      (stroke (width 0.05) (type solid)) (fill solid) (layer "F.CrtYd"))
    (fp_poly
      (pts
        (xy -5.11 0.74)
        (xy -4.91 0.74)
        (xy -4.91 1.19)
        (xy -5.11 1.19)
      )

      (stroke (width 0.05) (type solid)) (fill solid) (layer "F.CrtYd"))
    (fp_poly
      (pts
        (xy -4.71 -1.19)
        (xy -4.5 -1.19)
        (xy -4.5 -0.76)
        (xy -4.71 -0.76)
      )

      (stroke (width 0.05) (type solid)) (fill solid) (layer "F.CrtYd"))
    (fp_poly
      (pts
        (xy -4.71 0.74)
        (xy -4.5 0.74)
        (xy -4.5 1.19)
        (xy -4.71 1.19)
      )

      (stroke (width 0.05) (type solid)) (fill solid) (layer "F.CrtYd"))
    (fp_poly
      (pts
        (xy -4.32 -1.19)
        (xy -4.1 -1.19)
        (xy -4.1 -0.76)
        (xy -4.32 -0.76)
      )

      (stroke (width 0.05) (type solid)) (fill solid) (layer "F.CrtYd"))
    (fp_poly
      (pts
        (xy -4.32 0.74)
        (xy -4.1 0.74)
        (xy -4.1 1.19)
        (xy -4.32 1.19)
      )

      (stroke (width 0.05) (type solid)) (fill solid) (layer "F.CrtYd"))
    (fp_poly
      (pts
        (xy -3.92 -1.19)
        (xy -3.71 -1.19)
        (xy -3.71 -0.76)
        (xy -3.92 -0.76)
      )

      (stroke (width 0.05) (type solid)) (fill solid) (layer "F.CrtYd"))
    (fp_poly
      (pts
        (xy -3.91 0.74)
        (xy -3.71 0.74)
        (xy -3.71 1.19)
        (xy -3.91 1.19)
      )

      (stroke (width 0.05) (type solid)) (fill solid) (layer "F.CrtYd"))
    (fp_poly
      (pts
        (xy -3.51 -1.19)
        (xy -3.3 -1.19)
        (xy -3.3 -0.76)
        (xy -3.51 -0.76)
      )

      (stroke (width 0.05) (type solid)) (fill solid) (layer "F.CrtYd"))
    (fp_poly
      (pts
        (xy -3.51 0.74)
        (xy -3.3 0.74)
        (xy -3.3 1.19)
        (xy -3.51 1.19)
      )

      (stroke (width 0.05) (type solid)) (fill solid) (layer "F.CrtYd"))
    (fp_poly
      (pts
        (xy -3.11 -1.19)
        (xy -2.9 -1.19)
        (xy -2.9 -0.76)
        (xy -3.11 -0.76)
      )

      (stroke (width 0.05) (type solid)) (fill solid) (layer "F.CrtYd"))
    (fp_poly
      (pts
        (xy -3.11 0.74)
        (xy -2.9 0.74)
        (xy -2.9 1.19)
        (xy -3.11 1.19)
      )

      (stroke (width 0.05) (type solid)) (fill solid) (layer "F.CrtYd"))
    (fp_poly
      (pts
        (xy -2.71 -1.19)
        (xy -2.5 -1.19)
        (xy -2.5 -0.76)
        (xy -2.71 -0.76)
      )

      (stroke (width 0.05) (type solid)) (fill solid) (layer "F.CrtYd"))
    (fp_poly
      (pts
        (xy -2.71 0.74)
        (xy -2.5 0.74)
        (xy -2.5 1.19)
        (xy -2.71 1.19)
      )

      (stroke (width 0.05) (type solid)) (fill solid) (layer "F.CrtYd"))
    (fp_poly
      (pts
        (xy -2.31 -1.19)
        (xy -2.11 -1.19)
        (xy -2.11 -0.76)
        (xy -2.31 -0.76)
      )

      (stroke (width 0.05) (type solid)) (fill solid) (layer "F.CrtYd"))
    (fp_poly
      (pts
        (xy -2.31 0.74)
        (xy -2.11 0.74)
        (xy -2.11 1.19)
        (xy -2.31 1.19)
      )

      (stroke (width 0.05) (type solid)) (fill solid) (layer "F.CrtYd"))
    (fp_poly
      (pts
        (xy -1.91 -1.19)
        (xy -1.7 -1.19)
        (xy -1.7 -0.76)
        (xy -1.91 -0.76)
      )

      (stroke (width 0.05) (type solid)) (fill solid) (layer "F.CrtYd"))
    (fp_poly
      (pts
        (xy -1.91 0.74)
        (xy -1.7 0.74)
        (xy -1.7 1.19)
        (xy -1.91 1.19)
      )

      (stroke (width 0.05) (type solid)) (fill solid) (layer "F.CrtYd"))
    (fp_poly
      (pts
        (xy -1.51 -1.19)
        (xy -1.31 -1.19)
        (xy -1.31 -0.76)
        (xy -1.51 -0.76)
      )

      (stroke (width 0.05) (type solid)) (fill solid) (layer "F.CrtYd"))
    (fp_poly
      (pts
        (xy -1.51 0.74)
        (xy -1.31 0.74)
        (xy -1.31 1.19)
        (xy -1.51 1.19)
      )

      (stroke (width 0.05) (type solid)) (fill solid) (layer "F.CrtYd"))
    (fp_poly
      (pts
        (xy -1.11 -1.19)
        (xy -0.91 -1.19)
        (xy -0.91 -0.76)
        (xy -1.11 -0.76)
      )

      (stroke (width 0.05) (type solid)) (fill solid) (layer "F.CrtYd"))
    (fp_poly
      (pts
        (xy -1.11 0.74)
        (xy -0.91 0.74)
        (xy -0.91 1.19)
        (xy -1.11 1.19)
      )

      (stroke (width 0.05) (type solid)) (fill solid) (layer "F.CrtYd"))
    (fp_poly
      (pts
        (xy -0.71 -1.19)
        (xy -0.5 -1.19)
        (xy -0.5 -0.76)
        (xy -0.71 -0.76)
      )

      (stroke (width 0.05) (type solid)) (fill solid) (layer "F.CrtYd"))
    (fp_poly
      (pts
        (xy -0.71 0.74)
        (xy -0.5 0.74)
        (xy -0.5 1.19)
        (xy -0.71 1.19)
      )

      (stroke (width 0.05) (type solid)) (fill solid) (layer "F.CrtYd"))
    (fp_poly
      (pts
        (xy -0.31 -1.19)
        (xy -0.11 -1.19)
        (xy -0.11 -0.76)
        (xy -0.31 -0.76)
      )

      (stroke (width 0.05) (type solid)) (fill solid) (layer "F.CrtYd"))
    (fp_poly
      (pts
        (xy -0.31 0.74)
        (xy -0.11 0.74)
        (xy -0.11 1.19)
        (xy -0.31 1.19)
      )

      (stroke (width 0.05) (type solid)) (fill solid) (layer "F.CrtYd"))
    (fp_poly
      (pts
        (xy 0.1 -1.19)
        (xy 0.29 -1.19)
        (xy 0.29 -0.76)
        (xy 0.1 -0.76)
      )

      (stroke (width 0.05) (type solid)) (fill solid) (layer "F.CrtYd"))
    (fp_poly
      (pts
        (xy 0.1 0.74)
        (xy 0.29 0.74)
        (xy 0.29 1.19)
        (xy 0.1 1.19)
      )

      (stroke (width 0.05) (type solid)) (fill solid) (layer "F.CrtYd"))
    (fp_poly
      (pts
        (xy 0.5 -1.19)
        (xy 0.69 -1.19)
        (xy 0.69 -0.76)
        (xy 0.5 -0.76)
      )

      (stroke (width 0.05) (type solid)) (fill solid) (layer "F.CrtYd"))
    (fp_poly
      (pts
        (xy 0.5 0.74)
        (xy 0.69 0.74)
        (xy 0.69 1.19)
        (xy 0.5 1.19)
      )

      (stroke (width 0.05) (type solid)) (fill solid) (layer "F.CrtYd"))
    (fp_poly
      (pts
        (xy 0.9 -1.19)
        (xy 1.1 -1.19)
        (xy 1.1 -0.76)
        (xy 0.9 -0.76)
      )

      (stroke (width 0.05) (type solid)) (fill solid) (layer "F.CrtYd"))
    (fp_poly
      (pts
        (xy 0.9 0.74)
        (xy 1.1 0.74)
        (xy 1.1 1.19)
        (xy 0.9 1.19)
      )

      (stroke (width 0.05) (type solid)) (fill solid) (layer "F.CrtYd"))
    (fp_poly
      (pts
        (xy 1.3 -1.19)
        (xy 1.49 -1.19)
        (xy 1.49 -0.76)
        (xy 1.3 -0.76)
      )

      (stroke (width 0.05) (type solid)) (fill solid) (layer "F.CrtYd"))
    (fp_poly
      (pts
        (xy 1.3 0.74)
        (xy 1.49 0.74)
        (xy 1.49 1.19)
        (xy 1.3 1.19)
      )

      (stroke (width 0.05) (type solid)) (fill solid) (layer "F.CrtYd"))
    (fp_poly
      (pts
        (xy 1.7 -1.19)
        (xy 1.89 -1.19)
        (xy 1.89 -0.76)
        (xy 1.7 -0.76)
      )

      (stroke (width 0.05) (type solid)) (fill solid) (layer "F.CrtYd"))
    (fp_poly
      (pts
        (xy 1.7 0.74)
        (xy 1.89 0.74)
        (xy 1.89 1.19)
        (xy 1.7 1.19)
      )

      (stroke (width 0.05) (type solid)) (fill solid) (layer "F.CrtYd"))
    (fp_poly
      (pts
        (xy 2.1 -1.19)
        (xy 2.29 -1.19)
        (xy 2.29 -0.76)
        (xy 2.1 -0.76)
      )

      (stroke (width 0.05) (type solid)) (fill solid) (layer "F.CrtYd"))
    (fp_poly
      (pts
        (xy 2.1 0.74)
        (xy 2.29 0.74)
        (xy 2.29 1.19)
        (xy 2.1 1.19)
      )

      (stroke (width 0.05) (type solid)) (fill solid) (layer "F.CrtYd"))
    (fp_poly
      (pts
        (xy 2.5 -1.19)
        (xy 2.7 -1.19)
        (xy 2.7 -0.76)
        (xy 2.5 -0.76)
      )

      (stroke (width 0.05) (type solid)) (fill solid) (layer "F.CrtYd"))
    (fp_poly
      (pts
        (xy 2.5 0.74)
        (xy 2.7 0.74)
        (xy 2.7 1.19)
        (xy 2.5 1.19)
      )

      (stroke (width 0.05) (type solid)) (fill solid) (layer "F.CrtYd"))
    (fp_poly
      (pts
        (xy 2.9 -1.19)
        (xy 3.1 -1.19)
        (xy 3.1 -0.76)
        (xy 2.9 -0.76)
      )

      (stroke (width 0.05) (type solid)) (fill solid) (layer "F.CrtYd"))
    (fp_poly
      (pts
        (xy 2.9 0.74)
        (xy 3.1 0.74)
        (xy 3.1 1.19)
        (xy 2.9 1.19)
      )

      (stroke (width 0.05) (type solid)) (fill solid) (layer "F.CrtYd"))
    (fp_poly
      (pts
        (xy 3.3 -1.19)
        (xy 3.49 -1.19)
        (xy 3.49 -0.76)
        (xy 3.3 -0.76)
      )

      (stroke (width 0.05) (type solid)) (fill solid) (layer "F.CrtYd"))
    (fp_poly
      (pts
        (xy 3.3 0.74)
        (xy 3.49 0.74)
        (xy 3.49 1.19)
        (xy 3.3 1.19)
      )

      (stroke (width 0.05) (type solid)) (fill solid) (layer "F.CrtYd"))
    (fp_poly
      (pts
        (xy 3.7 -1.19)
        (xy 3.89 -1.19)
        (xy 3.89 -0.76)
        (xy 3.7 -0.76)
      )

      (stroke (width 0.05) (type solid)) (fill solid) (layer "F.CrtYd"))
    (fp_poly
      (pts
        (xy 3.71 0.74)
        (xy 3.89 0.74)
        (xy 3.89 1.19)
        (xy 3.71 1.19)
      )

      (stroke (width 0.05) (type solid)) (fill solid) (layer "F.CrtYd"))
    (fp_poly
      (pts
        (xy 4.1 0.74)
        (xy 4.29 0.74)
        (xy 4.29 1.19)
        (xy 4.1 1.19)
      )

      (stroke (width 0.05) (type solid)) (fill solid) (layer "F.CrtYd"))
    (fp_poly
      (pts
        (xy 4.11 -1.19)
        (xy 4.29 -1.19)
        (xy 4.29 -0.76)
        (xy 4.11 -0.76)
      )

      (stroke (width 0.05) (type solid)) (fill solid) (layer "F.CrtYd"))
    (fp_poly
      (pts
        (xy 4.5 0.74)
        (xy 4.7 0.74)
        (xy 4.7 1.19)
        (xy 4.5 1.19)
      )

      (stroke (width 0.05) (type solid)) (fill solid) (layer "F.CrtYd"))
    (fp_poly
      (pts
        (xy 4.51 -1.19)
        (xy 4.7 -1.19)
        (xy 4.7 -0.76)
        (xy 4.51 -0.76)
      )

      (stroke (width 0.05) (type solid)) (fill solid) (layer "F.CrtYd"))
    (fp_poly
      (pts
        (xy 4.9 -1.19)
        (xy 5.09 -1.19)
        (xy 5.09 -0.76)
        (xy 4.9 -0.76)
      )

      (stroke (width 0.05) (type solid)) (fill solid) (layer "F.CrtYd"))
    (fp_poly
      (pts
        (xy 4.9 0.74)
        (xy 5.09 0.74)
        (xy 5.09 1.19)
        (xy 4.9 1.19)
      )

      (stroke (width 0.05) (type solid)) (fill solid) (layer "F.CrtYd"))
    (fp_poly
      (pts
        (xy 5.3 0.74)
        (xy 5.49 0.74)
        (xy 5.49 1.19)
        (xy 5.3 1.19)
      )

      (stroke (width 0.05) (type solid)) (fill solid) (layer "F.CrtYd"))
    (fp_poly
      (pts
        (xy 5.31 -1.19)
        (xy 5.49 -1.19)
        (xy 5.49 -0.76)
        (xy 5.31 -0.76)
      )

      (stroke (width 0.05) (type solid)) (fill solid) (layer "F.CrtYd"))
    (fp_poly
      (pts
        (xy 5.7 0.74)
        (xy 5.9 0.74)
        (xy 5.9 1.19)
        (xy 5.7 1.19)
      )

      (stroke (width 0.05) (type solid)) (fill solid) (layer "F.CrtYd"))
    (fp_poly
      (pts
        (xy 5.71 -1.19)
        (xy 5.9 -1.19)
        (xy 5.9 -0.76)
        (xy 5.71 -0.76)
      )

      (stroke (width 0.05) (type solid)) (fill solid) (layer "F.CrtYd"))
    (fp_poly
      (pts
        (xy 6.1 -1.19)
        (xy 6.29 -1.19)
        (xy 6.29 -0.76)
        (xy 6.1 -0.76)
      )

      (stroke (width 0.05) (type solid)) (fill solid) (layer "F.CrtYd"))
    (fp_poly
      (pts
        (xy 6.11 0.74)
        (xy 6.29 0.74)
        (xy 6.29 1.19)
        (xy 6.11 1.19)
      )

      (stroke (width 0.05) (type solid)) (fill solid) (layer "F.CrtYd"))
    (fp_poly
      (pts
        (xy 6.5 0.74)
        (xy 6.7 0.74)
        (xy 6.7 1.19)
        (xy 6.5 1.19)
      )

      (stroke (width 0.05) (type solid)) (fill solid) (layer "F.CrtYd"))
    (fp_poly
      (pts
        (xy 6.52 -1.19)
        (xy 6.7 -1.19)
        (xy 6.7 -0.76)
        (xy 6.52 -0.76)
      )

      (stroke (width 0.05) (type solid)) (fill solid) (layer "F.CrtYd"))
    (fp_poly
      (pts
        (xy 6.9 -1.19)
        (xy 7.09 -1.19)
        (xy 7.09 -0.76)
        (xy 6.9 -0.76)
      )

      (stroke (width 0.05) (type solid)) (fill solid) (layer "F.CrtYd"))
    (fp_poly
      (pts
        (xy 6.91 0.74)
        (xy 7.09 0.74)
        (xy 7.09 1.19)
        (xy 6.91 1.19)
      )

      (stroke (width 0.05) (type solid)) (fill solid) (layer "F.CrtYd"))
    (fp_poly
      (pts
        (xy 7.31 -1.19)
        (xy 7.49 -1.19)
        (xy 7.49 -0.76)
        (xy 7.31 -0.76)
      )

      (stroke (width 0.05) (type solid)) (fill solid) (layer "F.CrtYd"))
    (fp_poly
      (pts
        (xy 7.31 0.74)
        (xy 7.49 0.74)
        (xy 7.49 1.19)
        (xy 7.31 1.19)
      )

      (stroke (width 0.05) (type solid)) (fill solid) (layer "F.CrtYd"))
    (fp_poly
      (pts
        (xy 7.71 -1.19)
        (xy 7.9 -1.19)
        (xy 7.9 -0.76)
        (xy 7.71 -0.76)
      )

      (stroke (width 0.05) (type solid)) (fill solid) (layer "F.CrtYd"))
    (fp_poly
      (pts
        (xy 7.71 0.74)
        (xy 7.9 0.74)
        (xy 7.9 1.19)
        (xy 7.71 1.19)
      )

      (stroke (width 0.05) (type solid)) (fill solid) (layer "F.CrtYd"))
    (fp_poly
      (pts
        (xy 8.11 -1.19)
        (xy 8.3 -1.19)
        (xy 8.3 -0.76)
        (xy 8.11 -0.76)
      )

      (stroke (width 0.05) (type solid)) (fill solid) (layer "F.CrtYd"))
    (fp_poly
      (pts
        (xy 8.12 0.74)
        (xy 8.3 0.74)
        (xy 8.3 1.19)
        (xy 8.12 1.19)
      )

      (stroke (width 0.05) (type solid)) (fill solid) (layer "F.CrtYd"))
    (fp_poly
      (pts
        (xy 8.5 -1.19)
        (xy 8.69 -1.19)
        (xy 8.69 -0.76)
        (xy 8.5 -0.76)
      )

      (stroke (width 0.05) (type solid)) (fill solid) (layer "F.CrtYd"))
    (fp_poly
      (pts
        (xy 8.53 0.74)
        (xy 8.69 0.74)
        (xy 8.69 1.19)
        (xy 8.53 1.19)
      )

      (stroke (width 0.05) (type solid)) (fill solid) (layer "F.CrtYd"))
    (fp_poly
      (pts
        (xy 8.9 -1.19)
        (xy 9.09 -1.19)
        (xy 9.09 -0.76)
        (xy 8.9 -0.76)
      )

      (stroke (width 0.05) (type solid)) (fill solid) (layer "F.CrtYd"))
    (fp_poly
      (pts
        (xy 8.91 0.74)
        (xy 9.09 0.74)
        (xy 9.09 1.19)
        (xy 8.91 1.19)
      )

      (stroke (width 0.05) (type solid)) (fill solid) (layer "F.CrtYd"))
    (fp_poly
      (pts
        (xy 9.3 0.74)
        (xy 9.49 0.74)
        (xy 9.49 1.19)
        (xy 9.3 1.19)
      )

      (stroke (width 0.05) (type solid)) (fill solid) (layer "F.CrtYd"))
    (fp_poly
      (pts
        (xy 9.32 -1.19)
        (xy 9.49 -1.19)
        (xy 9.49 -0.76)
        (xy 9.32 -0.76)
      )

      (stroke (width 0.05) (type solid)) (fill solid) (layer "F.CrtYd"))
    (fp_poly
      (pts
        (xy 9.73 -1.19)
        (xy 9.9 -1.19)
        (xy 9.9 -0.76)
        (xy 9.73 -0.76)
      )

      (stroke (width 0.05) (type solid)) (fill solid) (layer "F.CrtYd"))
    (fp_poly
      (pts
        (xy 9.73 0.74)
        (xy 9.9 0.74)
        (xy 9.9 1.19)
        (xy 9.73 1.19)
      )

      (stroke (width 0.05) (type solid)) (fill solid) (layer "F.CrtYd"))
    (fp_line (start -11.301 -1.44) (end -10.08 -1.44)
      (stroke (width 0.15) (type solid)) (layer "F.Fab"))
    (fp_line (start -11.301 1.439) (end -11.301 -1.44)
      (stroke (width 0.15) (type solid)) (layer "F.Fab"))
    (fp_line (start -10.16 2.539) (end -10.15 2.539)
      (stroke (width 0.15) (type solid)) (layer "F.Fab"))
    (fp_line (start -10.08 -1.44) (end 10.079 -1.44)
      (stroke (width 0.15) (type solid)) (layer "F.Fab"))
    (fp_line (start -10.08 1.439) (end -11.301 1.439)
      (stroke (width 0.15) (type solid)) (layer "F.Fab"))
    (fp_line (start 10.079 -1.44) (end 11.3 -1.44)
      (stroke (width 0.15) (type solid)) (layer "F.Fab"))
    (fp_line (start 10.079 1.439) (end -10.061 1.439)
      (stroke (width 0.15) (type solid)) (layer "F.Fab"))
    (fp_line (start 11.3 -1.44) (end 11.3 1.439)
      (stroke (width 0.15) (type solid)) (layer "F.Fab"))
    (fp_line (start 11.3 1.439) (end 10.079 1.439)
      (stroke (width 0.15) (type solid)) (layer "F.Fab"))
    (pad "1" smd rect (at -9.801 1.54 180) (size 0.2 0.7) (layers "F.Cu" "F.Paste" "F.Mask")
      (net 95 "USBOTG_ID") (pintype "passive"))
    (pad "2" smd rect (at -9.801 -1.541 180) (size 0.2 0.7) (layers "F.Cu" "F.Paste" "F.Mask")
      (net 96 "PCIE_CLK_nREQ") (pintype "passive"))
    (pad "3" smd rect (at -9.401 1.54 180) (size 0.2 0.7) (layers "F.Cu" "F.Paste" "F.Mask")
      (net 97 "USB2_N") (pintype "passive"))
    (pad "4" smd rect (at -9.401 -1.541 180) (size 0.2 0.7) (layers "F.Cu" "F.Paste" "F.Mask")
      (net 209 "unconnected-(J8-Pad4)") (pintype "passive+no_connect"))
    (pad "5" smd rect (at -9 1.54 180) (size 0.2 0.7) (layers "F.Cu" "F.Paste" "F.Mask")
      (net 98 "USB2_P") (pintype "passive"))
    (pad "6" smd rect (at -9 -1.541 180) (size 0.2 0.7) (layers "F.Cu" "F.Paste" "F.Mask")
      (net 210 "unconnected-(J8-Pad6)") (pintype "passive+no_connect"))
    (pad "7" smd rect (at -8.6 1.54 180) (size 0.2 0.7) (layers "F.Cu" "F.Paste" "F.Mask")
      (net 11 "GND") (pintype "passive"))
    (pad "8" smd rect (at -8.6 -1.541 180) (size 0.2 0.7) (layers "F.Cu" "F.Paste" "F.Mask")
      (net 11 "GND") (pintype "passive"))
    (pad "9" smd rect (at -8.2 1.54 180) (size 0.2 0.7) (layers "F.Cu" "F.Paste" "F.Mask")
      (net 99 "PSCIE_nRST") (pintype "passive"))
    (pad "10" smd rect (at -8.2 -1.541 180) (size 0.2 0.7) (layers "F.Cu" "F.Paste" "F.Mask")
      (net 100 "PCIE_CLK_P") (pintype "passive"))
    (pad "11" smd rect (at -7.8 1.54 180) (size 0.2 0.7) (layers "F.Cu" "F.Paste" "F.Mask")
      (net 101 "TV_OUT") (pintype "passive"))
    (pad "12" smd rect (at -7.8 -1.541 180) (size 0.2 0.7) (layers "F.Cu" "F.Paste" "F.Mask")
      (net 102 "PCIE_CLK_N") (pintype "passive"))
    (pad "13" smd rect (at -7.401 1.54 180) (size 0.2 0.7) (layers "F.Cu" "F.Paste" "F.Mask")
      (net 11 "GND") (pintype "passive"))
    (pad "14" smd rect (at -7.401 -1.541 180) (size 0.2 0.7) (layers "F.Cu" "F.Paste" "F.Mask")
      (net 11 "GND") (pintype "passive"))
    (pad "15" smd rect (at -7 1.54 180) (size 0.2 0.7) (layers "F.Cu" "F.Paste" "F.Mask")
      (net 103 "CAM1_D0_N") (pintype "passive"))
    (pad "16" smd rect (at -7 -1.541 180) (size 0.2 0.7) (layers "F.Cu" "F.Paste" "F.Mask")
      (net 18 "PCIE_RX_P") (pintype "passive"))
    (pad "17" smd rect (at -6.6 1.54 180) (size 0.2 0.7) (layers "F.Cu" "F.Paste" "F.Mask")
      (net 104 "CAM1_D0_P") (pintype "passive"))
    (pad "18" smd rect (at -6.6 -1.541 180) (size 0.2 0.7) (layers "F.Cu" "F.Paste" "F.Mask")
      (net 16 "PCIE_RX_N") (pintype "passive"))
    (pad "19" smd rect (at -6.201 1.54 180) (size 0.2 0.7) (layers "F.Cu" "F.Paste" "F.Mask")
      (net 11 "GND") (pintype "passive"))
    (pad "20" smd rect (at -6.201 -1.541 180) (size 0.2 0.7) (layers "F.Cu" "F.Paste" "F.Mask")
      (net 11 "GND") (pintype "passive"))
    (pad "21" smd rect (at -5.8 1.54 180) (size 0.2 0.7) (layers "F.Cu" "F.Paste" "F.Mask")
      (net 105 "CAM1_D1_N") (pintype "passive"))
    (pad "22" smd rect (at -5.8 -1.541 180) (size 0.2 0.7) (layers "F.Cu" "F.Paste" "F.Mask")
      (net 17 "PCIE_TX_P") (pintype "passive"))
    (pad "23" smd rect (at -5.401 1.54 180) (size 0.2 0.7) (layers "F.Cu" "F.Paste" "F.Mask")
      (net 106 "CAM1_D1_P") (pintype "passive"))
    (pad "24" smd rect (at -5.401 -1.541 180) (size 0.2 0.7) (layers "F.Cu" "F.Paste" "F.Mask")
      (net 15 "PCIE_TX_N") (pintype "passive"))
    (pad "25" smd rect (at -5 1.54 180) (size 0.2 0.7) (layers "F.Cu" "F.Paste" "F.Mask")
      (net 11 "GND") (pintype "passive"))
    (pad "26" smd rect (at -5 -1.541 180) (size 0.2 0.7) (layers "F.Cu" "F.Paste" "F.Mask")
      (net 11 "GND") (pintype "passive"))
    (pad "27" smd rect (at -4.6 1.54 180) (size 0.2 0.7) (layers "F.Cu" "F.Paste" "F.Mask")
      (net 107 "CAM1_C_N") (pintype "passive"))
    (pad "28" smd rect (at -4.6 -1.541 180) (size 0.2 0.7) (layers "F.Cu" "F.Paste" "F.Mask")
      (net 108 "CAM0_D0_N") (pintype "passive"))
    (pad "29" smd rect (at -4.201 1.54 180) (size 0.2 0.7) (layers "F.Cu" "F.Paste" "F.Mask")
      (net 109 "CAM1_C_P") (pintype "passive"))
    (pad "30" smd rect (at -4.201 -1.541 180) (size 0.2 0.7) (layers "F.Cu" "F.Paste" "F.Mask")
      (net 110 "CAM0_D0_P") (pintype "passive"))
    (pad "31" smd rect (at -3.8 1.54 180) (size 0.2 0.7) (layers "F.Cu" "F.Paste" "F.Mask")
      (net 11 "GND") (pintype "passive"))
    (pad "32" smd rect (at -3.8 -1.541 180) (size 0.2 0.7) (layers "F.Cu" "F.Paste" "F.Mask")
      (net 11 "GND") (pintype "passive"))
    (pad "33" smd rect (at -3.4 1.54 180) (size 0.2 0.7) (layers "F.Cu" "F.Paste" "F.Mask")
      (net 111 "CAM1_D2_N") (pintype "passive"))
    (pad "34" smd rect (at -3.4 -1.541 180) (size 0.2 0.7) (layers "F.Cu" "F.Paste" "F.Mask")
      (net 112 "CAM0_D1_N") (pintype "passive"))
    (pad "35" smd rect (at -3 1.54 180) (size 0.2 0.7) (layers "F.Cu" "F.Paste" "F.Mask")
      (net 113 "CAM1_D2_P") (pintype "passive"))
    (pad "36" smd rect (at -3 -1.541 180) (size 0.2 0.7) (layers "F.Cu" "F.Paste" "F.Mask")
      (net 114 "CAM0_D1_P") (pintype "passive"))
    (pad "37" smd rect (at -2.601 1.54 180) (size 0.2 0.7) (layers "F.Cu" "F.Paste" "F.Mask")
      (net 11 "GND") (pintype "passive"))
    (pad "38" smd rect (at -2.601 -1.541 180) (size 0.2 0.7) (layers "F.Cu" "F.Paste" "F.Mask")
      (net 11 "GND") (pintype "passive"))
    (pad "39" smd rect (at -2.201 1.54 180) (size 0.2 0.7) (layers "F.Cu" "F.Paste" "F.Mask")
      (net 115 "CAM1_D3_N") (pintype "passive"))
    (pad "40" smd rect (at -2.201 -1.541 180) (size 0.2 0.7) (layers "F.Cu" "F.Paste" "F.Mask")
      (net 116 "CAM0_C_N") (pintype "passive"))
    (pad "41" smd rect (at -1.801 1.54 180) (size 0.2 0.7) (layers "F.Cu" "F.Paste" "F.Mask")
      (net 117 "CAM1_D3_P") (pintype "passive"))
    (pad "42" smd rect (at -1.801 -1.541 180) (size 0.2 0.7) (layers "F.Cu" "F.Paste" "F.Mask")
      (net 118 "CAM0_C_P") (pintype "passive"))
    (pad "43" smd rect (at -1.4 1.54 180) (size 0.2 0.7) (layers "F.Cu" "F.Paste" "F.Mask")
      (net 119 "HDMI1_HOTPLUG") (pintype "passive"))
    (pad "44" smd rect (at -1.4 -1.541 180) (size 0.2 0.7) (layers "F.Cu" "F.Paste" "F.Mask")
      (net 11 "GND") (pintype "passive"))
    (pad "45" smd rect (at -1 1.54 180) (size 0.2 0.7) (layers "F.Cu" "F.Paste" "F.Mask")
      (net 120 "HDMI1_SDA") (pintype "passive"))
    (pad "46" smd rect (at -1 -1.541 180) (size 0.2 0.7) (layers "F.Cu" "F.Paste" "F.Mask")
      (net 121 "HDMI1_D2_P") (pintype "passive"))
    (pad "47" smd rect (at -0.6 1.54 180) (size 0.2 0.7) (layers "F.Cu" "F.Paste" "F.Mask")
      (net 122 "HDMI1_SCL") (pintype "passive"))
    (pad "48" smd rect (at -0.6 -1.541 180) (size 0.2 0.7) (layers "F.Cu" "F.Paste" "F.Mask")
      (net 123 "HDMI1_D2_N") (pintype "passive"))
    (pad "49" smd rect (at -0.201 1.54 180) (size 0.2 0.7) (layers "F.Cu" "F.Paste" "F.Mask")
      (net 124 "HDMI1_CEC") (pintype "passive"))
    (pad "50" smd rect (at -0.201 -1.541 180) (size 0.2 0.7) (layers "F.Cu" "F.Paste" "F.Mask")
      (net 11 "GND") (pintype "passive"))
    (pad "51" smd rect (at 0.2 1.54 180) (size 0.2 0.7) (layers "F.Cu" "F.Paste" "F.Mask")
      (net 125 "HDMI0_CEC") (pintype "passive"))
    (pad "52" smd rect (at 0.2 -1.541 180) (size 0.2 0.7) (layers "F.Cu" "F.Paste" "F.Mask")
      (net 126 "HDMI1_D1_P") (pintype "passive"))
    (pad "53" smd rect (at 0.599 1.54 180) (size 0.2 0.7) (layers "F.Cu" "F.Paste" "F.Mask")
      (net 127 "HDMI0_HOTPLUG") (pintype "passive"))
    (pad "54" smd rect (at 0.599 -1.541 180) (size 0.2 0.7) (layers "F.Cu" "F.Paste" "F.Mask")
      (net 128 "HDMI1_D1_N") (pintype "passive"))
    (pad "55" smd rect (at 0.999 1.54 180) (size 0.2 0.7) (layers "F.Cu" "F.Paste" "F.Mask")
      (net 11 "GND") (pintype "passive"))
    (pad "56" smd rect (at 0.999 -1.541 180) (size 0.2 0.7) (layers "F.Cu" "F.Paste" "F.Mask")
      (net 11 "GND") (pintype "passive"))
    (pad "57" smd rect (at 1.399 1.54 180) (size 0.2 0.7) (layers "F.Cu" "F.Paste" "F.Mask")
      (net 129 "DSI0_D0_N") (pintype "passive"))
    (pad "58" smd rect (at 1.399 -1.541 180) (size 0.2 0.7) (layers "F.Cu" "F.Paste" "F.Mask")
      (net 130 "HDMI1_D0_P") (pintype "passive"))
    (pad "59" smd rect (at 1.8 1.54 180) (size 0.2 0.7) (layers "F.Cu" "F.Paste" "F.Mask")
      (net 131 "DSI0_D0_P") (pintype "passive"))
    (pad "60" smd rect (at 1.8 -1.541 180) (size 0.2 0.7) (layers "F.Cu" "F.Paste" "F.Mask")
      (net 132 "HDMI1_D0_N") (pintype "passive"))
    (pad "61" smd rect (at 2.2 1.54 180) (size 0.2 0.7) (layers "F.Cu" "F.Paste" "F.Mask")
      (net 11 "GND") (pintype "passive"))
    (pad "62" smd rect (at 2.2 -1.541 180) (size 0.2 0.7) (layers "F.Cu" "F.Paste" "F.Mask")
      (net 11 "GND") (pintype "passive"))
    (pad "63" smd rect (at 2.6 1.54 180) (size 0.2 0.7) (layers "F.Cu" "F.Paste" "F.Mask")
      (net 133 "DSI0_D1_N") (pintype "passive"))
    (pad "64" smd rect (at 2.6 -1.541 180) (size 0.2 0.7) (layers "F.Cu" "F.Paste" "F.Mask")
      (net 134 "HDMI1_CK_P") (pintype "passive"))
    (pad "65" smd rect (at 2.999 1.54 180) (size 0.2 0.7) (layers "F.Cu" "F.Paste" "F.Mask")
      (net 135 "DSI0_D1_P") (pintype "passive"))
    (pad "66" smd rect (at 2.999 -1.541 180) (size 0.2 0.7) (layers "F.Cu" "F.Paste" "F.Mask")
      (net 136 "HDMI1_CK_N") (pintype "passive"))
    (pad "67" smd rect (at 3.399 1.54 180) (size 0.2 0.7) (layers "F.Cu" "F.Paste" "F.Mask")
      (net 11 "GND") (pintype "passive"))
    (pad "68" smd rect (at 3.399 -1.541 180) (size 0.2 0.7) (layers "F.Cu" "F.Paste" "F.Mask")
      (net 11 "GND") (pintype "passive"))
    (pad "69" smd rect (at 3.799 1.54 180) (size 0.2 0.7) (layers "F.Cu" "F.Paste" "F.Mask")
      (net 137 "DSI0_C_N") (pintype "passive"))
    (pad "70" smd rect (at 3.799 -1.541 180) (size 0.2 0.7) (layers "F.Cu" "F.Paste" "F.Mask")
      (net 36 "HDMI0_D2_P") (pintype "passive"))
    (pad "71" smd rect (at 4.2 1.54 180) (size 0.2 0.7) (layers "F.Cu" "F.Paste" "F.Mask")
      (net 138 "DSI0_C_P") (pintype "passive"))
    (pad "72" smd rect (at 4.2 -1.541 180) (size 0.2 0.7) (layers "F.Cu" "F.Paste" "F.Mask")
      (net 37 "HDMI0_D2_N") (pintype "passive"))
    (pad "73" smd rect (at 4.599 1.54 180) (size 0.2 0.7) (layers "F.Cu" "F.Paste" "F.Mask")
      (net 11 "GND") (pintype "passive"))
    (pad "74" smd rect (at 4.599 -1.541 180) (size 0.2 0.7) (layers "F.Cu" "F.Paste" "F.Mask")
      (net 11 "GND") (pintype "passive"))
    (pad "75" smd rect (at 4.999 1.54 180) (size 0.2 0.7) (layers "F.Cu" "F.Paste" "F.Mask")
      (net 139 "DSI1_D0_N") (pintype "passive"))
    (pad "76" smd rect (at 4.999 -1.541 180) (size 0.2 0.7) (layers "F.Cu" "F.Paste" "F.Mask")
      (net 38 "HDMI0_D1_P") (pintype "passive"))
    (pad "77" smd rect (at 5.4 1.54 180) (size 0.2 0.7) (layers "F.Cu" "F.Paste" "F.Mask")
      (net 140 "DSI1_D0_P") (pintype "passive"))
    (pad "78" smd rect (at 5.4 -1.541 180) (size 0.2 0.7) (layers "F.Cu" "F.Paste" "F.Mask")
      (net 39 "HDMI0_D1_N") (pintype "passive"))
    (pad "79" smd rect (at 5.799 1.54 180) (size 0.2 0.7) (layers "F.Cu" "F.Paste" "F.Mask")
      (net 11 "GND") (pintype "passive"))
    (pad "80" smd rect (at 5.799 -1.541 180) (size 0.2 0.7) (layers "F.Cu" "F.Paste" "F.Mask")
      (net 11 "GND") (pintype "passive"))
    (pad "81" smd rect (at 6.2 1.54 180) (size 0.2 0.7) (layers "F.Cu" "F.Paste" "F.Mask")
      (net 141 "DSI1_D1_N") (pintype "passive"))
    (pad "82" smd rect (at 6.2 -1.541 180) (size 0.2 0.7) (layers "F.Cu" "F.Paste" "F.Mask")
      (net 142 "HDMI0_D0_P") (pintype "passive"))
    (pad "83" smd rect (at 6.599 1.54 180) (size 0.2 0.7) (layers "F.Cu" "F.Paste" "F.Mask")
      (net 143 "DSI1_D1_P") (pintype "passive"))
    (pad "84" smd rect (at 6.599 -1.541 180) (size 0.2 0.7) (layers "F.Cu" "F.Paste" "F.Mask")
      (net 144 "HDMI0_D0_N") (pintype "passive"))
    (pad "85" smd rect (at 6.999 1.54 180) (size 0.2 0.7) (layers "F.Cu" "F.Paste" "F.Mask")
      (net 11 "GND") (pintype "passive"))
    (pad "86" smd rect (at 6.999 -1.541 180) (size 0.2 0.7) (layers "F.Cu" "F.Paste" "F.Mask")
      (net 11 "GND") (pintype "passive"))
    (pad "87" smd rect (at 7.4 1.54 180) (size 0.2 0.7) (layers "F.Cu" "F.Paste" "F.Mask")
      (net 145 "DSI1_C_N") (pintype "passive"))
    (pad "88" smd rect (at 7.4 -1.541 180) (size 0.2 0.7) (layers "F.Cu" "F.Paste" "F.Mask")
      (net 40 "HDMI0_CK_P") (pintype "passive"))
    (pad "89" smd rect (at 7.799 1.54 180) (size 0.2 0.7) (layers "F.Cu" "F.Paste" "F.Mask")
      (net 146 "DSI1_C_P") (pintype "passive"))
    (pad "90" smd rect (at 7.799 -1.541 180) (size 0.2 0.7) (layers "F.Cu" "F.Paste" "F.Mask")
      (net 41 "HDMI0_CK_N") (pintype "passive"))
    (pad "91" smd rect (at 8.199 1.54 180) (size 0.2 0.7) (layers "F.Cu" "F.Paste" "F.Mask")
      (net 11 "GND") (pintype "passive"))
    (pad "92" smd rect (at 8.199 -1.541 180) (size 0.2 0.7) (layers "F.Cu" "F.Paste" "F.Mask")
      (net 11 "GND") (pintype "passive"))
    (pad "93" smd rect (at 8.599 1.54 180) (size 0.2 0.7) (layers "F.Cu" "F.Paste" "F.Mask")
      (net 147 "DSI2_D1_N") (pintype "passive"))
    (pad "94" smd rect (at 8.599 -1.541 180) (size 0.2 0.7) (layers "F.Cu" "F.Paste" "F.Mask")
      (net 148 "DSI1_D3_N") (pintype "passive"))
    (pad "95" smd rect (at 8.999 1.54 180) (size 0.2 0.7) (layers "F.Cu" "F.Paste" "F.Mask")
      (net 149 "DSI2_D1_P") (pintype "passive"))
    (pad "96" smd rect (at 8.999 -1.541 180) (size 0.2 0.7) (layers "F.Cu" "F.Paste" "F.Mask")
      (net 150 "DSI1_D3_P") (pintype "passive"))
    (pad "97" smd rect (at 9.4 1.54 180) (size 0.2 0.7) (layers "F.Cu" "F.Paste" "F.Mask")
      (net 11 "GND") (pintype "passive"))
    (pad "98" smd rect (at 9.4 -1.541 180) (size 0.2 0.7) (layers "F.Cu" "F.Paste" "F.Mask")
      (net 11 "GND") (pintype "passive"))
    (pad "99" smd rect (at 9.8 1.54 180) (size 0.2 0.7) (layers "F.Cu" "F.Paste" "F.Mask")
      (net 151 "HDMI0_SDA") (pintype "passive"))
    (pad "100" smd rect (at 9.8 -1.541 180) (size 0.2 0.7) (layers "F.Cu" "F.Paste" "F.Mask")
      (net 152 "HDMI0_SCL") (pintype "passive"))
  )

  (footprint "scalenode-cm4-baseboard-footprints:R_0402_1005Metric" (layer "F.Cu")
    (at 175.959 85.186 90)
    (descr "Resistor SMD 0402")
    (tags "resistor SMD 0402")
    (property "Author" "Antmicro")
    (property "License" "Apache-2.0")
    (property "MPN" "CR0402-FX-1002GLF")
    (property "Manufacturer" "Bourns")
    (property "Sheetfile" "interfaces.kicad_sch")
    (property "Sheetname" "Interfaces")
    (property "Tolerance" "1%")
    (property "Val" "10k")
    (property "ki_description" "10k resistor in 0402 package with 1% tolerance")
    (attr smd)
    (fp_text reference "R14" (at -0.439 0.491 180) (layer "F.SilkS")
        (effects (font (size 0.7 0.7) (thickness 0.15)) (justify left bottom))
    )
    (fp_text value "R_10k_0402" (at 0 1.4 90) (layer "F.Fab")
        (effects (font (size 0.7 0.7) (thickness 0.15)) (justify left bottom))
    )
    (fp_text user "Author: Antmicro" (at -0.95 4.169 90) (layer "F.Fab") hide
        (effects (font (size 0.7 0.7) (thickness 0.15)) (justify left bottom))
    )
    (fp_text user "${REFERENCE}" (at -0.95 3.168 90) (layer "F.Fab") hide
        (effects (font (size 0.7 0.7) (thickness 0.15)) (justify left bottom))
    )
    (fp_text user "License: Apache-2.0" (at -0.95 5.169 90) (layer "F.Fab") hide
        (effects (font (size 0.7 0.7) (thickness 0.15)) (justify left bottom))
    )
    (fp_rect (start -0.95 -0.48) (end 0.95 0.48)
      (stroke (width 0.05) (type solid)) (fill none) (layer "F.CrtYd"))
    (fp_rect (start -0.5 -0.25) (end 0.5 0.25)
      (stroke (width 0.15) (type solid)) (fill none) (layer "F.Fab"))
    (pad "1" smd roundrect (at -0.485 0 90) (size 0.59 0.64) (layers "F.Cu" "F.Paste" "F.Mask") (roundrect_rratio 0.25)
      (net 250 "Net-(U1-~{OE})") (pintype "passive"))
    (pad "2" smd roundrect (at 0.485 0 90) (size 0.59 0.64) (layers "F.Cu" "F.Paste" "F.Mask") (roundrect_rratio 0.25)
      (net 11 "GND") (pintype "passive"))
  )

  (footprint "scalenode-cm4-baseboard-footprints:C_0402_1005Metric" (layer "F.Cu")
    (at 85.75 84.5 -90)
    (descr "Capacitor SMD 0402")
    (tags "capacitor SMD 0402")
    (property "Author" "Antmicro")
    (property "Dielectric" "")
    (property "License" "Apache-2.0")
    (property "MPN" "C1005X6S1A105K050BC")
    (property "Manufacturer" "TDK")
    (property "Sheetfile" "interfaces.kicad_sch")
    (property "Sheetname" "Interfaces")
    (property "Val" "1u")
    (property "Voltage" "")
    (property "ki_description" " ")
    (attr smd)
    (fp_text reference "C15" (at -1.25 -1.5 90) (layer "F.SilkS")
        (effects (font (size 0.7 0.7) (thickness 0.15)) (justify right bottom))
    )
    (fp_text value "C_1u_0402" (at 0 1.4 90) (layer "F.Fab")
        (effects (font (size 0.7 0.7) (thickness 0.15)) (justify right bottom))
    )
    (fp_text user "${REFERENCE}" (at -0.932 3.168 90) (layer "F.Fab") hide
        (effects (font (size 0.7 0.7) (thickness 0.15)) (justify right bottom))
    )
    (fp_text user "License: Apache-2.0" (at -0.932 5.17 90) (layer "F.Fab") hide
        (effects (font (size 0.7 0.7) (thickness 0.15)) (justify right bottom))
    )
    (fp_text user "Author: Antmicro" (at -0.932 4.17 90) (layer "F.Fab") hide
        (effects (font (size 0.7 0.7) (thickness 0.15)) (justify right bottom))
    )
    (fp_rect (start -0.94 -0.47) (end 0.94 0.47)
      (stroke (width 0.05) (type solid)) (fill none) (layer "F.CrtYd"))
    (fp_rect (start -0.499 -0.249) (end 0.499 0.249)
      (stroke (width 0.15) (type solid)) (fill none) (layer "F.Fab"))
    (pad "1" smd roundrect (at -0.484 0 270) (size 0.59 0.64) (layers "F.Cu" "F.Paste" "F.Mask") (roundrect_rratio 0.25)
      (net 11 "GND") (pintype "passive"))
    (pad "2" smd roundrect (at 0.484 0 270) (size 0.59 0.64) (layers "F.Cu" "F.Paste" "F.Mask") (roundrect_rratio 0.25)
      (net 232 "3V3_RPi") (pintype "passive"))
  )

  (footprint "scalenode-cm4-baseboard-footprints:MP_Pad6.2mm_Drill2.75mm" (layer "F.Cu")
    (at 200.341 93.092)
    (descr "mounting hole 2.75mm M2.5 D6.2mm PTH annular")
    (property "Author" "Antmicro")
    (property "License" "Apache-2.0")
    (property "MPN" "")
    (property "Manufacturer" "")
    (property "Sheetfile" "expansion-connectors.kicad_sch")
    (property "Sheetname" "Expansion connectors")
    (property "exclude_from_bom" "")
    (property "ki_description" "Mechanical part")
    (property "ki_keywords" "MECHANICAL")
    (attr through_hole exclude_from_pos_files exclude_from_bom)
    (fp_text reference "MP2" (at -1.091 -3.3) (layer "F.SilkS") hide
        (effects (font (size 0.7 0.7) (thickness 0.15)) (justify left bottom))
    )
    (fp_text value "MP_Pad6.2mm_Drill2.75mm" (at -11.541666 4.2) (layer "F.Fab")
        (effects (font (size 0.7 0.7) (thickness 0.15)) (justify left bottom))
    )
    (fp_text user "${REFERENCE}" (at 0 2.499) (layer "F.Fab") hide
        (effects (font (size 0.7 0.7) (thickness 0.15)) (justify left bottom))
    )
    (fp_text user "License: Apache-2.0" (at 0 4.9) (layer "F.Fab") hide
        (effects (font (size 0.7 0.7) (thickness 0.15)) (justify left bottom))
    )
    (fp_text user "Author: Antmicro" (at 0 3.7) (layer "F.Fab") hide
        (effects (font (size 0.7 0.7) (thickness 0.15)) (justify left bottom))
    )
    (pad "1" thru_hole circle (at 0 0) (size 6.2 6.2) (drill 2.75) (layers "*.Cu" "*.Mask")
      (net 234 "unconnected-(MP2-Pad1)") (pintype "passive+no_connect"))
  )

  (footprint "scalenode-cm4-baseboard-footprints:MP_Pad6.2mm_Drill2.75mm" (layer "F.Cu")
    (at 200.341 60.092)
    (descr "mounting hole 2.75mm M2.5 D6.2mm PTH annular")
    (property "Author" "Antmicro")
    (property "License" "Apache-2.0")
    (property "MPN" "")
    (property "Manufacturer" "")
    (property "Sheetfile" "expansion-connectors.kicad_sch")
    (property "Sheetname" "Expansion connectors")
    (property "exclude_from_bom" "")
    (property "ki_description" "Mechanical part")
    (property "ki_keywords" "MECHANICAL")
    (attr through_hole exclude_from_pos_files exclude_from_bom)
    (fp_text reference "MP3" (at -1.091 4.158) (layer "F.SilkS") hide
        (effects (font (size 0.7 0.7) (thickness 0.15)) (justify left bottom))
    )
    (fp_text value "MP_Pad6.2mm_Drill2.75mm" (at -11.541666 4.2) (layer "F.Fab")
        (effects (font (size 0.7 0.7) (thickness 0.15)) (justify left bottom))
    )
    (fp_text user "License: Apache-2.0" (at 0 4.9) (layer "F.Fab") hide
        (effects (font (size 0.7 0.7) (thickness 0.15)) (justify left bottom))
    )
    (fp_text user "Author: Antmicro" (at 0 3.7) (layer "F.Fab") hide
        (effects (font (size 0.7 0.7) (thickness 0.15)) (justify left bottom))
    )
    (fp_text user "${REFERENCE}" (at 0 2.499) (layer "F.Fab") hide
        (effects (font (size 0.7 0.7) (thickness 0.15)) (justify left bottom))
    )
    (pad "1" thru_hole circle (at 0 0) (size 6.2 6.2) (drill 2.75) (layers "*.Cu" "*.Mask")
      (net 245 "unconnected-(MP3-Pad1)") (pintype "passive+no_connect"))
  )

  (footprint "scalenode-cm4-baseboard-footprints:R_0402_1005Metric" (layer "F.Cu")
    (at 150.922 62.303 90)
    (descr "Resistor SMD 0402")
    (tags "resistor SMD 0402")
    (property "Author" "Antmicro")
    (property "License" "Apache-2.0")
    (property "MPN" "CR0402-FX-4700GLF")
    (property "Manufacturer" "Bourns")
    (property "Sheetfile" "compute-module.kicad_sch")
    (property "Sheetname" "Compute module")
    (property "Tolerance" "1%")
    (property "Val" "470R")
    (property "ki_description" "470R resistor in 0402 package with 1% tolerance")
    (attr smd)
    (fp_text reference "R64" (at -1.122 -0.672 90) (layer "F.SilkS")
        (effects (font (size 0.7 0.7) (thickness 0.15)) (justify left bottom))
    )
    (fp_text value "R_470R_0402" (at -2.197 -1.022 90) (layer "F.Fab")
        (effects (font (size 0.7 0.7) (thickness 0.15)) (justify left bottom))
    )
    (fp_text user "${REFERENCE}" (at -0.95 3.168 90) (layer "F.Fab") hide
        (effects (font (size 0.7 0.7) (thickness 0.15)) (justify left bottom))
    )
    (fp_text user "License: Apache-2.0" (at -0.95 5.169 90) (layer "F.Fab") hide
        (effects (font (size 0.7 0.7) (thickness 0.15)) (justify left bottom))
    )
    (fp_text user "Author: Antmicro" (at -0.95 4.169 90) (layer "F.Fab") hide
        (effects (font (size 0.7 0.7) (thickness 0.15)) (justify left bottom))
    )
    (fp_rect (start -0.95 -0.48) (end 0.95 0.48)
      (stroke (width 0.05) (type solid)) (fill none) (layer "F.CrtYd"))
    (fp_rect (start -0.5 -0.25) (end 0.5 0.25)
      (stroke (width 0.15) (type solid)) (fill none) (layer "F.Fab"))
    (pad "1" smd roundrect (at -0.485 0 90) (size 0.59 0.64) (layers "F.Cu" "F.Paste" "F.Mask") (roundrect_rratio 0.25)
      (net 244 "PROG_MODE") (pintype "passive"))
    (pad "2" smd roundrect (at 0.485 0 90) (size 0.59 0.64) (layers "F.Cu" "F.Paste" "F.Mask") (roundrect_rratio 0.25)
      (net 246 "Net-(Q6-G)") (pintype "passive"))
  )

  (footprint "scalenode-cm4-baseboard-footprints:R_0402_1005Metric" (layer "F.Cu")
    (at 152.362 61.818)
    (descr "Resistor SMD 0402")
    (tags "resistor SMD 0402")
    (property "Author" "Antmicro")
    (property "License" "Apache-2.0")
    (property "MPN" "CR0402-FX-1002GLF")
    (property "Manufacturer" "Bourns")
    (property "Sheetfile" "compute-module.kicad_sch")
    (property "Sheetname" "Compute module")
    (property "Tolerance" "1%")
    (property "Val" "10k")
    (property "ki_description" "10k resistor in 0402 package with 1% tolerance")
    (attr smd)
    (fp_text reference "R65" (at -0.962 1.382) (layer "F.SilkS")
        (effects (font (size 0.7 0.7) (thickness 0.15)) (justify left bottom))
    )
    (fp_text value "R_10k_0402" (at 0 1.4) (layer "F.Fab")
        (effects (font (size 0.7 0.7) (thickness 0.15)) (justify left bottom))
    )
    (fp_text user "${REFERENCE}" (at -0.95 3.168) (layer "F.Fab") hide
        (effects (font (size 0.7 0.7) (thickness 0.15)) (justify left bottom))
    )
    (fp_text user "License: Apache-2.0" (at -0.95 5.169) (layer "F.Fab") hide
        (effects (font (size 0.7 0.7) (thickness 0.15)) (justify left bottom))
    )
    (fp_text user "Author: Antmicro" (at -0.95 4.169) (layer "F.Fab") hide
        (effects (font (size 0.7 0.7) (thickness 0.15)) (justify left bottom))
    )
    (fp_rect (start -0.95 -0.48) (end 0.95 0.48)
      (stroke (width 0.05) (type solid)) (fill none) (layer "F.CrtYd"))
    (fp_rect (start -0.5 -0.25) (end 0.5 0.25)
      (stroke (width 0.15) (type solid)) (fill none) (layer "F.Fab"))
    (pad "1" smd roundrect (at -0.485 0) (size 0.59 0.64) (layers "F.Cu" "F.Paste" "F.Mask") (roundrect_rratio 0.25)
      (net 246 "Net-(Q6-G)") (pintype "passive"))
    (pad "2" smd roundrect (at 0.485 0) (size 0.59 0.64) (layers "F.Cu" "F.Paste" "F.Mask") (roundrect_rratio 0.25)
      (net 11 "GND") (pintype "passive"))
  )

  (footprint "scalenode-cm4-baseboard-footprints:MSOP-10_W3mm" (layer "F.Cu")
    (at 172.149 86.329 -90)
    (property "Author" "Antmicro")
    (property "License" "Apache-2.0")
    (property "MPN" "TS3USB30EDGSR")
    (property "Manufacturer" "Texas Instruments")
    (property "Sheetfile" "interfaces.kicad_sch")
    (property "Sheetname" "Interfaces")
    (attr smd)
    (fp_text reference "U1" (at -1.929 0.424) (layer "F.SilkS")
        (effects (font (size 0.7 0.7) (thickness 0.15)) (justify left bottom))
    )
    (fp_text value "TS3USB30EDGSR" (at 0 4.799 -90) (layer "F.Fab")
        (effects (font (size 0.7 0.7) (thickness 0.15)) (justify left bottom))
    )
    (fp_text user "License: Apache-2.0" (at -2.351 7.999 -90) (layer "F.Fab") hide
        (effects (font (size 0.7 0.7) (thickness 0.15)) (justify left bottom))
    )
    (fp_text user "${REFERENCE}" (at -2.351 9.198 -90) (layer "F.Fab") hide
        (effects (font (size 0.7 0.7) (thickness 0.15)) (justify left bottom))
    )
    (fp_text user "Author: Antmicro" (at -2.351 6.799 -90) (layer "F.Fab") hide
        (effects (font (size 0.7 0.7) (thickness 0.15)) (justify left bottom))
    )
    (fp_text user "REF**" (at 0 0 -90) (layer "F.Fab") hide
        (effects (font (size 0.5 0.5) (thickness 0.05)))
    )
    (fp_line (start -1.601 -1.601) (end -1.301 -1.601)
      (stroke (width 0.15) (type solid)) (layer "F.SilkS"))
    (fp_line (start -1.601 -1.301) (end -1.601 -1.601)
      (stroke (width 0.15) (type solid)) (layer "F.SilkS"))
    (fp_line (start -1.601 1.3) (end -1.301 1.6)
      (stroke (width 0.15) (type solid)) (layer "F.SilkS"))
    (fp_line (start -1.301 1.6) (end -1.301 2.797)
      (stroke (width 0.15) (type solid)) (layer "F.SilkS"))
    (fp_line (start 1.3 -1.601) (end 1.6 -1.601)
      (stroke (width 0.15) (type solid)) (layer "F.SilkS"))
    (fp_line (start 1.6 -1.601) (end 1.6 -1.301)
      (stroke (width 0.15) (type solid)) (layer "F.SilkS"))
    (fp_line (start 1.6 1.3) (end 1.6 1.6)
      (stroke (width 0.15) (type solid)) (layer "F.SilkS"))
    (fp_line (start 1.6 1.6) (end 1.3 1.6)
      (stroke (width 0.15) (type solid)) (layer "F.SilkS"))
    (fp_circle (center -1.6 1.7) (end -1.55 1.7)
      (stroke (width 0.15) (type solid)) (fill solid) (layer "F.SilkS"))
    (fp_line (start -1.75 -3.19) (end 1.71 -3.19)
      (stroke (width 0.05) (type solid)) (layer "F.CrtYd"))
    (fp_line (start -1.75 3.18) (end -1.75 -3.19)
      (stroke (width 0.05) (type solid)) (layer "F.CrtYd"))
    (fp_line (start -1.75 3.18) (end 1.71 3.18)
      (stroke (width 0.05) (type solid)) (layer "F.CrtYd"))
    (fp_line (start 1.71 -3.19) (end 1.71 3.18)
      (stroke (width 0.05) (type solid)) (layer "F.CrtYd"))
    (fp_line (start -1.45 -1.45) (end -1.45 1.1)
      (stroke (width 0.15) (type solid)) (layer "F.Fab"))
    (fp_line (start -1.45 -1.45) (end 1.449 -1.45)
      (stroke (width 0.15) (type solid)) (layer "F.Fab"))
    (fp_line (start -1.45 1.1) (end -1.101 1.449)
      (stroke (width 0.15) (type solid)) (layer "F.Fab"))
    (fp_line (start -1.101 1.449) (end 1.449 1.449)
      (stroke (width 0.15) (type solid)) (layer "F.Fab"))
    (fp_line (start 1.449 -1.45) (end 1.449 1.449)
      (stroke (width 0.15) (type solid)) (layer "F.Fab"))
    (pad "1" smd rect (at -1 2.201 270) (size 0.3 1.45) (layers "F.Cu" "F.Paste" "F.Mask")
      (net 95 "USBOTG_ID") (pinfunction "S") (pintype "input") (solder_mask_margin 0.05))
    (pad "2" smd rect (at -0.5 2.201 270) (size 0.3 1.45) (layers "F.Cu" "F.Paste" "F.Mask")
      (net 239 "Adapter_USB_P") (pinfunction "D1+") (pintype "bidirectional") (solder_mask_margin 0.05))
    (pad "3" smd rect (at 0 2.201 270) (size 0.3 1.45) (layers "F.Cu" "F.Paste" "F.Mask")
      (net 25 "/Interfaces/RPi_USB_P") (pinfunction "D2+") (pintype "bidirectional") (solder_mask_margin 0.05))
    (pad "4" smd rect (at 0.496 2.201 270) (size 0.3 1.45) (layers "F.Cu" "F.Paste" "F.Mask")
      (net 247 "Net-(U1-D+)") (pinfunction "D+") (pintype "bidirectional") (solder_mask_margin 0.05))
    (pad "5" smd rect (at 0.996 2.201 270) (size 0.3 1.45) (layers "F.Cu" "F.Paste" "F.Mask")
      (net 11 "GND") (pinfunction "GND") (pintype "power_in") (solder_mask_margin 0.05))
    (pad "6" smd rect (at 0.996 -2.202 270) (size 0.3 1.45) (layers "F.Cu" "F.Paste" "F.Mask")
      (net 248 "Net-(U1-D-)") (pinfunction "D-") (pintype "bidirectional") (solder_mask_margin 0.05))
    (pad "7" smd rect (at 0.496 -2.202 270) (size 0.3 1.45) (layers "F.Cu" "F.Paste" "F.Mask")
      (net 24 "/Interfaces/RPi_USB_N") (pinfunction "D2-") (pintype "bidirectional") (solder_mask_margin 0.05))
    (pad "8" smd rect (at 0 -2.202 270) (size 0.3 1.45) (layers "F.Cu" "F.Paste" "F.Mask")
      (net 240 "Adapter_USB_N") (pinfunction "D1-") (pintype "bidirectional") (solder_mask_margin 0.05))
    (pad "9" smd rect (at -0.5 -2.202 270) (size 0.3 1.45) (layers "F.Cu" "F.Paste" "F.Mask")
      (net 250 "Net-(U1-~{OE})") (pinfunction "~{OE}") (pintype "input") (solder_mask_margin 0.05))
    (pad "10" smd rect (at -1 -2.202 270) (size 0.3 1.45) (layers "F.Cu" "F.Paste" "F.Mask")
      (net 232 "3V3_RPi") (pinfunction "VCC") (pintype "power_in") (solder_mask_margin 0.05))
  )

  (footprint "scalenode-cm4-baseboard-footprints:antmicro-logo" (layer "F.Cu")
    (at 97.420173 79.269924)
    (property "Author" "Antmicro")
    (property "License" "Apache-2.0")
    (property "MPN" "")
    (property "Manufacturer" "")
    (property "Sheetfile" "scalenode-cm4-baseboard.kicad_sch")
    (property "Sheetname" "")
    (attr through_hole exclude_from_pos_files)
    (fp_text reference "N1" (at -7.701 -10.301) (layer "F.SilkS") hide
        (effects (font (size 0.7 0.7) (thickness 0.15)) (justify left bottom))
    )
    (fp_text value "antmicro_logo" (at -5.3 10.099) (layer "F.SilkS") hide
        (effects (font (size 0.7 0.7) (thickness 0.15)) (justify left bottom))
    )
    (fp_text user "Author: Antmicro" (at -7.952 13.299) (layer "F.Fab") hide
        (effects (font (size 0.7 0.7) (thickness 0.15)) (justify left bottom))
    )
    (fp_text user "${REFERENCE}" (at -7.952 12.099) (layer "F.Fab") hide
        (effects (font (size 0.7 0.7) (thickness 0.15)) (justify left bottom))
    )
    (fp_text user "License: Apache-2.0" (at -7.952 14.499) (layer "F.Fab") hide
        (effects (font (size 0.7 0.7) (thickness 0.15)) (justify left bottom))
    )
    (fp_poly
      (pts
        (xy 3.456 0.778)
        (xy 3.172 0.778)
        (xy 3.172 -0.899)
        (xy 3.456 -0.899)
        (xy 3.456 0.778)
      )

      (stroke (width 0.001395) (type solid)) (fill solid) (layer "F.Cu"))
    (fp_poly
      (pts
        (xy 5.67 -0.921)
        (xy 5.691 -0.918)
        (xy 5.699 -0.913)
        (xy 5.7 -0.911)
        (xy 5.696 -0.894)
        (xy 5.687 -0.86)
        (xy 5.675 -0.816)
        (xy 5.669 -0.797)
        (xy 5.653 -0.749)
        (xy 5.641 -0.72)
        (xy 5.63 -0.706)
        (xy 5.619 -0.704)
        (xy 5.617 -0.704)
        (xy 5.543 -0.72)
        (xy 5.461 -0.725)
        (xy 5.38 -0.72)
        (xy 5.309 -0.705)
        (xy 5.295 -0.7)
        (xy 5.263 -0.687)
        (xy 5.263 0.778)
        (xy 4.979 0.778)
        (xy 4.979 -0.814)
        (xy 5.065 -0.845)
        (xy 5.139 -0.87)
        (xy 5.207 -0.888)
        (xy 5.276 -0.902)
        (xy 5.35 -0.911)
        (xy 5.438 -0.917)
        (xy 5.502 -0.919)
        (xy 5.578 -0.922)
        (xy 5.633 -0.922)
        (xy 5.67 -0.921)
      )

      (stroke (width 0.001395) (type solid)) (fill solid) (layer "F.Cu"))
    (fp_poly
      (pts
        (xy 0.143 -1.349)
        (xy 0.145 -1.317)
        (xy 0.147 -1.27)
        (xy 0.148 -1.209)
        (xy 0.148 -1.139)
        (xy 0.148 -1.13)
        (xy 0.148 -0.899)
        (xy 0.432 -0.899)
        (xy 0.432 -0.71)
        (xy 0.148 -0.71)
        (xy 0.148 0.443)
        (xy 0.175 0.494)
        (xy 0.21 0.543)
        (xy 0.254 0.573)
        (xy 0.312 0.586)
        (xy 0.358 0.587)
        (xy 0.432 0.583)
        (xy 0.432 0.674)
        (xy 0.43 0.73)
        (xy 0.424 0.764)
        (xy 0.417 0.774)
        (xy 0.4 0.778)
        (xy 0.364 0.782)
        (xy 0.317 0.785)
        (xy 0.284 0.787)
        (xy 0.22 0.787)
        (xy 0.171 0.784)
        (xy 0.13 0.776)
        (xy 0.104 0.768)
        (xy 0.032 0.734)
        (xy -0.025 0.687)
        (xy -0.073 0.622)
        (xy -0.088 0.595)
        (xy -0.129 0.515)
        (xy -0.132 -0.098)
        (xy -0.136 -0.71)
        (xy -0.324 -0.71)
        (xy -0.324 -0.899)
        (xy -0.135 -0.899)
        (xy -0.135 -1.276)
        (xy -0.001 -1.318)
        (xy 0.052 -1.334)
        (xy 0.096 -1.348)
        (xy 0.127 -1.357)
        (xy 0.14 -1.36)
        (xy 0.143 -1.349)
      )

      (stroke (width 0.001395) (type solid)) (fill solid) (layer "F.Cu"))
    (fp_poly
      (pts
        (xy -1.069 -0.916)
        (xy -1.006 -0.915)
        (xy -0.958 -0.912)
        (xy -0.919 -0.906)
        (xy -0.886 -0.899)
        (xy -0.874 -0.895)
        (xy -0.767 -0.854)
        (xy -0.68 -0.803)
        (xy -0.613 -0.742)
        (xy -0.569 -0.678)
        (xy -0.555 -0.651)
        (xy -0.543 -0.626)
        (xy -0.533 -0.6)
        (xy -0.524 -0.572)
        (xy -0.518 -0.539)
        (xy -0.512 -0.499)
        (xy -0.508 -0.45)
        (xy -0.505 -0.39)
        (xy -0.503 -0.316)
        (xy -0.502 -0.228)
        (xy -0.501 -0.122)
        (xy -0.501 0.003)
        (xy -0.501 0.149)
        (xy -0.501 0.778)
        (xy -0.785 0.778)
        (xy -0.785 0.154)
        (xy -0.785 0.007)
        (xy -0.785 -0.118)
        (xy -0.786 -0.224)
        (xy -0.787 -0.311)
        (xy -0.789 -0.384)
        (xy -0.792 -0.442)
        (xy -0.797 -0.489)
        (xy -0.802 -0.526)
        (xy -0.809 -0.555)
        (xy -0.818 -0.578)
        (xy -0.829 -0.598)
        (xy -0.842 -0.615)
        (xy -0.857 -0.633)
        (xy -0.858 -0.634)
        (xy -0.907 -0.678)
        (xy -0.966 -0.709)
        (xy -1.042 -0.73)
        (xy -1.07 -0.734)
        (xy -1.149 -0.739)
        (xy -1.237 -0.735)
        (xy -1.322 -0.722)
        (xy -1.384 -0.706)
        (xy -1.428 -0.69)
        (xy -1.431 0.044)
        (xy -1.434 0.778)
        (xy -1.718 0.778)
        (xy -1.718 -0.814)
        (xy -1.608 -0.849)
        (xy -1.533 -0.873)
        (xy -1.469 -0.891)
        (xy -1.41 -0.903)
        (xy -1.35 -0.911)
        (xy -1.282 -0.915)
        (xy -1.2 -0.917)
        (xy -1.151 -0.917)
        (xy -1.069 -0.916)
      )

      (stroke (width 0.001395) (type solid)) (fill solid) (layer "F.Cu"))
    (fp_poly
      (pts
        (xy 2.364 -0.914)
        (xy 2.479 -0.889)
        (xy 2.578 -0.847)
        (xy 2.661 -0.79)
        (xy 2.727 -0.716)
        (xy 2.758 -0.663)
        (xy 2.771 -0.638)
        (xy 2.781 -0.613)
        (xy 2.79 -0.587)
        (xy 2.798 -0.558)
        (xy 2.803 -0.523)
        (xy 2.808 -0.481)
        (xy 2.812 -0.429)
        (xy 2.814 -0.366)
        (xy 2.816 -0.289)
        (xy 2.817 -0.196)
        (xy 2.818 -0.085)
        (xy 2.818 0.047)
        (xy 2.818 0.153)
        (xy 2.818 0.778)
        (xy 2.535 0.778)
        (xy 2.532 0.125)
        (xy 2.528 -0.527)
        (xy 2.494 -0.589)
        (xy 2.447 -0.651)
        (xy 2.386 -0.697)
        (xy 2.314 -0.727)
        (xy 2.236 -0.739)
        (xy 2.153 -0.735)
        (xy 2.071 -0.714)
        (xy 1.991 -0.676)
        (xy 1.935 -0.634)
        (xy 1.885 -0.59)
        (xy 1.885 0.778)
        (xy 1.601 0.778)
        (xy 1.601 0.139)
        (xy 1.601 -0.022)
        (xy 1.6 -0.159)
        (xy 1.599 -0.275)
        (xy 1.598 -0.369)
        (xy 1.596 -0.443)
        (xy 1.593 -0.497)
        (xy 1.59 -0.532)
        (xy 1.588 -0.546)
        (xy 1.556 -0.613)
        (xy 1.506 -0.666)
        (xy 1.439 -0.706)
        (xy 1.356 -0.73)
        (xy 1.26 -0.74)
        (xy 1.162 -0.735)
        (xy 1.108 -0.728)
        (xy 1.07 -0.722)
        (xy 1.038 -0.715)
        (xy 1.005 -0.704)
        (xy 0.984 -0.696)
        (xy 0.952 -0.684)
        (xy 0.952 0.778)
        (xy 0.68 0.778)
        (xy 0.68 -0.815)
        (xy 0.792 -0.852)
        (xy 0.919 -0.887)
        (xy 1.038 -0.91)
        (xy 1.158 -0.92)
        (xy 1.282 -0.92)
        (xy 1.382 -0.914)
        (xy 1.464 -0.903)
        (xy 1.534 -0.885)
        (xy 1.595 -0.858)
        (xy 1.654 -0.822)
        (xy 1.679 -0.804)
        (xy 1.756 -0.745)
        (xy 1.806 -0.786)
        (xy 1.901 -0.849)
        (xy 2.009 -0.892)
        (xy 2.129 -0.917)
        (xy 2.233 -0.922)
        (xy 2.364 -0.914)
      )

      (stroke (width 0.001395) (type solid)) (fill solid) (layer "F.Cu"))
    (fp_poly
      (pts
        (xy 6.505 -0.915)
        (xy 6.611 -0.891)
        (xy 6.704 -0.849)
        (xy 6.788 -0.79)
        (xy 6.828 -0.753)
        (xy 6.902 -0.662)
        (xy 6.962 -0.554)
        (xy 7.006 -0.43)
        (xy 7.035 -0.288)
        (xy 7.045 -0.196)
        (xy 7.05 -0.031)
        (xy 7.041 0.124)
        (xy 7.016 0.266)
        (xy 6.977 0.395)
        (xy 6.924 0.508)
        (xy 6.858 0.605)
        (xy 6.779 0.684)
        (xy 6.73 0.72)
        (xy 6.653 0.758)
        (xy 6.56 0.787)
        (xy 6.461 0.804)
        (xy 6.361 0.809)
        (xy 6.271 0.801)
        (xy 6.154 0.769)
        (xy 6.051 0.718)
        (xy 5.961 0.648)
        (xy 5.886 0.559)
        (xy 5.825 0.453)
        (xy 5.779 0.329)
        (xy 5.754 0.221)
        (xy 5.733 0.061)
        (xy 5.729 -0.067)
        (xy 6.011 -0.067)
        (xy 6.016 0.065)
        (xy 6.032 0.192)
        (xy 6.058 0.308)
        (xy 6.094 0.406)
        (xy 6.14 0.484)
        (xy 6.199 0.545)
        (xy 6.267 0.587)
        (xy 6.341 0.61)
        (xy 6.419 0.613)
        (xy 6.498 0.594)
        (xy 6.524 0.582)
        (xy 6.59 0.539)
        (xy 6.645 0.479)
        (xy 6.689 0.402)
        (xy 6.723 0.306)
        (xy 6.748 0.191)
        (xy 6.762 0.069)
        (xy 6.768 -0.079)
        (xy 6.762 -0.217)
        (xy 6.744 -0.343)
        (xy 6.715 -0.454)
        (xy 6.675 -0.549)
        (xy 6.625 -0.626)
        (xy 6.594 -0.659)
        (xy 6.527 -0.707)
        (xy 6.454 -0.733)
        (xy 6.378 -0.74)
        (xy 6.303 -0.727)
        (xy 6.233 -0.695)
        (xy 6.17 -0.645)
        (xy 6.117 -0.578)
        (xy 6.096 -0.54)
        (xy 6.059 -0.441)
        (xy 6.032 -0.325)
        (xy 6.016 -0.199)
        (xy 6.011 -0.067)
        (xy 5.729 -0.067)
        (xy 5.728 -0.094)
        (xy 5.738 -0.243)
        (xy 5.762 -0.382)
        (xy 5.801 -0.509)
        (xy 5.854 -0.622)
        (xy 5.92 -0.719)
        (xy 5.939 -0.741)
        (xy 6.024 -0.817)
        (xy 6.12 -0.872)
        (xy 6.228 -0.907)
        (xy 6.348 -0.922)
        (xy 6.384 -0.923)
        (xy 6.505 -0.915)
      )

      (stroke (width 0.001395) (type solid)) (fill solid) (layer "F.Cu"))
    (fp_poly
      (pts
        (xy 4.407 -0.921)
        (xy 4.484 -0.913)
        (xy 4.528 -0.905)
        (xy 4.572 -0.892)
        (xy 4.62 -0.875)
        (xy 4.665 -0.855)
        (xy 4.701 -0.837)
        (xy 4.722 -0.822)
        (xy 4.723 -0.82)
        (xy 4.722 -0.805)
        (xy 4.713 -0.776)
        (xy 4.7 -0.74)
        (xy 4.685 -0.703)
        (xy 4.671 -0.672)
        (xy 4.66 -0.655)
        (xy 4.658 -0.653)
        (xy 4.643 -0.657)
        (xy 4.614 -0.669)
        (xy 4.585 -0.682)
        (xy 4.494 -0.713)
        (xy 4.405 -0.725)
        (xy 4.32 -0.718)
        (xy 4.246 -0.692)
        (xy 4.185 -0.648)
        (xy 4.128 -0.583)
        (xy 4.078 -0.5)
        (xy 4.037 -0.402)
        (xy 4.02 -0.346)
        (xy 4.006 -0.276)
        (xy 3.997 -0.19)
        (xy 3.993 -0.096)
        (xy 3.994 0.001)
        (xy 4 0.093)
        (xy 4.011 0.173)
        (xy 4.02 0.213)
        (xy 4.06 0.33)
        (xy 4.11 0.426)
        (xy 4.171 0.502)
        (xy 4.243 0.557)
        (xy 4.249 0.56)
        (xy 4.285 0.578)
        (xy 4.316 0.589)
        (xy 4.353 0.593)
        (xy 4.404 0.594)
        (xy 4.406 0.594)
        (xy 4.46 0.592)
        (xy 4.506 0.584)
        (xy 4.554 0.568)
        (xy 4.609 0.543)
        (xy 4.65 0.521)
        (xy 4.655 0.524)
        (xy 4.664 0.54)
        (xy 4.678 0.57)
        (xy 4.698 0.617)
        (xy 4.724 0.684)
        (xy 4.727 0.69)
        (xy 4.72 0.703)
        (xy 4.696 0.721)
        (xy 4.66 0.741)
        (xy 4.616 0.761)
        (xy 4.569 0.778)
        (xy 4.557 0.782)
        (xy 4.493 0.796)
        (xy 4.417 0.804)
        (xy 4.337 0.808)
        (xy 4.265 0.805)
        (xy 4.235 0.801)
        (xy 4.191 0.79)
        (xy 4.138 0.771)
        (xy 4.087 0.749)
        (xy 3.989 0.688)
        (xy 3.905 0.608)
        (xy 3.834 0.509)
        (xy 3.777 0.393)
        (xy 3.735 0.258)
        (xy 3.721 0.193)
        (xy 3.711 0.116)
        (xy 3.705 0.024)
        (xy 3.705 -0.075)
        (xy 3.708 -0.176)
        (xy 3.716 -0.27)
        (xy 3.728 -0.353)
        (xy 3.738 -0.397)
        (xy 3.784 -0.528)
        (xy 3.845 -0.642)
        (xy 3.919 -0.738)
        (xy 4.007 -0.816)
        (xy 4.107 -0.874)
        (xy 4.187 -0.904)
        (xy 4.249 -0.916)
        (xy 4.325 -0.922)
        (xy 4.407 -0.921)
      )

      (stroke (width 0.001395) (type solid)) (fill solid) (layer "F.Cu"))
    (fp_poly
      (pts
        (xy -2.526 -0.915)
        (xy -2.451 -0.901)
        (xy -2.366 -0.875)
        (xy -2.297 -0.843)
        (xy -2.238 -0.8)
        (xy -2.209 -0.773)
        (xy -2.166 -0.72)
        (xy -2.128 -0.651)
        (xy -2.098 -0.576)
        (xy -2.084 -0.523)
        (xy -2.081 -0.496)
        (xy -2.079 -0.448)
        (xy -2.077 -0.38)
        (xy -2.075 -0.294)
        (xy -2.074 -0.193)
        (xy -2.073 -0.078)
        (xy -2.072 0.049)
        (xy -2.072 0.118)
        (xy -2.072 0.694)
        (xy -2.127 0.719)
        (xy -2.226 0.754)
        (xy -2.341 0.782)
        (xy -2.465 0.8)
        (xy -2.591 0.809)
        (xy -2.712 0.807)
        (xy -2.776 0.801)
        (xy -2.901 0.776)
        (xy -3.008 0.736)
        (xy -3.097 0.682)
        (xy -3.167 0.614)
        (xy -3.218 0.531)
        (xy -3.25 0.435)
        (xy -3.263 0.325)
        (xy -3.263 0.27)
        (xy -3.261 0.26)
        (xy -2.991 0.26)
        (xy -2.988 0.358)
        (xy -2.967 0.442)
        (xy -2.927 0.513)
        (xy -2.869 0.568)
        (xy -2.794 0.609)
        (xy -2.758 0.621)
        (xy -2.711 0.629)
        (xy -2.649 0.632)
        (xy -2.579 0.632)
        (xy -2.509 0.628)
        (xy -2.445 0.62)
        (xy -2.395 0.609)
        (xy -2.388 0.607)
        (xy -2.332 0.587)
        (xy -2.332 -0.157)
        (xy -2.4 -0.149)
        (xy -2.443 -0.142)
        (xy -2.499 -0.131)
        (xy -2.558 -0.118)
        (xy -2.577 -0.113)
        (xy -2.698 -0.076)
        (xy -2.797 -0.03)
        (xy -2.875 0.025)
        (xy -2.933 0.089)
        (xy -2.971 0.163)
        (xy -2.99 0.248)
        (xy -2.991 0.26)
        (xy -3.261 0.26)
        (xy -3.247 0.164)
        (xy -3.212 0.069)
        (xy -3.155 -0.015)
        (xy -3.123 -0.049)
        (xy -3.052 -0.105)
        (xy -2.961 -0.157)
        (xy -2.852 -0.204)
        (xy -2.729 -0.243)
        (xy -2.595 -0.275)
        (xy -2.453 -0.298)
        (xy -2.451 -0.298)
        (xy -2.329 -0.313)
        (xy -2.336 -0.413)
        (xy -2.349 -0.508)
        (xy -2.377 -0.584)
        (xy -2.418 -0.642)
        (xy -2.476 -0.685)
        (xy -2.551 -0.714)
        (xy -2.587 -0.722)
        (xy -2.685 -0.731)
        (xy -2.793 -0.723)
        (xy -2.908 -0.699)
        (xy -3.023 -0.66)
        (xy -3.033 -0.655)
        (xy -3.069 -0.641)
        (xy -3.096 -0.632)
        (xy -3.106 -0.631)
        (xy -3.112 -0.643)
        (xy -3.124 -0.671)
        (xy -3.138 -0.707)
        (xy -3.152 -0.745)
        (xy -3.163 -0.777)
        (xy -3.17 -0.797)
        (xy -3.17 -0.8)
        (xy -3.161 -0.807)
        (xy -3.135 -0.821)
        (xy -3.106 -0.835)
        (xy -3 -0.873)
        (xy -2.882 -0.901)
        (xy -2.76 -0.917)
        (xy -2.639 -0.922)
        (xy -2.526 -0.915)
      )

      (stroke (width 0.001395) (type solid)) (fill solid) (layer "F.Cu"))
    (fp_poly
      (pts
        (xy -5.818 -2.455)
        (xy -5.769 -2.444)
        (xy -5.768 -2.444)
        (xy -5.753 -2.436)
        (xy -5.719 -2.417)
        (xy -5.668 -2.388)
        (xy -5.602 -2.351)
        (xy -5.523 -2.306)
        (xy -5.433 -2.254)
        (xy -5.332 -2.197)
        (xy -5.224 -2.135)
        (xy -5.11 -2.07)
        (xy -4.992 -2.002)
        (xy -4.872 -1.933)
        (xy -4.75 -1.863)
        (xy -4.63 -1.794)
        (xy -4.514 -1.727)
        (xy -4.401 -1.662)
        (xy -4.296 -1.601)
        (xy -4.199 -1.545)
        (xy -4.112 -1.494)
        (xy -4.037 -1.45)
        (xy -3.976 -1.415)
        (xy -3.931 -1.388)
        (xy -3.903 -1.371)
        (xy -3.899 -1.369)
        (xy -3.849 -1.328)
        (xy -3.811 -1.279)
        (xy -3.779 -1.224)
        (xy -3.775 -0.098)
        (xy -3.775 0.117)
        (xy -3.775 0.312)
        (xy -3.775 0.485)
        (xy -3.775 0.636)
        (xy -3.776 0.765)
        (xy -3.777 0.873)
        (xy -3.779 0.957)
        (xy -3.781 1.019)
        (xy -3.783 1.058)
        (xy -3.784 1.072)
        (xy -3.789 1.09)
        (xy -3.794 1.106)
        (xy -3.801 1.122)
        (xy -3.81 1.137)
        (xy -3.824 1.154)
        (xy -3.843 1.172)
        (xy -3.868 1.192)
        (xy -3.9 1.216)
        (xy -3.942 1.245)
        (xy -3.994 1.278)
        (xy -4.057 1.317)
        (xy -4.133 1.362)
        (xy -4.223 1.415)
        (xy -4.327 1.476)
        (xy -4.448 1.546)
        (xy -4.586 1.626)
        (xy -4.743 1.717)
        (xy -4.813 1.758)
        (xy -5.763 2.306)
        (xy -5.852 2.311)
        (xy -5.94 2.315)
        (xy -6.289 2.115)
        (xy -6.502 1.992)
        (xy -6.696 1.881)
        (xy -6.871 1.78)
        (xy -7.029 1.689)
        (xy -7.17 1.608)
        (xy -7.295 1.535)
        (xy -7.406 1.471)
        (xy -7.502 1.414)
        (xy -7.586 1.364)
        (xy -7.658 1.321)
        (xy -7.719 1.284)
        (xy -7.77 1.251)
        (xy -7.812 1.224)
        (xy -7.846 1.2)
        (xy -7.873 1.18)
        (xy -7.893 1.163)
        (xy -7.909 1.148)
        (xy -7.92 1.134)
        (xy -7.927 1.122)
        (xy -7.932 1.11)
        (xy -7.936 1.098)
        (xy -7.939 1.085)
        (xy -7.942 1.072)
        (xy -7.945 1.051)
        (xy -7.947 1.007)
        (xy -7.948 0.94)
        (xy -7.95 0.85)
        (xy -7.951 0.738)
        (xy -7.951 0.604)
        (xy -7.952 0.447)
        (xy -7.952 0.269)
        (xy -7.952 0.07)
        (xy -7.951 -0.072)
        (xy -7.222 -0.072)
        (xy -7.222 0.081)
        (xy -7.221 0.213)
        (xy -7.221 0.324)
        (xy -7.22 0.418)
        (xy -7.219 0.495)
        (xy -7.217 0.557)
        (xy -7.214 0.607)
        (xy -7.211 0.646)
        (xy -7.206 0.675)
        (xy -7.2 0.698)
        (xy -7.193 0.714)
        (xy -7.184 0.727)
        (xy -7.174 0.738)
        (xy -7.162 0.748)
        (xy -7.161 0.749)
        (xy -7.145 0.76)
        (xy -7.111 0.781)
        (xy -7.061 0.811)
        (xy -6.997 0.849)
        (xy -6.922 0.893)
        (xy -6.837 0.943)
        (xy -6.745 0.996)
        (xy -6.649 1.052)
        (xy -6.549 1.109)
        (xy -6.45 1.167)
        (xy -6.352 1.223)
        (xy -6.258 1.277)
        (xy -6.17 1.326)
        (xy -6.091 1.371)
        (xy -6.022 1.41)
        (xy -5.967 1.44)
        (xy -5.926 1.462)
        (xy -5.903 1.474)
        (xy -5.9 1.475)
        (xy -5.87 1.483)
        (xy -5.85 1.484)
        (xy -5.826 1.476)
        (xy -5.811 1.47)
        (xy -5.792 1.46)
        (xy -5.754 1.44)
        (xy -5.701 1.41)
        (xy -5.635 1.373)
        (xy -5.558 1.329)
        (xy -5.472 1.28)
        (xy -5.379 1.227)
        (xy -5.282 1.171)
        (xy -5.183 1.114)
        (xy -5.084 1.057)
        (xy -4.987 1)
        (xy -4.895 0.947)
        (xy -4.81 0.897)
        (xy -4.734 0.852)
        (xy -4.67 0.814)
        (xy -4.619 0.783)
        (xy -4.583 0.762)
        (xy -4.566 0.75)
        (xy -4.553 0.739)
        (xy -4.543 0.728)
        (xy -4.534 0.715)
        (xy -4.527 0.699)
        (xy -4.521 0.677)
        (xy -4.516 0.648)
        (xy -4.513 0.61)
        (xy -4.51 0.562)
        (xy -4.508 0.5)
        (xy -4.506 0.424)
        (xy -4.506 0.332)
        (xy -4.505 0.222)
        (xy -4.505 0.092)
        (xy -4.505 -0.059)
        (xy -4.505 -0.072)
        (xy -4.505 -0.227)
        (xy -4.505 -0.359)
        (xy -4.506 -0.471)
        (xy -4.506 -0.565)
        (xy -4.508 -0.643)
        (xy -4.51 -0.706)
        (xy -4.513 -0.756)
        (xy -4.517 -0.795)
        (xy -4.522 -0.825)
        (xy -4.529 -0.847)
        (xy -4.537 -0.864)
        (xy -4.547 -0.877)
        (xy -4.558 -0.887)
        (xy -4.572 -0.898)
        (xy -4.578 -0.902)
        (xy -4.595 -0.913)
        (xy -4.631 -0.935)
        (xy -4.683 -0.966)
        (xy -4.75 -1.005)
        (xy -4.83 -1.052)
        (xy -4.92 -1.105)
        (xy -5.02 -1.162)
        (xy -5.126 -1.224)
        (xy -5.215 -1.275)
        (xy -5.342 -1.349)
        (xy -5.451 -1.411)
        (xy -5.543 -1.463)
        (xy -5.619 -1.506)
        (xy -5.682 -1.541)
        (xy -5.732 -1.568)
        (xy -5.772 -1.588)
        (xy -5.802 -1.602)
        (xy -5.826 -1.612)
        (xy -5.843 -1.617)
        (xy -5.857 -1.62)
        (xy -5.862 -1.62)
        (xy -5.874 -1.619)
        (xy -5.89 -1.615)
        (xy -5.911 -1.607)
        (xy -5.938 -1.595)
        (xy -5.973 -1.578)
        (xy -6.018 -1.554)
        (xy -6.074 -1.523)
        (xy -6.144 -1.484)
        (xy -6.228 -1.437)
        (xy -6.328 -1.379)
        (xy -6.446 -1.312)
        (xy -6.528 -1.264)
        (xy -6.639 -1.2)
        (xy -6.745 -1.139)
        (xy -6.842 -1.082)
        (xy -6.931 -1.03)
        (xy -7.008 -0.985)
        (xy -7.072 -0.947)
        (xy -7.121 -0.918)
        (xy -7.154 -0.898)
        (xy -7.167 -0.889)
        (xy -7.178 -0.879)
        (xy -7.187 -0.869)
        (xy -7.195 -0.856)
        (xy -7.202 -0.839)
        (xy -7.207 -0.817)
        (xy -7.211 -0.786)
        (xy -7.215 -0.746)
        (xy -7.217 -0.694)
        (xy -7.219 -0.63)
        (xy -7.22 -0.551)
        (xy -7.221 -0.454)
        (xy -7.221 -0.34)
        (xy -7.222 -0.205)
        (xy -7.222 -0.072)
        (xy -7.951 -0.072)
        (xy -7.951 -0.098)
        (xy -7.951 -0.29)
        (xy -7.95 -0.459)
        (xy -7.95 -0.607)
        (xy -7.949 -0.736)
        (xy -7.948 -0.848)
        (xy -7.947 -0.943)
        (xy -7.946 -1.023)
        (xy -7.944 -1.089)
        (xy -7.941 -1.143)
        (xy -7.938 -1.187)
        (xy -7.934 -1.221)
        (xy -7.93 -1.248)
        (xy -7.924 -1.268)
        (xy -7.917 -1.284)
        (xy -7.909 -1.296)
        (xy -7.9 -1.306)
        (xy -7.89 -1.315)
        (xy -7.878 -1.326)
        (xy -7.873 -1.33)
        (xy -7.858 -1.341)
        (xy -7.824 -1.362)
        (xy -7.773 -1.393)
        (xy -7.705 -1.434)
        (xy -7.623 -1.483)
        (xy -7.528 -1.539)
        (xy -7.422 -1.601)
        (xy -7.305 -1.669)
        (xy -7.18 -1.742)
        (xy -7.048 -1.819)
        (xy -6.911 -1.898)
        (xy -6.896 -1.907)
        (xy -6.736 -1.999)
        (xy -6.595 -2.081)
        (xy -6.472 -2.152)
        (xy -6.365 -2.213)
        (xy -6.273 -2.266)
        (xy -6.195 -2.31)
        (xy -6.13 -2.346)
        (xy -6.076 -2.376)
        (xy -6.031 -2.4)
        (xy -5.995 -2.418)
        (xy -5.967 -2.432)
        (xy -5.944 -2.442)
        (xy -5.926 -2.448)
        (xy -5.911 -2.452)
        (xy -5.898 -2.455)
        (xy -5.885 -2.456)
        (xy -5.881 -2.456)
        (xy -5.818 -2.455)
      )

      (stroke (width 0.001395) (type solid)) (fill solid) (layer "F.Cu"))
    (fp_poly
      (pts
        (xy -5.8 -1.041)
        (xy -5.789 -1.037)
        (xy -5.735 -1.001)
        (xy -5.695 -0.951)
        (xy -5.673 -0.891)
        (xy -5.671 -0.827)
        (xy -5.674 -0.812)
        (xy -5.697 -0.751)
        (xy -5.738 -0.706)
        (xy -5.779 -0.681)
        (xy -5.828 -0.657)
        (xy -5.828 -0.38)
        (xy -5.622 -0.38)
        (xy -5.537 -0.464)
        (xy -5.452 -0.548)
        (xy -5.458 -0.609)
        (xy -5.458 -0.61)
        (xy -5.378 -0.61)
        (xy -5.365 -0.583)
        (xy -5.337 -0.57)
        (xy -5.304 -0.573)
        (xy -5.28 -0.587)
        (xy -5.263 -0.615)
        (xy -5.269 -0.643)
        (xy -5.285 -0.663)
        (xy -5.307 -0.682)
        (xy -5.326 -0.684)
        (xy -5.351 -0.67)
        (xy -5.353 -0.668)
        (xy -5.374 -0.642)
        (xy -5.378 -0.61)
        (xy -5.458 -0.61)
        (xy -5.46 -0.648)
        (xy -5.455 -0.674)
        (xy -5.44 -0.699)
        (xy -5.433 -0.707)
        (xy -5.39 -0.744)
        (xy -5.343 -0.76)
        (xy -5.295 -0.759)
        (xy -5.251 -0.743)
        (xy -5.215 -0.714)
        (xy -5.191 -0.673)
        (xy -5.182 -0.624)
        (xy -5.19 -0.575)
        (xy -5.217 -0.528)
        (xy -5.259 -0.498)
        (xy -5.316 -0.486)
        (xy -5.326 -0.486)
        (xy -5.351 -0.485)
        (xy -5.371 -0.481)
        (xy -5.392 -0.47)
        (xy -5.418 -0.45)
        (xy -5.453 -0.418)
        (xy -5.482 -0.391)
        (xy -5.583 -0.297)
        (xy -5.828 -0.297)
        (xy -5.828 -0.108)
        (xy -5.38 -0.108)
        (xy -5.362 -0.142)
        (xy -5.33 -0.18)
        (xy -5.286 -0.203)
        (xy -5.236 -0.21)
        (xy -5.187 -0.2)
        (xy -5.145 -0.172)
        (xy -5.141 -0.168)
        (xy -5.11 -0.12)
        (xy -5.1 -0.071)
        (xy -5.107 -0.025)
        (xy -5.129 0.016)
        (xy -5.163 0.047)
        (xy -5.206 0.065)
        (xy -5.255 0.068)
        (xy -5.308 0.051)
        (xy -5.318 0.045)
        (xy -5.346 0.024)
        (xy -5.363 0.002)
        (xy -5.364 -0.002)
        (xy -5.367 -0.01)
        (xy -5.374 -0.016)
        (xy -5.389 -0.02)
        (xy -5.413 -0.023)
        (xy -5.451 -0.024)
        (xy -5.506 -0.025)
        (xy -5.58 -0.025)
        (xy -5.599 -0.025)
        (xy -5.828 -0.025)
        (xy -5.828 0.152)
        (xy -5.585 0.152)
        (xy -5.389 0.349)
        (xy -5.334 0.344)
        (xy -5.275 0.348)
        (xy -5.229 0.371)
        (xy -5.197 0.412)
        (xy -5.189 0.434)
        (xy -5.181 0.49)
        (xy -5.195 0.539)
        (xy -5.224 0.578)
        (xy -5.27 0.61)
        (xy -5.319 0.621)
        (xy -5.366 0.615)
        (xy -5.408 0.592)
        (xy -5.439 0.555)
        (xy -5.457 0.507)
        (xy -5.458 0.471)
        (xy -5.377 0.471)
        (xy -5.373 0.501)
        (xy -5.362 0.518)
        (xy -5.335 0.538)
        (xy -5.309 0.537)
        (xy -5.285 0.518)
        (xy -5.264 0.489)
        (xy -5.266 0.463)
        (xy -5.284 0.442)
        (xy -5.313 0.427)
        (xy -5.342 0.43)
        (xy -5.365 0.446)
        (xy -5.377 0.471)
        (xy -5.458 0.471)
        (xy -5.458 0.46)
        (xy -5.451 0.404)
        (xy -5.622 0.235)
        (xy -5.828 0.235)
        (xy -5.828 0.514)
        (xy -5.779 0.536)
        (xy -5.728 0.571)
        (xy -5.693 0.618)
        (xy -5.674 0.674)
        (xy -5.67 0.732)
        (xy -5.684 0.789)
        (xy -5.713 0.839)
        (xy -5.759 0.879)
        (xy -5.77 0.885)
        (xy -5.831 0.904)
        (xy -5.897 0.904)
        (xy -5.958 0.885)
        (xy -5.96 0.884)
        (xy -6.008 0.846)
        (xy -6.04 0.797)
        (xy -6.055 0.741)
        (xy -6.055 0.713)
        (xy -5.974 0.713)
        (xy -5.97 0.748)
        (xy -5.952 0.776)
        (xy -5.936 0.791)
        (xy -5.893 0.819)
        (xy -5.85 0.823)
        (xy -5.806 0.804)
        (xy -5.79 0.791)
        (xy -5.764 0.762)
        (xy -5.753 0.732)
        (xy -5.752 0.713)
        (xy -5.763 0.67)
        (xy -5.791 0.633)
        (xy -5.829 0.608)
        (xy -5.863 0.601)
        (xy -5.906 0.611)
        (xy -5.943 0.639)
        (xy -5.967 0.678)
        (xy -5.974 0.713)
        (xy -6.055 0.713)
        (xy -6.054 0.682)
        (xy -6.037 0.626)
        (xy -6.004 0.577)
        (xy -5.956 0.54)
        (xy -5.947 0.536)
        (xy -5.899 0.514)
        (xy -5.899 0.235)
        (xy -6.105 0.235)
        (xy -6.275 0.404)
        (xy -6.269 0.46)
        (xy -6.271 0.516)
        (xy -6.292 0.563)
        (xy -6.326 0.597)
        (xy -6.369 0.617)
        (xy -6.417 0.621)
        (xy -6.465 0.606)
        (xy -6.502 0.578)
        (xy -6.535 0.533)
        (xy -6.546 0.483)
        (xy -6.543 0.468)
        (xy -6.463 0.468)
        (xy -6.46 0.494)
        (xy -6.442 0.518)
        (xy -6.413 0.539)
        (xy -6.388 0.537)
        (xy -6.366 0.519)
        (xy -6.351 0.488)
        (xy -6.355 0.457)
        (xy -6.375 0.434)
        (xy -6.39 0.428)
        (xy -6.424 0.43)
        (xy -6.443 0.442)
        (xy -6.463 0.468)
        (xy -6.543 0.468)
        (xy -6.537 0.434)
        (xy -6.512 0.386)
        (xy -6.472 0.356)
        (xy -6.418 0.344)
        (xy -6.393 0.344)
        (xy -6.338 0.349)
        (xy -6.141 0.152)
        (xy -5.899 0.152)
        (xy -5.899 -0.025)
        (xy -6.128 -0.025)
        (xy -6.207 -0.025)
        (xy -6.266 -0.025)
        (xy -6.307 -0.023)
        (xy -6.335 -0.021)
        (xy -6.351 -0.017)
        (xy -6.36 -0.012)
        (xy -6.364 -0.004)
        (xy -6.366 -0.001)
        (xy -6.385 0.026)
        (xy -6.419 0.05)
        (xy -6.46 0.066)
        (xy -6.487 0.069)
        (xy -6.541 0.059)
        (xy -6.584 0.033)
        (xy -6.613 -0.007)
        (xy -6.626 -0.054)
        (xy -6.625 -0.07)
        (xy -6.547 -0.07)
        (xy -6.543 -0.053)
        (xy -6.531 -0.038)
        (xy -6.5 -0.017)
        (xy -6.469 -0.018)
        (xy -6.449 -0.032)
        (xy -6.432 -0.062)
        (xy -6.435 -0.082)
        (xy -5.295 -0.082)
        (xy -5.29 -0.049)
        (xy -5.278 -0.032)
        (xy -5.248 -0.015)
        (xy -5.216 -0.021)
        (xy -5.195 -0.038)
        (xy -5.181 -0.057)
        (xy -5.182 -0.075)
        (xy -5.191 -0.094)
        (xy -5.216 -0.121)
        (xy -5.246 -0.129)
        (xy -5.275 -0.116)
        (xy -5.277 -0.114)
        (xy -5.295 -0.082)
        (xy -6.435 -0.082)
        (xy -6.438 -0.094)
        (xy -6.453 -0.113)
        (xy -6.483 -0.129)
        (xy -6.512 -0.122)
        (xy -6.536 -0.094)
        (xy -6.547 -0.07)
        (xy -6.625 -0.07)
        (xy -6.622 -0.104)
        (xy -6.598 -0.153)
        (xy -6.586 -0.168)
        (xy -6.544 -0.199)
        (xy -6.495 -0.211)
        (xy -6.444 -0.204)
        (xy -6.399 -0.18)
        (xy -6.367 -0.143)
        (xy -6.346 -0.108)
        (xy -5.899 -0.108)
        (xy -5.899 -0.297)
        (xy -6.143 -0.297)
        (xy -6.244 -0.391)
        (xy -6.288 -0.432)
        (xy -6.319 -0.459)
        (xy -6.342 -0.475)
        (xy -6.363 -0.483)
        (xy -6.384 -0.486)
        (xy -6.404 -0.486)
        (xy -6.462 -0.494)
        (xy -6.504 -0.52)
        (xy -6.532 -0.565)
        (xy -6.538 -0.58)
        (xy -6.543 -0.623)
        (xy -6.466 -0.623)
        (xy -6.456 -0.596)
        (xy -6.431 -0.577)
        (xy -6.399 -0.569)
        (xy -6.37 -0.576)
        (xy -6.362 -0.583)
        (xy -6.348 -0.611)
        (xy -6.353 -0.642)
        (xy -6.374 -0.668)
        (xy -6.396 -0.682)
        (xy -6.409 -0.687)
        (xy -6.426 -0.678)
        (xy -6.447 -0.657)
        (xy -6.462 -0.634)
        (xy -6.466 -0.623)
        (xy -6.543 -0.623)
        (xy -6.544 -0.635)
        (xy -6.532 -0.683)
        (xy -6.505 -0.722)
        (xy -6.467 -0.748)
        (xy -6.422 -0.761)
        (xy -6.374 -0.759)
        (xy -6.327 -0.738)
        (xy -6.294 -0.707)
        (xy -6.275 -0.681)
        (xy -6.267 -0.657)
        (xy -6.267 -0.623)
        (xy -6.268 -0.609)
        (xy -6.275 -0.548)
        (xy -6.19 -0.464)
        (xy -6.105 -0.38)
        (xy -5.899 -0.38)
        (xy -5.899 -0.658)
        (xy -5.946 -0.679)
        (xy -6.001 -0.715)
        (xy -6.038 -0.766)
        (xy -6.052 -0.805)
        (xy -6.058 -0.86)
        (xy -5.977 -0.86)
        (xy -5.973 -0.833)
        (xy -5.964 -0.813)
        (xy -5.934 -0.772)
        (xy -5.894 -0.75)
        (xy -5.849 -0.748)
        (xy -5.804 -0.767)
        (xy -5.799 -0.771)
        (xy -5.764 -0.808)
        (xy -5.752 -0.849)
        (xy -5.762 -0.892)
        (xy -5.79 -0.937)
        (xy -5.828 -0.962)
        (xy -5.87 -0.968)
        (xy -5.912 -0.956)
        (xy -5.948 -0.925)
        (xy -5.969 -0.889)
        (xy -5.977 -0.86)
        (xy -6.058 -0.86)
        (xy -6.059 -0.868)
        (xy -6.045 -0.927)
        (xy -6.015 -0.977)
        (xy -5.972 -1.017)
        (xy -5.92 -1.043)
        (xy -5.861 -1.052)
        (xy -5.8 -1.041)
      )

      (stroke (width 0.001395) (type solid)) (fill solid) (layer "F.Cu"))
    (fp_poly
      (pts
        (xy 3.456 0.778)
        (xy 3.172 0.778)
        (xy 3.172 -0.899)
        (xy 3.456 -0.899)
        (xy 3.456 0.778)
      )

      (stroke (width 0.001395) (type solid)) (fill solid) (layer "F.Mask"))
    (fp_poly
      (pts
        (xy 5.67 -0.921)
        (xy 5.691 -0.918)
        (xy 5.699 -0.913)
        (xy 5.7 -0.911)
        (xy 5.696 -0.894)
        (xy 5.687 -0.86)
        (xy 5.675 -0.816)
        (xy 5.669 -0.797)
        (xy 5.653 -0.749)
        (xy 5.641 -0.72)
        (xy 5.63 -0.706)
        (xy 5.619 -0.704)
        (xy 5.617 -0.704)
        (xy 5.543 -0.72)
        (xy 5.461 -0.725)
        (xy 5.38 -0.72)
        (xy 5.309 -0.705)
        (xy 5.295 -0.7)
        (xy 5.263 -0.687)
        (xy 5.263 0.778)
        (xy 4.979 0.778)
        (xy 4.979 -0.814)
        (xy 5.065 -0.845)
        (xy 5.139 -0.87)
        (xy 5.207 -0.888)
        (xy 5.276 -0.902)
        (xy 5.35 -0.911)
        (xy 5.438 -0.917)
        (xy 5.502 -0.919)
        (xy 5.578 -0.922)
        (xy 5.633 -0.922)
        (xy 5.67 -0.921)
      )

      (stroke (width 0.001395) (type solid)) (fill solid) (layer "F.Mask"))
    (fp_poly
      (pts
        (xy 0.143 -1.349)
        (xy 0.145 -1.317)
        (xy 0.147 -1.27)
        (xy 0.148 -1.209)
        (xy 0.148 -1.139)
        (xy 0.148 -1.13)
        (xy 0.148 -0.899)
        (xy 0.432 -0.899)
        (xy 0.432 -0.71)
        (xy 0.148 -0.71)
        (xy 0.148 0.443)
        (xy 0.175 0.494)
        (xy 0.21 0.543)
        (xy 0.254 0.573)
        (xy 0.312 0.586)
        (xy 0.358 0.587)
        (xy 0.432 0.583)
        (xy 0.432 0.674)
        (xy 0.43 0.73)
        (xy 0.424 0.764)
        (xy 0.417 0.774)
        (xy 0.4 0.778)
        (xy 0.364 0.782)
        (xy 0.317 0.785)
        (xy 0.284 0.787)
        (xy 0.22 0.787)
        (xy 0.171 0.784)
        (xy 0.13 0.776)
        (xy 0.104 0.768)
        (xy 0.032 0.734)
        (xy -0.025 0.687)
        (xy -0.073 0.622)
        (xy -0.088 0.595)
        (xy -0.129 0.515)
        (xy -0.132 -0.098)
        (xy -0.136 -0.71)
        (xy -0.324 -0.71)
        (xy -0.324 -0.899)
        (xy -0.135 -0.899)
        (xy -0.135 -1.276)
        (xy -0.001 -1.318)
        (xy 0.052 -1.334)
        (xy 0.096 -1.348)
        (xy 0.127 -1.357)
        (xy 0.14 -1.36)
        (xy 0.143 -1.349)
      )

      (stroke (width 0.001395) (type solid)) (fill solid) (layer "F.Mask"))
    (fp_poly
      (pts
        (xy -1.069 -0.916)
        (xy -1.006 -0.915)
        (xy -0.958 -0.912)
        (xy -0.919 -0.906)
        (xy -0.886 -0.899)
        (xy -0.874 -0.895)
        (xy -0.767 -0.854)
        (xy -0.68 -0.803)
        (xy -0.613 -0.742)
        (xy -0.569 -0.678)
        (xy -0.555 -0.651)
        (xy -0.543 -0.626)
        (xy -0.533 -0.6)
        (xy -0.524 -0.572)
        (xy -0.518 -0.539)
        (xy -0.512 -0.499)
        (xy -0.508 -0.45)
        (xy -0.505 -0.39)
        (xy -0.503 -0.316)
        (xy -0.502 -0.228)
        (xy -0.501 -0.122)
        (xy -0.501 0.003)
        (xy -0.501 0.149)
        (xy -0.501 0.778)
        (xy -0.785 0.778)
        (xy -0.785 0.154)
        (xy -0.785 0.007)
        (xy -0.785 -0.118)
        (xy -0.786 -0.224)
        (xy -0.787 -0.311)
        (xy -0.789 -0.384)
        (xy -0.792 -0.442)
        (xy -0.797 -0.489)
        (xy -0.802 -0.526)
        (xy -0.809 -0.555)
        (xy -0.818 -0.578)
        (xy -0.829 -0.598)
        (xy -0.842 -0.615)
        (xy -0.857 -0.633)
        (xy -0.858 -0.634)
        (xy -0.907 -0.678)
        (xy -0.966 -0.709)
        (xy -1.042 -0.73)
        (xy -1.07 -0.734)
        (xy -1.149 -0.739)
        (xy -1.237 -0.735)
        (xy -1.322 -0.722)
        (xy -1.384 -0.706)
        (xy -1.428 -0.69)
        (xy -1.431 0.044)
        (xy -1.434 0.778)
        (xy -1.718 0.778)
        (xy -1.718 -0.814)
        (xy -1.608 -0.849)
        (xy -1.533 -0.873)
        (xy -1.469 -0.891)
        (xy -1.41 -0.903)
        (xy -1.35 -0.911)
        (xy -1.282 -0.915)
        (xy -1.2 -0.917)
        (xy -1.151 -0.917)
        (xy -1.069 -0.916)
      )

      (stroke (width 0.001395) (type solid)) (fill solid) (layer "F.Mask"))
    (fp_poly
      (pts
        (xy 2.364 -0.914)
        (xy 2.479 -0.889)
        (xy 2.578 -0.847)
        (xy 2.661 -0.79)
        (xy 2.727 -0.716)
        (xy 2.758 -0.663)
        (xy 2.771 -0.638)
        (xy 2.781 -0.613)
        (xy 2.79 -0.587)
        (xy 2.798 -0.558)
        (xy 2.803 -0.523)
        (xy 2.808 -0.481)
        (xy 2.812 -0.429)
        (xy 2.814 -0.366)
        (xy 2.816 -0.289)
        (xy 2.817 -0.196)
        (xy 2.818 -0.085)
        (xy 2.818 0.047)
        (xy 2.818 0.153)
        (xy 2.818 0.778)
        (xy 2.535 0.778)
        (xy 2.532 0.125)
        (xy 2.528 -0.527)
        (xy 2.494 -0.589)
        (xy 2.447 -0.651)
        (xy 2.386 -0.697)
        (xy 2.314 -0.727)
        (xy 2.236 -0.739)
        (xy 2.153 -0.735)
        (xy 2.071 -0.714)
        (xy 1.991 -0.676)
        (xy 1.935 -0.634)
        (xy 1.885 -0.59)
        (xy 1.885 0.778)
        (xy 1.601 0.778)
        (xy 1.601 0.139)
        (xy 1.601 -0.022)
        (xy 1.6 -0.159)
        (xy 1.599 -0.275)
        (xy 1.598 -0.369)
        (xy 1.596 -0.443)
        (xy 1.593 -0.497)
        (xy 1.59 -0.532)
        (xy 1.588 -0.546)
        (xy 1.556 -0.613)
        (xy 1.506 -0.666)
        (xy 1.439 -0.706)
        (xy 1.356 -0.73)
        (xy 1.26 -0.74)
        (xy 1.162 -0.735)
        (xy 1.108 -0.728)
        (xy 1.07 -0.722)
        (xy 1.038 -0.715)
        (xy 1.005 -0.704)
        (xy 0.984 -0.696)
        (xy 0.952 -0.684)
        (xy 0.952 0.778)
        (xy 0.68 0.778)
        (xy 0.68 -0.815)
        (xy 0.792 -0.852)
        (xy 0.919 -0.887)
        (xy 1.038 -0.91)
        (xy 1.158 -0.92)
        (xy 1.282 -0.92)
        (xy 1.382 -0.914)
        (xy 1.464 -0.903)
        (xy 1.534 -0.885)
        (xy 1.595 -0.858)
        (xy 1.654 -0.822)
        (xy 1.679 -0.804)
        (xy 1.756 -0.745)
        (xy 1.806 -0.786)
        (xy 1.901 -0.849)
        (xy 2.009 -0.892)
        (xy 2.129 -0.917)
        (xy 2.233 -0.922)
        (xy 2.364 -0.914)
      )

      (stroke (width 0.001395) (type solid)) (fill solid) (layer "F.Mask"))
    (fp_poly
      (pts
        (xy 6.505 -0.915)
        (xy 6.611 -0.891)
        (xy 6.704 -0.849)
        (xy 6.788 -0.79)
        (xy 6.828 -0.753)
        (xy 6.902 -0.662)
        (xy 6.962 -0.554)
        (xy 7.006 -0.43)
        (xy 7.035 -0.288)
        (xy 7.045 -0.196)
        (xy 7.05 -0.031)
        (xy 7.041 0.124)
        (xy 7.016 0.266)
        (xy 6.977 0.395)
        (xy 6.924 0.508)
        (xy 6.858 0.605)
        (xy 6.779 0.684)
        (xy 6.73 0.72)
        (xy 6.653 0.758)
        (xy 6.56 0.787)
        (xy 6.461 0.804)
        (xy 6.361 0.809)
        (xy 6.271 0.801)
        (xy 6.154 0.769)
        (xy 6.051 0.718)
        (xy 5.961 0.648)
        (xy 5.886 0.559)
        (xy 5.825 0.453)
        (xy 5.779 0.329)
        (xy 5.754 0.221)
        (xy 5.733 0.061)
        (xy 5.729 -0.067)
        (xy 6.011 -0.067)
        (xy 6.016 0.065)
        (xy 6.032 0.192)
        (xy 6.058 0.308)
        (xy 6.094 0.406)
        (xy 6.14 0.484)
        (xy 6.199 0.545)
        (xy 6.267 0.587)
        (xy 6.341 0.61)
        (xy 6.419 0.613)
        (xy 6.498 0.594)
        (xy 6.524 0.582)
        (xy 6.59 0.539)
        (xy 6.645 0.479)
        (xy 6.689 0.402)
        (xy 6.723 0.306)
        (xy 6.748 0.191)
        (xy 6.762 0.069)
        (xy 6.768 -0.079)
        (xy 6.762 -0.217)
        (xy 6.744 -0.343)
        (xy 6.715 -0.454)
        (xy 6.675 -0.549)
        (xy 6.625 -0.626)
        (xy 6.594 -0.659)
        (xy 6.527 -0.707)
        (xy 6.454 -0.733)
        (xy 6.378 -0.74)
        (xy 6.303 -0.727)
        (xy 6.233 -0.695)
        (xy 6.17 -0.645)
        (xy 6.117 -0.578)
        (xy 6.096 -0.54)
        (xy 6.059 -0.441)
        (xy 6.032 -0.325)
        (xy 6.016 -0.199)
        (xy 6.011 -0.067)
        (xy 5.729 -0.067)
        (xy 5.728 -0.094)
        (xy 5.738 -0.243)
        (xy 5.762 -0.382)
        (xy 5.801 -0.509)
        (xy 5.854 -0.622)
        (xy 5.92 -0.719)
        (xy 5.939 -0.741)
        (xy 6.024 -0.817)
        (xy 6.12 -0.872)
        (xy 6.228 -0.907)
        (xy 6.348 -0.922)
        (xy 6.384 -0.923)
        (xy 6.505 -0.915)
      )

      (stroke (width 0.001395) (type solid)) (fill solid) (layer "F.Mask"))
    (fp_poly
      (pts
        (xy 4.407 -0.921)
        (xy 4.484 -0.913)
        (xy 4.528 -0.905)
        (xy 4.572 -0.892)
        (xy 4.62 -0.875)
        (xy 4.665 -0.855)
        (xy 4.701 -0.837)
        (xy 4.722 -0.822)
        (xy 4.723 -0.82)
        (xy 4.722 -0.805)
        (xy 4.713 -0.776)
        (xy 4.7 -0.74)
        (xy 4.685 -0.703)
        (xy 4.671 -0.672)
        (xy 4.66 -0.655)
        (xy 4.658 -0.653)
        (xy 4.643 -0.657)
        (xy 4.614 -0.669)
        (xy 4.585 -0.682)
        (xy 4.494 -0.713)
        (xy 4.405 -0.725)
        (xy 4.32 -0.718)
        (xy 4.246 -0.692)
        (xy 4.185 -0.648)
        (xy 4.128 -0.583)
        (xy 4.078 -0.5)
        (xy 4.037 -0.402)
        (xy 4.02 -0.346)
        (xy 4.006 -0.276)
        (xy 3.997 -0.19)
        (xy 3.993 -0.096)
        (xy 3.994 0.001)
        (xy 4 0.093)
        (xy 4.011 0.173)
        (xy 4.02 0.213)
        (xy 4.06 0.33)
        (xy 4.11 0.426)
        (xy 4.171 0.502)
        (xy 4.243 0.557)
        (xy 4.249 0.56)
        (xy 4.285 0.578)
        (xy 4.316 0.589)
        (xy 4.353 0.593)
        (xy 4.404 0.594)
        (xy 4.406 0.594)
        (xy 4.46 0.592)
        (xy 4.506 0.584)
        (xy 4.554 0.568)
        (xy 4.609 0.543)
        (xy 4.65 0.521)
        (xy 4.655 0.524)
        (xy 4.664 0.54)
        (xy 4.678 0.57)
        (xy 4.698 0.617)
        (xy 4.724 0.684)
        (xy 4.727 0.69)
        (xy 4.72 0.703)
        (xy 4.696 0.721)
        (xy 4.66 0.741)
        (xy 4.616 0.761)
        (xy 4.569 0.778)
        (xy 4.557 0.782)
        (xy 4.493 0.796)
        (xy 4.417 0.804)
        (xy 4.337 0.808)
        (xy 4.265 0.805)
        (xy 4.235 0.801)
        (xy 4.191 0.79)
        (xy 4.138 0.771)
        (xy 4.087 0.749)
        (xy 3.989 0.688)
        (xy 3.905 0.608)
        (xy 3.834 0.509)
        (xy 3.777 0.393)
        (xy 3.735 0.258)
        (xy 3.721 0.193)
        (xy 3.711 0.116)
        (xy 3.705 0.024)
        (xy 3.705 -0.075)
        (xy 3.708 -0.176)
        (xy 3.716 -0.27)
        (xy 3.728 -0.353)
        (xy 3.738 -0.397)
        (xy 3.784 -0.528)
        (xy 3.845 -0.642)
        (xy 3.919 -0.738)
        (xy 4.007 -0.816)
        (xy 4.107 -0.874)
        (xy 4.187 -0.904)
        (xy 4.249 -0.916)
        (xy 4.325 -0.922)
        (xy 4.407 -0.921)
      )

      (stroke (width 0.001395) (type solid)) (fill solid) (layer "F.Mask"))
    (fp_poly
      (pts
        (xy -2.526 -0.915)
        (xy -2.451 -0.901)
        (xy -2.366 -0.875)
        (xy -2.297 -0.843)
        (xy -2.238 -0.8)
        (xy -2.209 -0.773)
        (xy -2.166 -0.72)
        (xy -2.128 -0.651)
        (xy -2.098 -0.576)
        (xy -2.084 -0.523)
        (xy -2.081 -0.496)
        (xy -2.079 -0.448)
        (xy -2.077 -0.38)
        (xy -2.075 -0.294)
        (xy -2.074 -0.193)
        (xy -2.073 -0.078)
        (xy -2.072 0.049)
        (xy -2.072 0.118)
        (xy -2.072 0.694)
        (xy -2.127 0.719)
        (xy -2.226 0.754)
        (xy -2.341 0.782)
        (xy -2.465 0.8)
        (xy -2.591 0.809)
        (xy -2.712 0.807)
        (xy -2.776 0.801)
        (xy -2.901 0.776)
        (xy -3.008 0.736)
        (xy -3.097 0.682)
        (xy -3.167 0.614)
        (xy -3.218 0.531)
        (xy -3.25 0.435)
        (xy -3.263 0.325)
        (xy -3.263 0.27)
        (xy -3.261 0.26)
        (xy -2.991 0.26)
        (xy -2.988 0.358)
        (xy -2.967 0.442)
        (xy -2.927 0.513)
        (xy -2.869 0.568)
        (xy -2.794 0.609)
        (xy -2.758 0.621)
        (xy -2.711 0.629)
        (xy -2.649 0.632)
        (xy -2.579 0.632)
        (xy -2.509 0.628)
        (xy -2.445 0.62)
        (xy -2.395 0.609)
        (xy -2.388 0.607)
        (xy -2.332 0.587)
        (xy -2.332 -0.157)
        (xy -2.4 -0.149)
        (xy -2.443 -0.142)
        (xy -2.499 -0.131)
        (xy -2.558 -0.118)
        (xy -2.577 -0.113)
        (xy -2.698 -0.076)
        (xy -2.797 -0.03)
        (xy -2.875 0.025)
        (xy -2.933 0.089)
        (xy -2.971 0.163)
        (xy -2.99 0.248)
        (xy -2.991 0.26)
        (xy -3.261 0.26)
        (xy -3.247 0.164)
        (xy -3.212 0.069)
        (xy -3.155 -0.015)
        (xy -3.123 -0.049)
        (xy -3.052 -0.105)
        (xy -2.961 -0.157)
        (xy -2.852 -0.204)
        (xy -2.729 -0.243)
        (xy -2.595 -0.275)
        (xy -2.453 -0.298)
        (xy -2.451 -0.298)
        (xy -2.329 -0.313)
        (xy -2.336 -0.413)
        (xy -2.349 -0.508)
        (xy -2.377 -0.584)
        (xy -2.418 -0.642)
        (xy -2.476 -0.685)
        (xy -2.551 -0.714)
        (xy -2.587 -0.722)
        (xy -2.685 -0.731)
        (xy -2.793 -0.723)
        (xy -2.908 -0.699)
        (xy -3.023 -0.66)
        (xy -3.033 -0.655)
        (xy -3.069 -0.641)
        (xy -3.096 -0.632)
        (xy -3.106 -0.631)
        (xy -3.112 -0.643)
        (xy -3.124 -0.671)
        (xy -3.138 -0.707)
        (xy -3.152 -0.745)
        (xy -3.163 -0.777)
        (xy -3.17 -0.797)
        (xy -3.17 -0.8)
        (xy -3.161 -0.807)
        (xy -3.135 -0.821)
        (xy -3.106 -0.835)
        (xy -3 -0.873)
        (xy -2.882 -0.901)
        (xy -2.76 -0.917)
        (xy -2.639 -0.922)
        (xy -2.526 -0.915)
      )

      (stroke (width 0.001395) (type solid)) (fill solid) (layer "F.Mask"))
    (fp_poly
      (pts
        (xy -5.818 -2.455)
        (xy -5.769 -2.444)
        (xy -5.768 -2.444)
        (xy -5.753 -2.436)
        (xy -5.719 -2.417)
        (xy -5.668 -2.388)
        (xy -5.602 -2.351)
        (xy -5.523 -2.306)
        (xy -5.433 -2.254)
        (xy -5.332 -2.197)
        (xy -5.224 -2.135)
        (xy -5.11 -2.07)
        (xy -4.992 -2.002)
        (xy -4.872 -1.933)
        (xy -4.75 -1.863)
        (xy -4.63 -1.794)
        (xy -4.514 -1.727)
        (xy -4.401 -1.662)
        (xy -4.296 -1.601)
        (xy -4.199 -1.545)
        (xy -4.112 -1.494)
        (xy -4.037 -1.45)
        (xy -3.976 -1.415)
        (xy -3.931 -1.388)
        (xy -3.903 -1.371)
        (xy -3.899 -1.369)
        (xy -3.849 -1.328)
        (xy -3.811 -1.279)
        (xy -3.779 -1.224)
        (xy -3.775 -0.098)
        (xy -3.775 0.117)
        (xy -3.775 0.312)
        (xy -3.775 0.485)
        (xy -3.775 0.636)
        (xy -3.776 0.765)
        (xy -3.777 0.873)
        (xy -3.779 0.957)
        (xy -3.781 1.019)
        (xy -3.783 1.058)
        (xy -3.784 1.072)
        (xy -3.789 1.09)
        (xy -3.794 1.106)
        (xy -3.801 1.122)
        (xy -3.81 1.137)
        (xy -3.824 1.154)
        (xy -3.843 1.172)
        (xy -3.868 1.192)
        (xy -3.9 1.216)
        (xy -3.942 1.245)
        (xy -3.994 1.278)
        (xy -4.057 1.317)
        (xy -4.133 1.362)
        (xy -4.223 1.415)
        (xy -4.327 1.476)
        (xy -4.448 1.546)
        (xy -4.586 1.626)
        (xy -4.743 1.717)
        (xy -4.813 1.758)
        (xy -5.763 2.306)
        (xy -5.852 2.311)
        (xy -5.94 2.315)
        (xy -6.289 2.115)
        (xy -6.502 1.992)
        (xy -6.696 1.881)
        (xy -6.871 1.78)
        (xy -7.029 1.689)
        (xy -7.17 1.608)
        (xy -7.295 1.535)
        (xy -7.406 1.471)
        (xy -7.502 1.414)
        (xy -7.586 1.364)
        (xy -7.658 1.321)
        (xy -7.719 1.284)
        (xy -7.77 1.251)
        (xy -7.812 1.224)
        (xy -7.846 1.2)
        (xy -7.873 1.18)
        (xy -7.893 1.163)
        (xy -7.909 1.148)
        (xy -7.92 1.134)
        (xy -7.927 1.122)
        (xy -7.932 1.11)
        (xy -7.936 1.098)
        (xy -7.939 1.085)
        (xy -7.942 1.072)
        (xy -7.945 1.051)
        (xy -7.947 1.007)
        (xy -7.948 0.94)
        (xy -7.95 0.85)
        (xy -7.951 0.738)
        (xy -7.951 0.604)
        (xy -7.952 0.447)
        (xy -7.952 0.269)
        (xy -7.952 0.07)
        (xy -7.951 -0.072)
        (xy -7.222 -0.072)
        (xy -7.222 0.081)
        (xy -7.221 0.213)
        (xy -7.221 0.324)
        (xy -7.22 0.418)
        (xy -7.219 0.495)
        (xy -7.217 0.557)
        (xy -7.214 0.607)
        (xy -7.211 0.646)
        (xy -7.206 0.675)
        (xy -7.2 0.698)
        (xy -7.193 0.714)
        (xy -7.184 0.727)
        (xy -7.174 0.738)
        (xy -7.162 0.748)
        (xy -7.161 0.749)
        (xy -7.145 0.76)
        (xy -7.111 0.781)
        (xy -7.061 0.811)
        (xy -6.997 0.849)
        (xy -6.922 0.893)
        (xy -6.837 0.943)
        (xy -6.745 0.996)
        (xy -6.649 1.052)
        (xy -6.549 1.109)
        (xy -6.45 1.167)
        (xy -6.352 1.223)
        (xy -6.258 1.277)
        (xy -6.17 1.326)
        (xy -6.091 1.371)
        (xy -6.022 1.41)
        (xy -5.967 1.44)
        (xy -5.926 1.462)
        (xy -5.903 1.474)
        (xy -5.9 1.475)
        (xy -5.87 1.483)
        (xy -5.85 1.484)
        (xy -5.826 1.476)
        (xy -5.811 1.47)
        (xy -5.792 1.46)
        (xy -5.754 1.44)
        (xy -5.701 1.41)
        (xy -5.635 1.373)
        (xy -5.558 1.329)
        (xy -5.472 1.28)
        (xy -5.379 1.227)
        (xy -5.282 1.171)
        (xy -5.183 1.114)
        (xy -5.084 1.057)
        (xy -4.987 1)
        (xy -4.895 0.947)
        (xy -4.81 0.897)
        (xy -4.734 0.852)
        (xy -4.67 0.814)
        (xy -4.619 0.783)
        (xy -4.583 0.762)
        (xy -4.566 0.75)
        (xy -4.553 0.739)
        (xy -4.543 0.728)
        (xy -4.534 0.715)
        (xy -4.527 0.699)
        (xy -4.521 0.677)
        (xy -4.516 0.648)
        (xy -4.513 0.61)
        (xy -4.51 0.562)
        (xy -4.508 0.5)
        (xy -4.506 0.424)
        (xy -4.506 0.332)
        (xy -4.505 0.222)
        (xy -4.505 0.092)
        (xy -4.505 -0.059)
        (xy -4.505 -0.072)
        (xy -4.505 -0.227)
        (xy -4.505 -0.359)
        (xy -4.506 -0.471)
        (xy -4.506 -0.565)
        (xy -4.508 -0.643)
        (xy -4.51 -0.706)
        (xy -4.513 -0.756)
        (xy -4.517 -0.795)
        (xy -4.522 -0.825)
        (xy -4.529 -0.847)
        (xy -4.537 -0.864)
        (xy -4.547 -0.877)
        (xy -4.558 -0.887)
        (xy -4.572 -0.898)
        (xy -4.578 -0.902)
        (xy -4.595 -0.913)
        (xy -4.631 -0.935)
        (xy -4.683 -0.966)
        (xy -4.75 -1.005)
        (xy -4.83 -1.052)
        (xy -4.92 -1.105)
        (xy -5.02 -1.162)
        (xy -5.126 -1.224)
        (xy -5.215 -1.275)
        (xy -5.342 -1.349)
        (xy -5.451 -1.411)
        (xy -5.543 -1.463)
        (xy -5.619 -1.506)
        (xy -5.682 -1.541)
        (xy -5.732 -1.568)
        (xy -5.772 -1.588)
        (xy -5.802 -1.602)
        (xy -5.826 -1.612)
        (xy -5.843 -1.617)
        (xy -5.857 -1.62)
        (xy -5.862 -1.62)
        (xy -5.874 -1.619)
        (xy -5.89 -1.615)
        (xy -5.911 -1.607)
        (xy -5.938 -1.595)
        (xy -5.973 -1.578)
        (xy -6.018 -1.554)
        (xy -6.074 -1.523)
        (xy -6.144 -1.484)
        (xy -6.228 -1.437)
        (xy -6.328 -1.379)
        (xy -6.446 -1.312)
        (xy -6.528 -1.264)
        (xy -6.639 -1.2)
        (xy -6.745 -1.139)
        (xy -6.842 -1.082)
        (xy -6.931 -1.03)
        (xy -7.008 -0.985)
        (xy -7.072 -0.947)
        (xy -7.121 -0.918)
        (xy -7.154 -0.898)
        (xy -7.167 -0.889)
        (xy -7.178 -0.879)
        (xy -7.187 -0.869)
        (xy -7.195 -0.856)
        (xy -7.202 -0.839)
        (xy -7.207 -0.817)
        (xy -7.211 -0.786)
        (xy -7.215 -0.746)
        (xy -7.217 -0.694)
        (xy -7.219 -0.63)
        (xy -7.22 -0.551)
        (xy -7.221 -0.454)
        (xy -7.221 -0.34)
        (xy -7.222 -0.205)
        (xy -7.222 -0.072)
        (xy -7.951 -0.072)
        (xy -7.951 -0.098)
        (xy -7.951 -0.29)
        (xy -7.95 -0.459)
        (xy -7.95 -0.607)
        (xy -7.949 -0.736)
        (xy -7.948 -0.848)
        (xy -7.947 -0.943)
        (xy -7.946 -1.023)
        (xy -7.944 -1.089)
        (xy -7.941 -1.143)
        (xy -7.938 -1.187)
        (xy -7.934 -1.221)
        (xy -7.93 -1.248)
        (xy -7.924 -1.268)
        (xy -7.917 -1.284)
        (xy -7.909 -1.296)
        (xy -7.9 -1.306)
        (xy -7.89 -1.315)
        (xy -7.878 -1.326)
        (xy -7.873 -1.33)
        (xy -7.858 -1.341)
        (xy -7.824 -1.362)
        (xy -7.773 -1.393)
        (xy -7.705 -1.434)
        (xy -7.623 -1.483)
        (xy -7.528 -1.539)
        (xy -7.422 -1.601)
        (xy -7.305 -1.669)
        (xy -7.18 -1.742)
        (xy -7.048 -1.819)
        (xy -6.911 -1.898)
        (xy -6.896 -1.907)
        (xy -6.736 -1.999)
        (xy -6.595 -2.081)
        (xy -6.472 -2.152)
        (xy -6.365 -2.213)
        (xy -6.273 -2.266)
        (xy -6.195 -2.31)
        (xy -6.13 -2.346)
        (xy -6.076 -2.376)
        (xy -6.031 -2.4)
        (xy -5.995 -2.418)
        (xy -5.967 -2.432)
        (xy -5.944 -2.442)
        (xy -5.926 -2.448)
        (xy -5.911 -2.452)
        (xy -5.898 -2.455)
        (xy -5.885 -2.456)
        (xy -5.881 -2.456)
        (xy -5.818 -2.455)
      )

      (stroke (width 0.001395) (type solid)) (fill solid) (layer "F.Mask"))
    (fp_poly
      (pts
        (xy -5.8 -1.041)
        (xy -5.789 -1.037)
        (xy -5.735 -1.001)
        (xy -5.695 -0.951)
        (xy -5.673 -0.891)
        (xy -5.671 -0.827)
        (xy -5.674 -0.812)
        (xy -5.697 -0.751)
        (xy -5.738 -0.706)
        (xy -5.779 -0.681)
        (xy -5.828 -0.657)
        (xy -5.828 -0.38)
        (xy -5.622 -0.38)
        (xy -5.537 -0.464)
        (xy -5.452 -0.548)
        (xy -5.458 -0.609)
        (xy -5.458 -0.61)
        (xy -5.378 -0.61)
        (xy -5.365 -0.583)
        (xy -5.337 -0.57)
        (xy -5.304 -0.573)
        (xy -5.28 -0.587)
        (xy -5.263 -0.615)
        (xy -5.269 -0.643)
        (xy -5.285 -0.663)
        (xy -5.307 -0.682)
        (xy -5.326 -0.684)
        (xy -5.351 -0.67)
        (xy -5.353 -0.668)
        (xy -5.374 -0.642)
        (xy -5.378 -0.61)
        (xy -5.458 -0.61)
        (xy -5.46 -0.648)
        (xy -5.455 -0.674)
        (xy -5.44 -0.699)
        (xy -5.433 -0.707)
        (xy -5.39 -0.744)
        (xy -5.343 -0.76)
        (xy -5.295 -0.759)
        (xy -5.251 -0.743)
        (xy -5.215 -0.714)
        (xy -5.191 -0.673)
        (xy -5.182 -0.624)
        (xy -5.19 -0.575)
        (xy -5.217 -0.528)
        (xy -5.259 -0.498)
        (xy -5.316 -0.486)
        (xy -5.326 -0.486)
        (xy -5.351 -0.485)
        (xy -5.371 -0.481)
        (xy -5.392 -0.47)
        (xy -5.418 -0.45)
        (xy -5.453 -0.418)
        (xy -5.482 -0.391)
        (xy -5.583 -0.297)
        (xy -5.828 -0.297)
        (xy -5.828 -0.108)
        (xy -5.38 -0.108)
        (xy -5.362 -0.142)
        (xy -5.33 -0.18)
        (xy -5.286 -0.203)
        (xy -5.236 -0.21)
        (xy -5.187 -0.2)
        (xy -5.145 -0.172)
        (xy -5.141 -0.168)
        (xy -5.11 -0.12)
        (xy -5.1 -0.071)
        (xy -5.107 -0.025)
        (xy -5.129 0.016)
        (xy -5.163 0.047)
        (xy -5.206 0.065)
        (xy -5.255 0.068)
        (xy -5.308 0.051)
        (xy -5.318 0.045)
        (xy -5.346 0.024)
        (xy -5.363 0.002)
        (xy -5.364 -0.002)
        (xy -5.367 -0.01)
        (xy -5.374 -0.016)
        (xy -5.389 -0.02)
        (xy -5.413 -0.023)
        (xy -5.451 -0.024)
        (xy -5.506 -0.025)
        (xy -5.58 -0.025)
        (xy -5.599 -0.025)
        (xy -5.828 -0.025)
        (xy -5.828 0.152)
        (xy -5.585 0.152)
        (xy -5.389 0.349)
        (xy -5.334 0.344)
        (xy -5.275 0.348)
        (xy -5.229 0.371)
        (xy -5.197 0.412)
        (xy -5.189 0.434)
        (xy -5.181 0.49)
        (xy -5.195 0.539)
        (xy -5.224 0.578)
        (xy -5.27 0.61)
        (xy -5.319 0.621)
        (xy -5.366 0.615)
        (xy -5.408 0.592)
        (xy -5.439 0.555)
        (xy -5.457 0.507)
        (xy -5.458 0.471)
        (xy -5.377 0.471)
        (xy -5.373 0.501)
        (xy -5.362 0.518)
        (xy -5.335 0.538)
        (xy -5.309 0.537)
        (xy -5.285 0.518)
        (xy -5.264 0.489)
        (xy -5.266 0.463)
        (xy -5.284 0.442)
        (xy -5.313 0.427)
        (xy -5.342 0.43)
        (xy -5.365 0.446)
        (xy -5.377 0.471)
        (xy -5.458 0.471)
        (xy -5.458 0.46)
        (xy -5.451 0.404)
        (xy -5.622 0.235)
        (xy -5.828 0.235)
        (xy -5.828 0.514)
        (xy -5.779 0.536)
        (xy -5.728 0.571)
        (xy -5.693 0.618)
        (xy -5.674 0.674)
        (xy -5.67 0.732)
        (xy -5.684 0.789)
        (xy -5.713 0.839)
        (xy -5.759 0.879)
        (xy -5.77 0.885)
        (xy -5.831 0.904)
        (xy -5.897 0.904)
        (xy -5.958 0.885)
        (xy -5.96 0.884)
        (xy -6.008 0.846)
        (xy -6.04 0.797)
        (xy -6.055 0.741)
        (xy -6.055 0.713)
        (xy -5.974 0.713)
        (xy -5.97 0.748)
        (xy -5.952 0.776)
        (xy -5.936 0.791)
        (xy -5.893 0.819)
        (xy -5.85 0.823)
        (xy -5.806 0.804)
        (xy -5.79 0.791)
        (xy -5.764 0.762)
        (xy -5.753 0.732)
        (xy -5.752 0.713)
        (xy -5.763 0.67)
        (xy -5.791 0.633)
        (xy -5.829 0.608)
        (xy -5.863 0.601)
        (xy -5.906 0.611)
        (xy -5.943 0.639)
        (xy -5.967 0.678)
        (xy -5.974 0.713)
        (xy -6.055 0.713)
        (xy -6.054 0.682)
        (xy -6.037 0.626)
        (xy -6.004 0.577)
        (xy -5.956 0.54)
        (xy -5.947 0.536)
        (xy -5.899 0.514)
        (xy -5.899 0.235)
        (xy -6.105 0.235)
        (xy -6.275 0.404)
        (xy -6.269 0.46)
        (xy -6.271 0.516)
        (xy -6.292 0.563)
        (xy -6.326 0.597)
        (xy -6.369 0.617)
        (xy -6.417 0.621)
        (xy -6.465 0.606)
        (xy -6.502 0.578)
        (xy -6.535 0.533)
        (xy -6.546 0.483)
        (xy -6.543 0.468)
        (xy -6.463 0.468)
        (xy -6.46 0.494)
        (xy -6.442 0.518)
        (xy -6.413 0.539)
        (xy -6.388 0.537)
        (xy -6.366 0.519)
        (xy -6.351 0.488)
        (xy -6.355 0.457)
        (xy -6.375 0.434)
        (xy -6.39 0.428)
        (xy -6.424 0.43)
        (xy -6.443 0.442)
        (xy -6.463 0.468)
        (xy -6.543 0.468)
        (xy -6.537 0.434)
        (xy -6.512 0.386)
        (xy -6.472 0.356)
        (xy -6.418 0.344)
        (xy -6.393 0.344)
        (xy -6.338 0.349)
        (xy -6.141 0.152)
        (xy -5.899 0.152)
        (xy -5.899 -0.025)
        (xy -6.128 -0.025)
        (xy -6.207 -0.025)
        (xy -6.266 -0.025)
        (xy -6.307 -0.023)
        (xy -6.335 -0.021)
        (xy -6.351 -0.017)
        (xy -6.36 -0.012)
        (xy -6.364 -0.004)
        (xy -6.366 -0.001)
        (xy -6.385 0.026)
        (xy -6.419 0.05)
        (xy -6.46 0.066)
        (xy -6.487 0.069)
        (xy -6.541 0.059)
        (xy -6.584 0.033)
        (xy -6.613 -0.007)
        (xy -6.626 -0.054)
        (xy -6.625 -0.07)
        (xy -6.547 -0.07)
        (xy -6.543 -0.053)
        (xy -6.531 -0.038)
        (xy -6.5 -0.017)
        (xy -6.469 -0.018)
        (xy -6.449 -0.032)
        (xy -6.432 -0.062)
        (xy -6.435 -0.082)
        (xy -5.295 -0.082)
        (xy -5.29 -0.049)
        (xy -5.278 -0.032)
        (xy -5.248 -0.015)
        (xy -5.216 -0.021)
        (xy -5.195 -0.038)
        (xy -5.181 -0.057)
        (xy -5.182 -0.075)
        (xy -5.191 -0.094)
        (xy -5.216 -0.121)
        (xy -5.246 -0.129)
        (xy -5.275 -0.116)
        (xy -5.277 -0.114)
        (xy -5.295 -0.082)
        (xy -6.435 -0.082)
        (xy -6.438 -0.094)
        (xy -6.453 -0.113)
        (xy -6.483 -0.129)
        (xy -6.512 -0.122)
        (xy -6.536 -0.094)
        (xy -6.547 -0.07)
        (xy -6.625 -0.07)
        (xy -6.622 -0.104)
        (xy -6.598 -0.153)
        (xy -6.586 -0.168)
        (xy -6.544 -0.199)
        (xy -6.495 -0.211)
        (xy -6.444 -0.204)
        (xy -6.399 -0.18)
        (xy -6.367 -0.143)
        (xy -6.346 -0.108)
        (xy -5.899 -0.108)
        (xy -5.899 -0.297)
        (xy -6.143 -0.297)
        (xy -6.244 -0.391)
        (xy -6.288 -0.432)
        (xy -6.319 -0.459)
        (xy -6.342 -0.475)
        (xy -6.363 -0.483)
        (xy -6.384 -0.486)
        (xy -6.404 -0.486)
        (xy -6.462 -0.494)
        (xy -6.504 -0.52)
        (xy -6.532 -0.565)
        (xy -6.538 -0.58)
        (xy -6.543 -0.623)
        (xy -6.466 -0.623)
        (xy -6.456 -0.596)
        (xy -6.431 -0.577)
        (xy -6.399 -0.569)
        (xy -6.37 -0.576)
        (xy -6.362 -0.583)
        (xy -6.348 -0.611)
        (xy -6.353 -0.642)
        (xy -6.374 -0.668)
        (xy -6.396 -0.682)
        (xy -6.409 -0.687)
        (xy -6.426 -0.678)
        (xy -6.447 -0.657)
        (xy -6.462 -0.634)
        (xy -6.466 -0.623)
        (xy -6.543 -0.623)
        (xy -6.544 -0.635)
        (xy -6.532 -0.683)
        (xy -6.505 -0.722)
        (xy -6.467 -0.748)
        (xy -6.422 -0.761)
        (xy -6.374 -0.759)
        (xy -6.327 -0.738)
        (xy -6.294 -0.707)
        (xy -6.275 -0.681)
        (xy -6.267 -0.657)
        (xy -6.267 -0.623)
        (xy -6.268 -0.609)
        (xy -6.275 -0.548)
        (xy -6.19 -0.464)
        (xy -6.105 -0.38)
        (xy -5.899 -0.38)
        (xy -5.899 -0.658)
        (xy -5.946 -0.679)
        (xy -6.001 -0.715)
        (xy -6.038 -0.766)
        (xy -6.052 -0.805)
        (xy -6.058 -0.86)
        (xy -5.977 -0.86)
        (xy -5.973 -0.833)
        (xy -5.964 -0.813)
        (xy -5.934 -0.772)
        (xy -5.894 -0.75)
        (xy -5.849 -0.748)
        (xy -5.804 -0.767)
        (xy -5.799 -0.771)
        (xy -5.764 -0.808)
        (xy -5.752 -0.849)
        (xy -5.762 -0.892)
        (xy -5.79 -0.937)
        (xy -5.828 -0.962)
        (xy -5.87 -0.968)
        (xy -5.912 -0.956)
        (xy -5.948 -0.925)
        (xy -5.969 -0.889)
        (xy -5.977 -0.86)
        (xy -6.058 -0.86)
        (xy -6.059 -0.868)
        (xy -6.045 -0.927)
        (xy -6.015 -0.977)
        (xy -5.972 -1.017)
        (xy -5.92 -1.043)
        (xy -5.861 -1.052)
        (xy -5.8 -1.041)
      )

      (stroke (width 0.001395) (type solid)) (fill solid) (layer "F.Mask"))
  )

  (footprint "scalenode-cm4-baseboard-footprints:SOIC127P1594X685-24N" (layer "F.Cu")
    (at 105.187 66.818 180)
    (descr "PS-2473.001-A")
    (tags "Inductor")
    (property "Author" "Antmicro")
    (property "Description" "Common Mode Chokes / Filters 1000Base-T SMD PoE+ 350uH .3Ohms 1-Port")
    (property "License" "Apache-2.0")
    (property "MPN" "H6096NL")
    (property "Manufacturer" "Pulse Electronics")
    (property "Sheetfile" "poe.kicad_sch")
    (property "Sheetname" "PoE")
    (property "ki_description" "Common Mode Chokes / Filters 1000Base-T SMD PoE+ 350uH .3Ohms 1-Port")
    (attr smd)
    (fp_text reference "L3" (at 5.397 -10.182 180) (layer "F.SilkS")
        (effects (font (size 0.7 0.7) (thickness 0.15)) (justify left bottom))
    )
    (fp_text value "H6096NL" (at 0.237 -12.082 180) (layer "F.SilkS") hide
        (effects (font (size 0.7 0.7) (thickness 0.15)) (justify left bottom))
    )
    (fp_text user "License: Apache-2.0" (at -8.75 13.854 180) (layer "F.Fab") hide
        (effects (font (size 0.7 0.7) (thickness 0.15)) (justify left bottom))
    )
    (fp_text user "${REFERENCE}" (at -8.75 11.454 180) (layer "F.Fab") hide
        (effects (font (size 0.7 0.7) (thickness 0.15)) (justify left bottom))
    )
    (fp_text user "Author: Antmicro" (at -8.75 12.653 180) (layer "F.Fab") hide
        (effects (font (size 0.7 0.7) (thickness 0.15)) (justify left bottom))
    )
    (fp_line (start -8.5 -7.76) (end -6.101 -7.76)
      (stroke (width 0.15) (type solid)) (layer "F.SilkS"))
    (fp_line (start -5.75 -9.08) (end 5.749 -9.08)
      (stroke (width 0.15) (type solid)) (layer "F.SilkS"))
    (fp_line (start -5.75 9.079) (end -5.75 -9.08)
      (stroke (width 0.15) (type solid)) (layer "F.SilkS"))
    (fp_line (start 5.749 -9.08) (end 5.749 9.079)
      (stroke (width 0.15) (type solid)) (layer "F.SilkS"))
    (fp_line (start 5.749 9.079) (end -5.75 9.079)
      (stroke (width 0.15) (type solid)) (layer "F.SilkS"))
    (fp_circle (center -9.017 -6.986) (end -8.967 -6.986)
      (stroke (width 0.15) (type solid)) (fill solid) (layer "F.SilkS"))
    (fp_line (start -8.75 -9.47) (end 8.74 -9.47)
      (stroke (width 0.05) (type solid)) (layer "F.CrtYd"))
    (fp_line (start -8.75 9.45) (end -8.75 -9.47)
      (stroke (width 0.05) (type solid)) (layer "F.CrtYd"))
    (fp_line (start 8.74 -9.47) (end 8.74 9.45)
      (stroke (width 0.05) (type solid)) (layer "F.CrtYd"))
    (fp_line (start 8.74 9.45) (end -8.75 9.45)
      (stroke (width 0.05) (type solid)) (layer "F.CrtYd"))
    (fp_line (start -6.101 -9.08) (end 6.099 -9.08)
      (stroke (width 0.15) (type solid)) (layer "F.Fab"))
    (fp_line (start -6.101 -7.811) (end -4.83 -9.08)
      (stroke (width 0.15) (type solid)) (layer "F.Fab"))
    (fp_line (start -6.101 9.079) (end -6.101 -9.08)
      (stroke (width 0.15) (type solid)) (layer "F.Fab"))
    (fp_line (start 6.099 -9.08) (end 6.099 9.079)
      (stroke (width 0.15) (type solid)) (layer "F.Fab"))
    (fp_line (start 6.099 9.079) (end -6.101 9.079)
      (stroke (width 0.15) (type solid)) (layer "F.Fab"))
    (pad "1" smd rect (at -7.3 -6.986 270) (size 0.85 2.4) (layers "F.Cu" "F.Paste" "F.Mask")
      (net 222 "Net-(L3-TCT1)") (pinfunction "TCT1") (pintype "passive"))
    (pad "2" smd rect (at -7.3 -5.715 270) (size 0.85 2.4) (layers "F.Cu" "F.Paste" "F.Mask")
      (net 87 "TRD0_P") (pinfunction "TD1+") (pintype "passive"))
    (pad "3" smd rect (at -7.3 -4.446 270) (size 0.85 2.4) (layers "F.Cu" "F.Paste" "F.Mask")
      (net 89 "TRD0_N") (pinfunction "TD1-") (pintype "passive"))
    (pad "4" smd rect (at -7.3 -3.176 270) (size 0.85 2.4) (layers "F.Cu" "F.Paste" "F.Mask")
      (net 223 "Net-(L3-TCT2)") (pinfunction "TCT2") (pintype "passive"))
    (pad "5" smd rect (at -7.3 -1.905 270) (size 0.85 2.4) (layers "F.Cu" "F.Paste" "F.Mask")
      (net 93 "TRD1_P") (pinfunction "TD2+") (pintype "passive"))
    (pad "6" smd rect (at -7.3 -0.635 270) (size 0.85 2.4) (layers "F.Cu" "F.Paste" "F.Mask")
      (net 91 "TRD1_N") (pinfunction "TD2-") (pintype "passive"))
    (pad "7" smd rect (at -7.3 0.633 270) (size 0.85 2.4) (layers "F.Cu" "F.Paste" "F.Mask")
      (net 224 "Net-(L3-TCT3)") (pinfunction "TCT3") (pintype "passive"))
    (pad "8" smd rect (at -7.3 1.904 270) (size 0.85 2.4) (layers "F.Cu" "F.Paste" "F.Mask")
      (net 88 "TRD2_P") (pinfunction "TD3+") (pintype "passive"))
    (pad "9" smd rect (at -7.3 3.173 270) (size 0.85 2.4) (layers "F.Cu" "F.Paste" "F.Mask")
      (net 90 "TRD2_N") (pinfunction "TD3-") (pintype "passive"))
    (pad "10" smd rect (at -7.3 4.445 270) (size 0.85 2.4) (layers "F.Cu" "F.Paste" "F.Mask")
      (net 228 "Net-(L3-TCT4)") (pinfunction "TCT4") (pintype "passive"))
    (pad "11" smd rect (at -7.3 5.714 270) (size 0.85 2.4) (layers "F.Cu" "F.Paste" "F.Mask")
      (net 94 "TRD3_P") (pinfunction "TD4+") (pintype "passive"))
    (pad "12" smd rect (at -7.3 6.985 270) (size 0.85 2.4) (layers "F.Cu" "F.Paste" "F.Mask")
      (net 92 "TRD3_N") (pinfunction "TD4-") (pintype "passive"))
    (pad "13" smd rect (at 7.299 6.985 270) (size 0.85 2.4) (layers "F.Cu" "F.Paste" "F.Mask")
      (net 160 "/PoE/T_ETH_D3_N") (pinfunction "MX4-") (pintype "passive"))
    (pad "14" smd rect (at 7.299 5.714 270) (size 0.85 2.4) (layers "F.Cu" "F.Paste" "F.Mask")
      (net 159 "/PoE/T_ETH_D3_P") (pinfunction "MX4+") (pintype "passive"))
    (pad "15" smd rect (at 7.299 4.445 270) (size 0.85 2.4) (layers "F.Cu" "F.Paste" "F.Mask")
      (net 20 "/PoE/PAIR78") (pinfunction "MCT4") (pintype "passive"))
    (pad "16" smd rect (at 7.299 3.173 270) (size 0.85 2.4) (layers "F.Cu" "F.Paste" "F.Mask")
      (net 157 "/PoE/T_ETH_D2_N") (pinfunction "MX3-") (pintype "passive"))
    (pad "17" smd rect (at 7.299 1.904 270) (size 0.85 2.4) (layers "F.Cu" "F.Paste" "F.Mask")
      (net 156 "/PoE/T_ETH_D2_P") (pinfunction "MX3+") (pintype "passive"))
    (pad "18" smd rect (at 7.299 0.633 270) (size 0.85 2.4) (layers "F.Cu" "F.Paste" "F.Mask")
      (net 3 "/PoE/PAIR45") (pinfunction "MCT3") (pintype "passive"))
    (pad "19" smd rect (at 7.299 -0.635 270) (size 0.85 2.4) (layers "F.Cu" "F.Paste" "F.Mask")
      (net 158 "/PoE/T_ETH_D1_N") (pinfunction "MX2-") (pintype "passive"))
    (pad "20" smd rect (at 7.299 -1.905 270) (size 0.85 2.4) (layers "F.Cu" "F.Paste" "F.Mask")
      (net 155 "/PoE/T_ETH_D1_P") (pinfunction "MX2+") (pintype "passive"))
    (pad "21" smd rect (at 7.299 -3.176 270) (size 0.85 2.4) (layers "F.Cu" "F.Paste" "F.Mask")
      (net 2 "/PoE/PAIR36") (pinfunction "MCT2") (pintype "passive"))
    (pad "22" smd rect (at 7.299 -4.446 270) (size 0.85 2.4) (layers "F.Cu" "F.Paste" "F.Mask")
      (net 154 "/PoE/T_ETH_D0_N") (pinfunction "MX1-") (pintype "passive"))
    (pad "23" smd rect (at 7.299 -5.715 270) (size 0.85 2.4) (layers "F.Cu" "F.Paste" "F.Mask")
      (net 153 "/PoE/T_ETH_D0_P") (pinfunction "MX1+") (pintype "passive"))
    (pad "24" smd rect (at 7.299 -6.986 270) (size 0.85 2.4) (layers "F.Cu" "F.Paste" "F.Mask")
      (net 1 "/PoE/PAIR12") (pinfunction "MCT1") (pintype "passive"))
  )

  (footprint "scalenode-cm4-baseboard-footprints:DFN-12-1EP_3x3mm" (layer "F.Cu")
    (at 165.19956 72.02372 180)
    (descr "http://www.ftdichip.com/Support/Documents/TechnicalNotes/TN_166%20FTDI%20Example%20IC%20PCB%20Footprints.pdf")
    (property "Author" "Antmicro")
    (property "License" "Apache-2.0")
    (property "MPN" "FT234XD-R")
    (property "Manufacturer" "FTDI Chip")
    (property "Sheetfile" "interfaces.kicad_sch")
    (property "Sheetname" "Interfaces")
    (property "ki_description" "USB to serial UART interface")
    (property "ki_keywords" "USB serial UART interface")
    (attr smd)
    (fp_text reference "U6" (at 2.19956 -1.47628 90) (layer "F.SilkS")
        (effects (font (size 0.7 0.7) (thickness 0.15)) (justify left bottom))
    )
    (fp_text value "FT234XD-R" (at 0 3.1) (layer "F.Fab")
        (effects (font (size 0.7 0.7) (thickness 0.15)) (justify right bottom))
    )
    (fp_text user "${REFERENCE}" (at -1.75 6.299) (layer "F.Fab") hide
        (effects (font (size 0.7 0.7) (thickness 0.15)) (justify right bottom))
    )
    (fp_text user "Author: Antmicro" (at -1.75 7.499) (layer "F.Fab") hide
        (effects (font (size 0.7 0.7) (thickness 0.15)) (justify right bottom))
    )
    (fp_text user "License: Apache-2.0" (at -1.75 8.699) (layer "F.Fab") hide
        (effects (font (size 0.7 0.7) (thickness 0.15)) (justify right bottom))
    )
    (fp_line (start -1.601 1.6) (end -1.601 1.396)
      (stroke (width 0.15) (type solid)) (layer "F.SilkS"))
    (fp_line (start -1.601 1.6) (end -1.397 1.6)
      (stroke (width 0.15) (type solid)) (layer "F.SilkS"))
    (fp_line (start -1.6 -1.5) (end -1.5 -1.6)
      (stroke (width 0.15) (type solid)) (layer "F.SilkS"))
    (fp_line (start -1.6 -1.4) (end -1.8 -1.4)
      (stroke (width 0.15) (type solid)) (layer "F.SilkS"))
    (fp_line (start -1.6 -1.4) (end -1.6 -1.5)
      (stroke (width 0.15) (type solid)) (layer "F.SilkS"))
    (fp_line (start -1.5 -1.6) (end -1.396 -1.6)
      (stroke (width 0.15) (type solid)) (layer "F.SilkS"))
    (fp_line (start 1.6 -1.601) (end 1.396 -1.601)
      (stroke (width 0.15) (type solid)) (layer "F.SilkS"))
    (fp_line (start 1.6 -1.601) (end 1.6 -1.397)
      (stroke (width 0.15) (type solid)) (layer "F.SilkS"))
    (fp_line (start 1.6 1.6) (end 1.396 1.6)
      (stroke (width 0.15) (type solid)) (layer "F.SilkS"))
    (fp_line (start 1.6 1.6) (end 1.6 1.396)
      (stroke (width 0.15) (type solid)) (layer "F.SilkS"))
    (fp_circle (center -1.8 -1.65) (end -1.8 -1.6)
      (stroke (width 0.15) (type solid)) (fill solid) (layer "F.SilkS"))
    (fp_rect (start -2 -1.79) (end 1.999 1.789)
      (stroke (width 0.05) (type solid)) (fill none) (layer "F.CrtYd"))
    (fp_line (start -1.5 -1.2) (end -1.5 1.499)
      (stroke (width 0.15) (type solid)) (layer "F.Fab"))
    (fp_line (start -1.2 -1.5) (end -1.5 -1.2)
      (stroke (width 0.15) (type solid)) (layer "F.Fab"))
    (fp_line (start -1.2 -1.5) (end 1.499 -1.5)
      (stroke (width 0.15) (type solid)) (layer "F.Fab"))
    (fp_line (start 1.499 -1.5) (end 1.499 1.499)
      (stroke (width 0.15) (type solid)) (layer "F.Fab"))
    (fp_line (start 1.499 1.499) (end -1.5 1.499)
      (stroke (width 0.15) (type solid)) (layer "F.Fab"))
    (pad "1" smd rect (at -1.551 -1.125 90) (size 0.25 0.65) (layers "F.Cu" "F.Paste" "F.Mask")
      (net 266 "Net-(U6-USBDM)") (pinfunction "USBDM") (pintype "bidirectional"))
    (pad "2" smd rect (at -1.551 -0.677 90) (size 0.25 0.65) (layers "F.Cu" "F.Paste" "F.Mask")
      (net 23 "Net-(U6-3.3VOUT)") (pinfunction "~{RESET}") (pintype "input"))
    (pad "3" smd rect (at -1.551 -0.227 90) (size 0.25 0.65) (layers "F.Cu" "F.Paste" "F.Mask")
      (net 23 "Net-(U6-3.3VOUT)") (pinfunction "3.3VOUT") (pintype "power_out"))
    (pad "4" smd rect (at -1.551 0.225 90) (size 0.25 0.65) (layers "F.Cu" "F.Paste" "F.Mask")
      (net 27 "/Interfaces/VBus_Slave") (pinfunction "VCC") (pintype "power_in"))
    (pad "5" smd rect (at -1.551 0.675 90) (size 0.25 0.65) (layers "F.Cu" "F.Paste" "F.Mask")
      (net 11 "GND") (pinfunction "GND") (pintype "passive"))
    (pad "6" smd rect (at -1.551 1.124 90) (size 0.25 0.65) (layers "F.Cu" "F.Paste" "F.Mask")
      (net 274 "unconnected-(U6-CBUS0-Pad6)") (pinfunction "CBUS0") (pintype "bidirectional+no_connect"))
    (pad "7" smd rect (at 1.55 1.124 90) (size 0.25 0.65) (layers "F.Cu" "F.Paste" "F.Mask")
      (net 268 "Net-(U6-TXD)") (pinfunction "TXD") (pintype "output"))
    (pad "8" smd rect (at 1.55 0.675 90) (size 0.25 0.65) (layers "F.Cu" "F.Paste" "F.Mask")
      (net 275 "unconnected-(U6-~{RTS}-Pad8)") (pinfunction "~{RTS}") (pintype "output+no_connect"))
    (pad "9" smd rect (at 1.55 0.225 90) (size 0.25 0.65) (layers "F.Cu" "F.Paste" "F.Mask")
      (net 23 "Net-(U6-3.3VOUT)") (pinfunction "VCCIO") (pintype "power_in"))
    (pad "10" smd rect (at 1.55 -0.227 90) (size 0.25 0.65) (layers "F.Cu" "F.Paste" "F.Mask")
      (net 265 "Net-(U6-RXD)") (pinfunction "RXD") (pintype "input"))
    (pad "11" smd rect (at 1.55 -0.677 90) (size 0.25 0.65) (layers "F.Cu" "F.Paste" "F.Mask")
      (net 276 "unconnected-(U6-~{CTS}-Pad11)") (pinfunction "~{CTS}") (pintype "input+no_connect"))
    (pad "12" smd rect (at 1.55 -1.125 90) (size 0.25 0.65) (layers "F.Cu" "F.Paste" "F.Mask")
      (net 267 "Net-(U6-USBDP)") (pinfunction "USBDP") (pintype "bidirectional"))
    (pad "13" smd rect (at 0 0 90) (size 2.5 1.7) (layers "F.Cu" "F.Paste" "F.Mask")
      (net 11 "GND") (pinfunction "GND") (pintype "power_in"))
  )

  (footprint "scalenode-cm4-baseboard-footprints:C_0402_1005Metric" (layer "F.Cu")
    (at 168.6414 70.1746 180)
    (descr "Capacitor SMD 0402")
    (tags "capacitor SMD 0402")
    (property "Author" "Antmicro")
    (property "Dielectric" "X5R")
    (property "License" "Apache-2.0")
    (property "MPN" "GRM155R61H104KE14D")
    (property "Manufacturer" "Murata")
    (property "Sheetfile" "interfaces.kicad_sch")
    (property "Sheetname" "Interfaces")
    (property "Val" "100n")
    (property "Voltage" "50V")
    (property "ki_description" " ")
    (attr smd)
    (fp_text reference "C54" (at -3.0586 -0.3254) (layer "F.SilkS")
        (effects (font (size 0.7 0.7) (thickness 0.15)) (justify right bottom))
    )
    (fp_text value "C_100n_0402" (at 0 1.4) (layer "F.Fab")
        (effects (font (size 0.7 0.7) (thickness 0.15)) (justify right bottom))
    )
    (fp_text user "Author: Antmicro" (at -0.932 4.17) (layer "F.Fab") hide
        (effects (font (size 0.7 0.7) (thickness 0.15)) (justify right bottom))
    )
    (fp_text user "License: Apache-2.0" (at -0.932 5.17) (layer "F.Fab") hide
        (effects (font (size 0.7 0.7) (thickness 0.15)) (justify right bottom))
    )
    (fp_text user "${REFERENCE}" (at -0.932 3.168) (layer "F.Fab") hide
        (effects (font (size 0.7 0.7) (thickness 0.15)) (justify right bottom))
    )
    (fp_rect (start -0.94 -0.47) (end 0.94 0.47)
      (stroke (width 0.05) (type solid)) (fill none) (layer "F.CrtYd"))
    (fp_rect (start -0.499 -0.249) (end 0.499 0.249)
      (stroke (width 0.15) (type solid)) (fill none) (layer "F.Fab"))
    (pad "1" smd roundrect (at -0.484 0 180) (size 0.59 0.64) (layers "F.Cu" "F.Paste" "F.Mask") (roundrect_rratio 0.25)
      (net 11 "GND") (pintype "passive"))
    (pad "2" smd roundrect (at 0.484 0 180) (size 0.59 0.64) (layers "F.Cu" "F.Paste" "F.Mask") (roundrect_rratio 0.25)
      (net 27 "/Interfaces/VBus_Slave") (pintype "passive"))
  )

  (footprint "scalenode-cm4-baseboard-footprints:C_0402_1005Metric" (layer "F.Cu")
    (at 168.6438 71.1906 180)
    (descr "Capacitor SMD 0402")
    (tags "capacitor SMD 0402")
    (property "Author" "Antmicro")
    (property "Dielectric" "")
    (property "License" "Apache-2.0")
    (property "MPN" "C1005X6S1A105K050BC")
    (property "Manufacturer" "TDK")
    (property "Sheetfile" "interfaces.kicad_sch")
    (property "Sheetname" "Interfaces")
    (property "Val" "1u")
    (property "Voltage" "")
    (property "ki_description" " ")
    (attr smd)
    (fp_text reference "C53" (at -3.0562 -0.3594) (layer "F.SilkS")
        (effects (font (size 0.7 0.7) (thickness 0.15)) (justify right bottom))
    )
    (fp_text value "C_1u_0402" (at 0 1.4) (layer "F.Fab")
        (effects (font (size 0.7 0.7) (thickness 0.15)) (justify right bottom))
    )
    (fp_text user "${REFERENCE}" (at -0.932 3.168) (layer "F.Fab") hide
        (effects (font (size 0.7 0.7) (thickness 0.15)) (justify right bottom))
    )
    (fp_text user "License: Apache-2.0" (at -0.932 5.17) (layer "F.Fab") hide
        (effects (font (size 0.7 0.7) (thickness 0.15)) (justify right bottom))
    )
    (fp_text user "Author: Antmicro" (at -0.932 4.17) (layer "F.Fab") hide
        (effects (font (size 0.7 0.7) (thickness 0.15)) (justify right bottom))
    )
    (fp_rect (start -0.94 -0.47) (end 0.94 0.47)
      (stroke (width 0.05) (type solid)) (fill none) (layer "F.CrtYd"))
    (fp_rect (start -0.499 -0.249) (end 0.499 0.249)
      (stroke (width 0.15) (type solid)) (fill none) (layer "F.Fab"))
    (pad "1" smd roundrect (at -0.484 0 180) (size 0.59 0.64) (layers "F.Cu" "F.Paste" "F.Mask") (roundrect_rratio 0.25)
      (net 11 "GND") (pintype "passive"))
    (pad "2" smd roundrect (at 0.484 0 180) (size 0.59 0.64) (layers "F.Cu" "F.Paste" "F.Mask") (roundrect_rratio 0.25)
      (net 27 "/Interfaces/VBus_Slave") (pintype "passive"))
  )

  (footprint "scalenode-cm4-baseboard-footprints:R_0402_1005Metric" (layer "F.Cu")
    (at 164.13456 74.33004 180)
    (descr "Resistor SMD 0402")
    (tags "resistor SMD 0402")
    (property "Author" "Antmicro")
    (property "License" "Apache-2.0")
    (property "MPN" "CR0402-FX-22R0GLF")
    (property "Manufacturer" "Bourns")
    (property "Sheetfile" "interfaces.kicad_sch")
    (property "Sheetname" "Interfaces")
    (property "Tolerance" "1%")
    (property "Val" "22R")
    (property "ki_description" "22R resistor in 0402 package with 1% tolerance")
    (attr smd)
    (fp_text reference "R59" (at 1.03456 -1.44496 180) (layer "F.SilkS")
        (effects (font (size 0.7 0.7) (thickness 0.15)) (justify left bottom))
    )
    (fp_text value "R_22R_0402" (at 0 1.4 180) (layer "F.Fab")
        (effects (font (size 0.7 0.7) (thickness 0.15)) (justify left bottom))
    )
    (fp_text user "Author: Antmicro" (at -0.95 4.169 180) (layer "F.Fab") hide
        (effects (font (size 0.7 0.7) (thickness 0.15)) (justify left bottom))
    )
    (fp_text user "${REFERENCE}" (at -0.95 3.168 180) (layer "F.Fab") hide
        (effects (font (size 0.7 0.7) (thickness 0.15)) (justify left bottom))
    )
    (fp_text user "License: Apache-2.0" (at -0.95 5.169 180) (layer "F.Fab") hide
        (effects (font (size 0.7 0.7) (thickness 0.15)) (justify left bottom))
    )
    (fp_rect (start -0.95 -0.48) (end 0.95 0.48)
      (stroke (width 0.05) (type solid)) (fill none) (layer "F.CrtYd"))
    (fp_rect (start -0.5 -0.25) (end 0.5 0.25)
      (stroke (width 0.15) (type solid)) (fill none) (layer "F.Fab"))
    (pad "1" smd roundrect (at -0.485 0 180) (size 0.59 0.64) (layers "F.Cu" "F.Paste" "F.Mask") (roundrect_rratio 0.25)
      (net 251 "/Interfaces/FTDI_USB_P") (pintype "passive"))
    (pad "2" smd roundrect (at 0.485 0 180) (size 0.59 0.64) (layers "F.Cu" "F.Paste" "F.Mask") (roundrect_rratio 0.25)
      (net 267 "Net-(U6-USBDP)") (pintype "passive"))
  )

  (footprint "scalenode-cm4-baseboard-footprints:R_0402_1005Metric" (layer "F.Cu")
    (at 166.26456 74.33512)
    (descr "Resistor SMD 0402")
    (tags "resistor SMD 0402")
    (property "Author" "Antmicro")
    (property "License" "Apache-2.0")
    (property "MPN" "CR0402-FX-22R0GLF")
    (property "Manufacturer" "Bourns")
    (property "Sheetfile" "interfaces.kicad_sch")
    (property "Sheetname" "Interfaces")
    (property "Tolerance" "1%")
    (property "Val" "22R")
    (property "ki_description" "22R resistor in 0402 package with 1% tolerance")
    (attr smd)
    (fp_text reference "R58" (at -1.11456 1.43988) (layer "F.SilkS")
        (effects (font (size 0.7 0.7) (thickness 0.15)) (justify left bottom))
    )
    (fp_text value "R_22R_0402" (at 0 1.4) (layer "F.Fab")
        (effects (font (size 0.7 0.7) (thickness 0.15)) (justify left bottom))
    )
    (fp_text user "License: Apache-2.0" (at -0.95 5.169) (layer "F.Fab") hide
        (effects (font (size 0.7 0.7) (thickness 0.15)) (justify left bottom))
    )
    (fp_text user "Author: Antmicro" (at -0.95 4.169) (layer "F.Fab") hide
        (effects (font (size 0.7 0.7) (thickness 0.15)) (justify left bottom))
    )
    (fp_text user "${REFERENCE}" (at -0.95 3.168) (layer "F.Fab") hide
        (effects (font (size 0.7 0.7) (thickness 0.15)) (justify left bottom))
    )
    (fp_rect (start -0.95 -0.48) (end 0.95 0.48)
      (stroke (width 0.05) (type solid)) (fill none) (layer "F.CrtYd"))
    (fp_rect (start -0.5 -0.25) (end 0.5 0.25)
      (stroke (width 0.15) (type solid)) (fill none) (layer "F.Fab"))
    (pad "1" smd roundrect (at -0.485 0) (size 0.59 0.64) (layers "F.Cu" "F.Paste" "F.Mask") (roundrect_rratio 0.25)
      (net 249 "/Interfaces/FTDI_USB_N") (pintype "passive"))
    (pad "2" smd roundrect (at 0.485 0) (size 0.59 0.64) (layers "F.Cu" "F.Paste" "F.Mask") (roundrect_rratio 0.25)
      (net 266 "Net-(U6-USBDM)") (pintype "passive"))
  )

  (footprint "scalenode-cm4-baseboard-footprints:R_0402_1005Metric" (layer "F.Cu")
    (at 158.89224 71.05344 180)
    (descr "Resistor SMD 0402")
    (tags "resistor SMD 0402")
    (property "Author" "Antmicro")
    (property "License" "Apache-2.0")
    (property "MPN" "CR0402-FX-2200GLF")
    (property "Manufacturer" "Bourns")
    (property "Sheetfile" "interfaces.kicad_sch")
    (property "Sheetname" "Interfaces")
    (property "Tolerance" "1%")
    (property "Val" "220R")
    (property "ki_description" "220R resistor in 0402 package with 1% tolerance")
    (attr smd)
    (fp_text reference "R60" (at 1.09224 0.62844 180) (layer "F.SilkS")
        (effects (font (size 0.7 0.7) (thickness 0.15)) (justify left bottom))
    )
    (fp_text value "R_220R_0402" (at 0 1.4 180) (layer "F.Fab")
        (effects (font (size 0.7 0.7) (thickness 0.15)) (justify left bottom))
    )
    (fp_text user "License: Apache-2.0" (at -0.95 5.169 180) (layer "F.Fab") hide
        (effects (font (size 0.7 0.7) (thickness 0.15)) (justify left bottom))
    )
    (fp_text user "${REFERENCE}" (at -0.95 3.168 180) (layer "F.Fab") hide
        (effects (font (size 0.7 0.7) (thickness 0.15)) (justify left bottom))
    )
    (fp_text user "Author: Antmicro" (at -0.95 4.169 180) (layer "F.Fab") hide
        (effects (font (size 0.7 0.7) (thickness 0.15)) (justify left bottom))
    )
    (fp_rect (start -0.95 -0.48) (end 0.95 0.48)
      (stroke (width 0.05) (type solid)) (fill none) (layer "F.CrtYd"))
    (fp_rect (start -0.5 -0.25) (end 0.5 0.25)
      (stroke (width 0.15) (type solid)) (fill none) (layer "F.Fab"))
    (pad "1" smd roundrect (at -0.485 0 180) (size 0.59 0.64) (layers "F.Cu" "F.Paste" "F.Mask") (roundrect_rratio 0.25)
      (net 268 "Net-(U6-TXD)") (pintype "passive"))
    (pad "2" smd roundrect (at 0.485 0 180) (size 0.59 0.64) (layers "F.Cu" "F.Paste" "F.Mask") (roundrect_rratio 0.25)
      (net 241 "RPi_RXD") (pintype "passive"))
  )

  (footprint "scalenode-cm4-baseboard-footprints:R_0402_1005Metric" (layer "F.Cu")
    (at 158.37916 71.5602 90)
    (descr "Resistor SMD 0402")
    (tags "resistor SMD 0402")
    (property "Author" "Antmicro")
    (property "DNP" "DNP")
    (property "License" "Apache-2.0")
    (property "MPN" "CR0402-FX-2200GLF")
    (property "Manufacturer" "Bourns")
    (property "Sheetfile" "interfaces.kicad_sch")
    (property "Sheetname" "Interfaces")
    (property "Tolerance" "1%")
    (property "Val" "220R")
    (property "dnp" "")
    (property "exclude_from_bom" "")
    (property "ki_description" "220R resistor in 0402 package with 1% tolerance")
    (attr exclude_from_pos_files exclude_from_bom)
    (fp_text reference "R61" (at -1.0648 -0.62916 90) (layer "F.SilkS")
        (effects (font (size 0.7 0.7) (thickness 0.15)) (justify left bottom))
    )
    (fp_text value "R_220R_0402" (at 0 1.4 90) (layer "F.Fab")
        (effects (font (size 0.7 0.7) (thickness 0.15)) (justify left bottom))
    )
    (fp_text user "License: Apache-2.0" (at -0.95 5.169 90) (layer "F.Fab") hide
        (effects (font (size 0.7 0.7) (thickness 0.15)) (justify left bottom))
    )
    (fp_text user "${REFERENCE}" (at -0.95 3.168 90) (layer "F.Fab") hide
        (effects (font (size 0.7 0.7) (thickness 0.15)) (justify left bottom))
    )
    (fp_text user "Author: Antmicro" (at -0.95 4.169 90) (layer "F.Fab") hide
        (effects (font (size 0.7 0.7) (thickness 0.15)) (justify left bottom))
    )
    (fp_rect (start -0.95 -0.48) (end 0.95 0.48)
      (stroke (width 0.05) (type solid)) (fill none) (layer "F.CrtYd"))
    (fp_rect (start -0.5 -0.25) (end 0.5 0.25)
      (stroke (width 0.15) (type solid)) (fill none) (layer "F.Fab"))
    (pad "1" smd roundrect (at -0.485 0 90) (size 0.59 0.64) (layers "F.Cu" "F.Paste" "F.Mask") (roundrect_rratio 0.25)
      (net 238 "Adapter_TXD") (pintype "passive"))
    (pad "2" smd roundrect (at 0.485 0 90) (size 0.59 0.64) (layers "F.Cu" "F.Paste" "F.Mask") (roundrect_rratio 0.25)
      (net 241 "RPi_RXD") (pintype "passive"))
  )

  (footprint "scalenode-cm4-baseboard-footprints:R_0402_1005Metric" (layer "F.Cu")
    (at 155.70104 71.0708)
    (descr "Resistor SMD 0402")
    (tags "resistor SMD 0402")
    (property "Author" "Antmicro")
    (property "License" "Apache-2.0")
    (property "MPN" "CR0402-FX-2200GLF")
    (property "Manufacturer" "Bourns")
    (property "Sheetfile" "interfaces.kicad_sch")
    (property "Sheetname" "Interfaces")
    (property "Tolerance" "1%")
    (property "Val" "220R")
    (property "ki_description" "220R resistor in 0402 package with 1% tolerance")
    (attr smd)
    (fp_text reference "R56" (at -1.10104 -0.6208) (layer "F.SilkS")
        (effects (font (size 0.7 0.7) (thickness 0.15)) (justify left bottom))
    )
    (fp_text value "R_220R_0402" (at 0 1.4) (layer "F.Fab")
        (effects (font (size 0.7 0.7) (thickness 0.15)) (justify left bottom))
    )
    (fp_text user "License: Apache-2.0" (at -0.95 5.169) (layer "F.Fab") hide
        (effects (font (size 0.7 0.7) (thickness 0.15)) (justify left bottom))
    )
    (fp_text user "${REFERENCE}" (at -0.95 3.168) (layer "F.Fab") hide
        (effects (font (size 0.7 0.7) (thickness 0.15)) (justify left bottom))
    )
    (fp_text user "Author: Antmicro" (at -0.95 4.169) (layer "F.Fab") hide
        (effects (font (size 0.7 0.7) (thickness 0.15)) (justify left bottom))
    )
    (fp_rect (start -0.95 -0.48) (end 0.95 0.48)
      (stroke (width 0.05) (type solid)) (fill none) (layer "F.CrtYd"))
    (fp_rect (start -0.5 -0.25) (end 0.5 0.25)
      (stroke (width 0.15) (type solid)) (fill none) (layer "F.Fab"))
    (pad "1" smd roundrect (at -0.485 0) (size 0.59 0.64) (layers "F.Cu" "F.Paste" "F.Mask") (roundrect_rratio 0.25)
      (net 242 "RPi_TXD") (pintype "passive"))
    (pad "2" smd roundrect (at 0.485 0) (size 0.59 0.64) (layers "F.Cu" "F.Paste" "F.Mask") (roundrect_rratio 0.25)
      (net 265 "Net-(U6-RXD)") (pintype "passive"))
  )

  (footprint "scalenode-cm4-baseboard-footprints:R_0402_1005Metric" (layer "F.Cu")
    (at 155.18288 71.5801 -90)
    (descr "Resistor SMD 0402")
    (tags "resistor SMD 0402")
    (property "Author" "Antmicro")
    (property "DNP" "DNP")
    (property "License" "Apache-2.0")
    (property "MPN" "CR0402-FX-2200GLF")
    (property "Manufacturer" "Bourns")
    (property "Sheetfile" "interfaces.kicad_sch")
    (property "Sheetname" "Interfaces")
    (property "Tolerance" "1%")
    (property "Val" "220R")
    (property "dnp" "")
    (property "exclude_from_bom" "")
    (property "ki_description" "220R resistor in 0402 package with 1% tolerance")
    (attr exclude_from_pos_files exclude_from_bom)
    (fp_text reference "R57" (at 0.9949 0.60788 90) (layer "F.SilkS")
        (effects (font (size 0.7 0.7) (thickness 0.15)) (justify left bottom))
    )
    (fp_text value "R_220R_0402" (at 0 1.4 -90) (layer "F.Fab")
        (effects (font (size 0.7 0.7) (thickness 0.15)) (justify left bottom))
    )
    (fp_text user "${REFERENCE}" (at -0.95 3.168 -90) (layer "F.Fab") hide
        (effects (font (size 0.7 0.7) (thickness 0.15)) (justify left bottom))
    )
    (fp_text user "License: Apache-2.0" (at -0.95 5.169 -90) (layer "F.Fab") hide
        (effects (font (size 0.7 0.7) (thickness 0.15)) (justify left bottom))
    )
    (fp_text user "Author: Antmicro" (at -0.95 4.169 -90) (layer "F.Fab") hide
        (effects (font (size 0.7 0.7) (thickness 0.15)) (justify left bottom))
    )
    (fp_rect (start -0.95 -0.48) (end 0.95 0.48)
      (stroke (width 0.05) (type solid)) (fill none) (layer "F.CrtYd"))
    (fp_rect (start -0.5 -0.25) (end 0.5 0.25)
      (stroke (width 0.15) (type solid)) (fill none) (layer "F.Fab"))
    (pad "1" smd roundrect (at -0.485 0 270) (size 0.59 0.64) (layers "F.Cu" "F.Paste" "F.Mask") (roundrect_rratio 0.25)
      (net 242 "RPi_TXD") (pintype "passive"))
    (pad "2" smd roundrect (at 0.485 0 270) (size 0.59 0.64) (layers "F.Cu" "F.Paste" "F.Mask") (roundrect_rratio 0.25)
      (net 237 "Adapter_RXD") (pintype "passive"))
  )

  (footprint "scalenode-cm4-baseboard-footprints:SOT-23-3" (layer "F.Cu")
    (at 151.892 59.405 90)
    (property "Author" "Antmicro")
    (property "License" "Apache-2.0")
    (property "MPN" "BSS138-7-F")
    (property "Manufacturer" "Diodes Incorporated")
    (property "Sheetfile" "compute-module.kicad_sch")
    (property "Sheetname" "Compute module")
    (attr smd)
    (fp_text reference "Q6" (at 1.205 -2.117 180) (layer "F.SilkS")
        (effects (font (size 0.7 0.7) (thickness 0.15)) (justify left bottom))
    )
    (fp_text value "BSS138-7-F" (at -6.67 2.483 90) (layer "F.Fab")
        (effects (font (size 0.7 0.7) (thickness 0.15)) (justify left bottom))
    )
    (fp_text user "License: Apache-2.0" (at -1.8 6.8 90) (layer "F.Fab") hide
        (effects (font (size 0.7 0.7) (thickness 0.15)) (justify left bottom))
    )
    (fp_text user "Author: Antmicro" (at -1.837 5.3 90) (layer "F.Fab") hide
        (effects (font (size 0.7 0.7) (thickness 0.15)) (justify left bottom))
    )
    (fp_text user "${REFERENCE}" (at -1.837 4 90) (layer "F.Fab") hide
        (effects (font (size 0.7 0.7) (thickness 0.15)) (justify left bottom))
    )
    (fp_line (start -1.45 -1.35) (end -0.85 -1.35)
      (stroke (width 0.15) (type solid)) (layer "F.SilkS"))
    (fp_line (start -0.85 -1.35) (end -0.7 -1.5)
      (stroke (width 0.15) (type solid)) (layer "F.SilkS"))
    (fp_line (start -0.7 1.5) (end -0.7 1.35)
      (stroke (width 0.15) (type solid)) (layer "F.SilkS"))
    (fp_line (start 0.7 -1.5) (end -0.7 -1.5)
      (stroke (width 0.15) (type solid)) (layer "F.SilkS"))
    (fp_line (start 0.7 -0.4) (end 0.7 -1.5)
      (stroke (width 0.15) (type solid)) (layer "F.SilkS"))
    (fp_line (start 0.7 0.4) (end 0.7 1.5)
      (stroke (width 0.15) (type solid)) (layer "F.SilkS"))
    (fp_line (start 0.7 1.5) (end -0.7 1.5)
      (stroke (width 0.15) (type solid)) (layer "F.SilkS"))
    (fp_line (start -1.75 -0.5) (end -1.75 -1.4)
      (stroke (width 0.05) (type solid)) (layer "F.CrtYd"))
    (fp_line (start -1.75 0.5) (end -0.85 0.5)
      (stroke (width 0.05) (type solid)) (layer "F.CrtYd"))
    (fp_line (start -1.75 1.4) (end -1.75 0.5)
      (stroke (width 0.05) (type solid)) (layer "F.CrtYd"))
    (fp_line (start -0.9 -1.6) (end -0.9 -1.4)
      (stroke (width 0.05) (type solid)) (layer "F.CrtYd"))
    (fp_line (start -0.9 -1.6) (end 0.825 -1.6)
      (stroke (width 0.05) (type solid)) (layer "F.CrtYd"))
    (fp_line (start -0.9 -1.4) (end -1.75 -1.4)
      (stroke (width 0.05) (type solid)) (layer "F.CrtYd"))
    (fp_line (start -0.85 -0.5) (end -1.75 -0.5)
      (stroke (width 0.05) (type solid)) (layer "F.CrtYd"))
    (fp_line (start -0.85 0.5) (end -0.85 -0.5)
      (stroke (width 0.05) (type solid)) (layer "F.CrtYd"))
    (fp_line (start -0.85 1.4) (end -1.75 1.4)
      (stroke (width 0.05) (type solid)) (layer "F.CrtYd"))
    (fp_line (start -0.85 1.65) (end -0.85 1.4)
      (stroke (width 0.05) (type solid)) (layer "F.CrtYd"))
    (fp_line (start 0.825 -1.6) (end 0.825 -0.45)
      (stroke (width 0.05) (type solid)) (layer "F.CrtYd"))
    (fp_line (start 0.825 -0.45) (end 1.75 -0.45)
      (stroke (width 0.05) (type solid)) (layer "F.CrtYd"))
    (fp_line (start 0.85 0.45) (end 0.85 1.65)
      (stroke (width 0.05) (type solid)) (layer "F.CrtYd"))
    (fp_line (start 0.85 1.65) (end -0.85 1.65)
      (stroke (width 0.05) (type solid)) (layer "F.CrtYd"))
    (fp_line (start 1.75 -0.45) (end 1.75 0.45)
      (stroke (width 0.05) (type solid)) (layer "F.CrtYd"))
    (fp_line (start 1.75 0.45) (end 0.85 0.45)
      (stroke (width 0.05) (type solid)) (layer "F.CrtYd"))
    (fp_line (start -0.712 -1.325) (end -0.712 1.523)
      (stroke (width 0.15) (type solid)) (layer "F.Fab"))
    (fp_line (start -0.712 1.519) (end 0.688 1.519)
      (stroke (width 0.15) (type solid)) (layer "F.Fab"))
    (fp_line (start -0.437 -1.526) (end -0.712 -1.325)
      (stroke (width 0.15) (type solid)) (layer "F.Fab"))
    (fp_line (start -0.437 -1.526) (end 0.688 -1.526)
      (stroke (width 0.15) (type solid)) (layer "F.Fab"))
    (fp_line (start 0.688 1.519) (end 0.688 -1.52)
      (stroke (width 0.15) (type solid)) (layer "F.Fab"))
    (pad "1" smd roundrect (at -1.1 -0.951 90) (size 1 0.6) (layers "F.Cu" "F.Paste" "F.Mask") (roundrect_rratio 0.15)
      (net 246 "Net-(Q6-G)") (pinfunction "G") (pintype "bidirectional"))
    (pad "2" smd roundrect (at -1.1 0.949 90) (size 1 0.6) (layers "F.Cu" "F.Paste" "F.Mask") (roundrect_rratio 0.15)
      (net 11 "GND") (pinfunction "S") (pintype "bidirectional"))
    (pad "3" smd roundrect (at 1.1 -0.0005 90) (size 1 0.6) (layers "F.Cu" "F.Paste" "F.Mask") (roundrect_rratio 0.15)
      (net 243 "/Compute module/nRPi_BOOT") (pinfunction "D") (pintype "bidirectional"))
  )

  (footprint "scalenode-cm4-baseboard-footprints:R_0402_1005Metric" (layer "F.Cu")
    (at 175.808 89.377 90)
    (descr "Resistor SMD 0402")
    (tags "resistor SMD 0402")
    (property "Author" "Antmicro")
    (property "License" "Apache-2.0")
    (property "MPN" "CR0402-FX-22R0GLF")
    (property "Manufacturer" "Bourns")
    (property "Sheetfile" "interfaces.kicad_sch")
    (property "Sheetname" "Interfaces")
    (property "Tolerance" "1%")
    (property "Val" "22R")
    (property "ki_description" "22R resistor in 0402 package with 1% tolerance")
    (attr smd)
    (fp_text reference "R7" (at -0.398 -2.008 180) (layer "F.SilkS")
        (effects (font (size 0.7 0.7) (thickness 0.15)) (justify left bottom))
    )
    (fp_text value "R_22R_0402" (at 0 1.4 90) (layer "F.Fab")
        (effects (font (size 0.7 0.7) (thickness 0.15)) (justify left bottom))
    )
    (fp_text user "${REFERENCE}" (at -0.95 3.168 90) (layer "F.Fab") hide
        (effects (font (size 0.7 0.7) (thickness 0.15)) (justify left bottom))
    )
    (fp_text user "Author: Antmicro" (at -0.95 4.169 90) (layer "F.Fab") hide
        (effects (font (size 0.7 0.7) (thickness 0.15)) (justify left bottom))
    )
    (fp_text user "License: Apache-2.0" (at -0.95 5.169 90) (layer "F.Fab") hide
        (effects (font (size 0.7 0.7) (thickness 0.15)) (justify left bottom))
    )
    (fp_rect (start -0.95 -0.48) (end 0.95 0.48)
      (stroke (width 0.05) (type solid)) (fill none) (layer "F.CrtYd"))
    (fp_rect (start -0.5 -0.25) (end 0.5 0.25)
      (stroke (width 0.15) (type solid)) (fill none) (layer "F.Fab"))
    (pad "1" smd roundrect (at -0.485 0 90) (size 0.59 0.64) (layers "F.Cu" "F.Paste" "F.Mask") (roundrect_rratio 0.25)
      (net 98 "USB2_P") (pintype "passive"))
    (pad "2" smd roundrect (at 0.485 0 90) (size 0.59 0.64) (layers "F.Cu" "F.Paste" "F.Mask") (roundrect_rratio 0.25)
      (net 247 "Net-(U1-D+)") (pintype "passive"))
  )

  (footprint "scalenode-cm4-baseboard-footprints:R_0402_1005Metric" (layer "F.Cu")
    (at 176.951 89.377 90)
    (descr "Resistor SMD 0402")
    (tags "resistor SMD 0402")
    (property "Author" "Antmicro")
    (property "License" "Apache-2.0")
    (property "MPN" "CR0402-FX-22R0GLF")
    (property "Manufacturer" "Bourns")
    (property "Sheetfile" "interfaces.kicad_sch")
    (property "Sheetname" "Interfaces")
    (property "Tolerance" "1%")
    (property "Val" "22R")
    (property "ki_description" "22R resistor in 0402 package with 1% tolerance")
    (attr smd)
    (fp_text reference "R8" (at -0.373 0.499 180) (layer "F.SilkS")
        (effects (font (size 0.7 0.7) (thickness 0.15)) (justify left bottom))
    )
    (fp_text value "R_22R_0402" (at 0 1.4 90) (layer "F.Fab")
        (effects (font (size 0.7 0.7) (thickness 0.15)) (justify left bottom))
    )
    (fp_text user "Author: Antmicro" (at -0.95 4.169 90) (layer "F.Fab") hide
        (effects (font (size 0.7 0.7) (thickness 0.15)) (justify left bottom))
    )
    (fp_text user "License: Apache-2.0" (at -0.95 5.169 90) (layer "F.Fab") hide
        (effects (font (size 0.7 0.7) (thickness 0.15)) (justify left bottom))
    )
    (fp_text user "${REFERENCE}" (at -0.95 3.168 90) (layer "F.Fab") hide
        (effects (font (size 0.7 0.7) (thickness 0.15)) (justify left bottom))
    )
    (fp_rect (start -0.95 -0.48) (end 0.95 0.48)
      (stroke (width 0.05) (type solid)) (fill none) (layer "F.CrtYd"))
    (fp_rect (start -0.5 -0.25) (end 0.5 0.25)
      (stroke (width 0.15) (type solid)) (fill none) (layer "F.Fab"))
    (pad "1" smd roundrect (at -0.485 0 90) (size 0.59 0.64) (layers "F.Cu" "F.Paste" "F.Mask") (roundrect_rratio 0.25)
      (net 97 "USB2_N") (pintype "passive"))
    (pad "2" smd roundrect (at 0.485 0 90) (size 0.59 0.64) (layers "F.Cu" "F.Paste" "F.Mask") (roundrect_rratio 0.25)
      (net 248 "Net-(U1-D-)") (pintype "passive"))
  )

  (footprint "scalenode-cm4-baseboard-footprints:C_0402_1005Metric" (layer "F.Cu")
    (at 168.6438 72.4606)
    (descr "Capacitor SMD 0402")
    (tags "capacitor SMD 0402")
    (property "Author" "Antmicro")
    (property "Dielectric" "X5R")
    (property "License" "Apache-2.0")
    (property "MPN" "GRM155R61H104KE14D")
    (property "Manufacturer" "Murata")
    (property "Sheetfile" "interfaces.kicad_sch")
    (property "Sheetname" "Interfaces")
    (property "Val" "100n")
    (property "Voltage" "50V")
    (property "ki_description" " ")
    (attr smd)
    (fp_text reference "C55" (at 0.9312 0.4394) (layer "F.SilkS")
        (effects (font (size 0.7 0.7) (thickness 0.15)) (justify left bottom))
    )
    (fp_text value "C_100n_0402" (at 0 1.4) (layer "F.Fab")
        (effects (font (size 0.7 0.7) (thickness 0.15)) (justify left bottom))
    )
    (fp_text user "Author: Antmicro" (at -0.932 4.17) (layer "F.Fab") hide
        (effects (font (size 0.7 0.7) (thickness 0.15)) (justify left bottom))
    )
    (fp_text user "${REFERENCE}" (at -0.932 3.168) (layer "F.Fab") hide
        (effects (font (size 0.7 0.7) (thickness 0.15)) (justify left bottom))
    )
    (fp_text user "License: Apache-2.0" (at -0.932 5.17) (layer "F.Fab") hide
        (effects (font (size 0.7 0.7) (thickness 0.15)) (justify left bottom))
    )
    (fp_rect (start -0.94 -0.47) (end 0.94 0.47)
      (stroke (width 0.05) (type solid)) (fill none) (layer "F.CrtYd"))
    (fp_rect (start -0.499 -0.249) (end 0.499 0.249)
      (stroke (width 0.15) (type solid)) (fill none) (layer "F.Fab"))
    (pad "1" smd roundrect (at -0.484 0) (size 0.59 0.64) (layers "F.Cu" "F.Paste" "F.Mask") (roundrect_rratio 0.25)
      (net 23 "Net-(U6-3.3VOUT)") (pintype "passive"))
    (pad "2" smd roundrect (at 0.484 0) (size 0.59 0.64) (layers "F.Cu" "F.Paste" "F.Mask") (roundrect_rratio 0.25)
      (net 11 "GND") (pintype "passive"))
  )

  (footprint "scalenode-cm4-baseboard-footprints:R_0402_1005Metric" (layer "F.Cu")
    (at 158.93 74.66 90)
    (descr "Resistor SMD 0402")
    (tags "resistor SMD 0402")
    (property "Author" "Antmicro")
    (property "License" "Apache-2.0")
    (property "MPN" "CR0402-FX-1101GLF")
    (property "Manufacturer" "Bourns")
    (property "Sheetfile" "interfaces.kicad_sch")
    (property "Sheetname" "Interfaces")
    (property "Tolerance" "1%")
    (property "Val" "1k1")
    (property "ki_description" "1k1 resistor in 0402 package with 1% tolerance")
    (attr smd)
    (fp_text reference "R16" (at -1.05 -0.63 270) (layer "F.SilkS")
        (effects (font (size 0.7 0.7) (thickness 0.15)) (justify left bottom))
    )
    (fp_text value "R_1k1_0402" (at 0 1.4 90) (layer "F.Fab")
        (effects (font (size 0.7 0.7) (thickness 0.15)) (justify left bottom))
    )
    (fp_text user "Author: Antmicro" (at -0.95 4.169 90) (layer "F.Fab") hide
        (effects (font (size 0.7 0.7) (thickness 0.15)) (justify left bottom))
    )
    (fp_text user "License: Apache-2.0" (at -0.95 5.169 90) (layer "F.Fab") hide
        (effects (font (size 0.7 0.7) (thickness 0.15)) (justify left bottom))
    )
    (fp_text user "${REFERENCE}" (at -0.95 3.168 90) (layer "F.Fab") hide
        (effects (font (size 0.7 0.7) (thickness 0.15)) (justify left bottom))
    )
    (fp_rect (start -0.95 -0.48) (end 0.95 0.48)
      (stroke (width 0.05) (type solid)) (fill none) (layer "F.CrtYd"))
    (fp_rect (start -0.5 -0.25) (end 0.5 0.25)
      (stroke (width 0.15) (type solid)) (fill none) (layer "F.Fab"))
    (pad "1" smd roundrect (at -0.485 0 90) (size 0.59 0.64) (layers "F.Cu" "F.Paste" "F.Mask") (roundrect_rratio 0.25)
      (net 95 "USBOTG_ID") (pintype "passive"))
    (pad "2" smd roundrect (at 0.485 0 90) (size 0.59 0.64) (layers "F.Cu" "F.Paste" "F.Mask") (roundrect_rratio 0.25)
      (net 244 "PROG_MODE") (pintype "passive"))
  )

  (footprint "scalenode-cm4-baseboard-footprints:MSOP-10_W3mm" (layer "F.Cu")
    (at 161.4 77.8 -90)
    (property "Author" "Antmicro")
    (property "License" "Apache-2.0")
    (property "MPN" "TS3USB30EDGSR")
    (property "Manufacturer" "Texas Instruments")
    (property "Sheetfile" "interfaces.kicad_sch")
    (property "Sheetname" "Interfaces")
    (attr smd)
    (fp_text reference "U5" (at 0 -4.401 -90) (layer "F.SilkS")
        (effects (font (size 0.7 0.7) (thickness 0.15)) (justify left bottom))
    )
    (fp_text value "TS3USB30EDGSR" (at 0 4.799 -90) (layer "F.Fab")
        (effects (font (size 0.7 0.7) (thickness 0.15)) (justify left bottom))
    )
    (fp_text user "License: Apache-2.0" (at -2.351 7.999 -90) (layer "F.Fab") hide
        (effects (font (size 0.7 0.7) (thickness 0.15)) (justify left bottom))
    )
    (fp_text user "${REFERENCE}" (at -2.351 9.198 -90) (layer "F.Fab") hide
        (effects (font (size 0.7 0.7) (thickness 0.15)) (justify left bottom))
    )
    (fp_text user "Author: Antmicro" (at -2.351 6.799 -90) (layer "F.Fab") hide
        (effects (font (size 0.7 0.7) (thickness 0.15)) (justify left bottom))
    )
    (fp_text user "REF**" (at 0 0 -90) (layer "F.Fab") hide
        (effects (font (size 0.5 0.5) (thickness 0.05)))
    )
    (fp_line (start -1.601 -1.601) (end -1.301 -1.601)
      (stroke (width 0.15) (type solid)) (layer "F.SilkS"))
    (fp_line (start -1.601 -1.301) (end -1.601 -1.601)
      (stroke (width 0.15) (type solid)) (layer "F.SilkS"))
    (fp_line (start -1.601 1.3) (end -1.301 1.6)
      (stroke (width 0.15) (type solid)) (layer "F.SilkS"))
    (fp_line (start -1.301 1.6) (end -1.301 2.797)
      (stroke (width 0.15) (type solid)) (layer "F.SilkS"))
    (fp_line (start 1.3 -1.601) (end 1.6 -1.601)
      (stroke (width 0.15) (type solid)) (layer "F.SilkS"))
    (fp_line (start 1.6 -1.601) (end 1.6 -1.301)
      (stroke (width 0.15) (type solid)) (layer "F.SilkS"))
    (fp_line (start 1.6 1.3) (end 1.6 1.6)
      (stroke (width 0.15) (type solid)) (layer "F.SilkS"))
    (fp_line (start 1.6 1.6) (end 1.3 1.6)
      (stroke (width 0.15) (type solid)) (layer "F.SilkS"))
    (fp_circle (center -1.6 1.7) (end -1.55 1.7)
      (stroke (width 0.15) (type solid)) (fill solid) (layer "F.SilkS"))
    (fp_line (start -1.75 -3.19) (end 1.71 -3.19)
      (stroke (width 0.05) (type solid)) (layer "F.CrtYd"))
    (fp_line (start -1.75 3.18) (end -1.75 -3.19)
      (stroke (width 0.05) (type solid)) (layer "F.CrtYd"))
    (fp_line (start -1.75 3.18) (end 1.71 3.18)
      (stroke (width 0.05) (type solid)) (layer "F.CrtYd"))
    (fp_line (start 1.71 -3.19) (end 1.71 3.18)
      (stroke (width 0.05) (type solid)) (layer "F.CrtYd"))
    (fp_line (start -1.45 -1.45) (end -1.45 1.1)
      (stroke (width 0.15) (type solid)) (layer "F.Fab"))
    (fp_line (start -1.45 -1.45) (end 1.449 -1.45)
      (stroke (width 0.15) (type solid)) (layer "F.Fab"))
    (fp_line (start -1.45 1.1) (end -1.101 1.449)
      (stroke (width 0.15) (type solid)) (layer "F.Fab"))
    (fp_line (start -1.101 1.449) (end 1.449 1.449)
      (stroke (width 0.15) (type solid)) (layer "F.Fab"))
    (fp_line (start 1.449 -1.45) (end 1.449 1.449)
      (stroke (width 0.15) (type solid)) (layer "F.Fab"))
    (pad "1" smd rect (at -1 2.201 270) (size 0.3 1.45) (layers "F.Cu" "F.Paste" "F.Mask")
      (net 95 "USBOTG_ID") (pinfunction "S") (pintype "input") (solder_mask_margin 0.05))
    (pad "2" smd rect (at -0.5 2.201 270) (size 0.3 1.45) (layers "F.Cu" "F.Paste" "F.Mask")
      (net 251 "/Interfaces/FTDI_USB_P") (pinfunction "D1+") (pintype "bidirectional") (solder_mask_margin 0.05))
    (pad "3" smd rect (at 0 2.201 270) (size 0.3 1.45) (layers "F.Cu" "F.Paste" "F.Mask")
      (net 25 "/Interfaces/RPi_USB_P") (pinfunction "D2+") (pintype "bidirectional") (solder_mask_margin 0.05))
    (pad "4" smd rect (at 0.496 2.201 270) (size 0.3 1.45) (layers "F.Cu" "F.Paste" "F.Mask")
      (net 236 "/Interfaces/CONN_USB_P") (pinfunction "D+") (pintype "bidirectional") (solder_mask_margin 0.05))
    (pad "5" smd rect (at 0.996 2.201 270) (size 0.3 1.45) (layers "F.Cu" "F.Paste" "F.Mask")
      (net 11 "GND") (pinfunction "GND") (pintype "power_in") (solder_mask_margin 0.05))
    (pad "6" smd rect (at 0.996 -2.202 270) (size 0.3 1.45) (layers "F.Cu" "F.Paste" "F.Mask")
      (net 235 "/Interfaces/CONN_USB_N") (pinfunction "D-") (pintype "bidirectional") (solder_mask_margin 0.05))
    (pad "7" smd rect (at 0.496 -2.202 270) (size 0.3 1.45) (layers "F.Cu" "F.Paste" "F.Mask")
      (net 24 "/Interfaces/RPi_USB_N") (pinfunction "D2-") (pintype "bidirectional") (solder_mask_margin 0.05))
    (pad "8" smd rect (at 0 -2.202 270) (size 0.3 1.45) (layers "F.Cu" "F.Paste" "F.Mask")
      (net 249 "/Interfaces/FTDI_USB_N") (pinfunction "D1-") (pintype "bidirectional") (solder_mask_margin 0.05))
    (pad "9" smd rect (at -0.5 -2.202 270) (size 0.3 1.45) (layers "F.Cu" "F.Paste" "F.Mask")
      (net 264 "Net-(U5-~{OE})") (pinfunction "~{OE}") (pintype "input") (solder_mask_margin 0.05))
    (pad "10" smd rect (at -1 -2.202 270) (size 0.3 1.45) (layers "F.Cu" "F.Paste" "F.Mask")
      (net 232 "3V3_RPi") (pinfunction "VCC") (pintype "power_in") (solder_mask_margin 0.05))
  )

  (footprint "scalenode-cm4-baseboard-footprints:USB-Micro-B_Receptacle_Molex_473460001" (layer "F.Cu")
    (at 77.05 87.373 -90)
    (descr "http://www.molex.com/pdm_docs/sd/473460001_sd.pdf")
    (property "Author" "Antmicro")
    (property "License" "Apache-2.0")
    (property "MPN" "473460001")
    (property "Manufacturer" "Molex")
    (property "Sheetfile" "interfaces.kicad_sch")
    (property "Sheetname" "Interfaces")
    (property "ki_description" "USB - micro B USB 2.0 Receptacle Connector 5 Position Surface Mount, Right Angle")
    (property "ki_keywords" "USB, MICRO, CONNECTOR, SMT, HORIZONTAL")
    (attr smd)
    (fp_text reference "J5" (at 5.202 1.8) (layer "F.SilkS")
        (effects (font (size 0.7 0.7) (thickness 0.15)) (justify left bottom))
    )
    (fp_text value "USB-Micro-B_Molex_473460001" (at -7.998 -0.05 -90) (layer "F.Fab")
        (effects (font (size 0.7 0.7) (thickness 0.15)) (justify left bottom))
    )
    (fp_text user "Author: Antmicro" (at -7.925 9.575 -90) (layer "F.Fab") hide
        (effects (font (size 0.7 0.7) (thickness 0.15)) (justify left bottom))
    )
    (fp_text user "License: Apache-2.0" (at -7.925 7.175 -90) (layer "F.Fab") hide
        (effects (font (size 0.7 0.7) (thickness 0.15)) (justify left bottom))
    )
    (fp_text user "${REFERENCE}" (at -7.925 5.975 -90) (layer "F.Fab") hide
        (effects (font (size 0.7 0.7) (thickness 0.15)) (justify left bottom))
    )
    (fp_line (start -4 -2.751) (end -4 -2.251)
      (stroke (width 0.15) (type solid)) (layer "F.SilkS"))
    (fp_line (start -4 -2.751) (end -3.5 -2.751)
      (stroke (width 0.15) (type solid)) (layer "F.SilkS"))
    (fp_line (start -4 2.698) (end -4 2.148)
      (stroke (width 0.15) (type solid)) (layer "F.SilkS"))
    (fp_line (start -4 2.698) (end -3.5 2.698)
      (stroke (width 0.15) (type solid)) (layer "F.SilkS"))
    (fp_line (start 3.999 -2.751) (end 3.499 -2.751)
      (stroke (width 0.15) (type solid)) (layer "F.SilkS"))
    (fp_line (start 3.999 -2.751) (end 3.999 -2.251)
      (stroke (width 0.15) (type solid)) (layer "F.SilkS"))
    (fp_line (start 3.999 2.698) (end 3.499 2.698)
      (stroke (width 0.15) (type solid)) (layer "F.SilkS"))
    (fp_line (start 3.999 2.698) (end 3.999 2.198)
      (stroke (width 0.15) (type solid)) (layer "F.SilkS"))
    (fp_circle (center -1.301 -3.601) (end -1.351 -3.601)
      (stroke (width 0.15) (type solid)) (fill solid) (layer "F.SilkS"))
    (fp_rect (start 4.236 2.946) (end -4.246 -3.23)
      (stroke (width 0.05) (type solid)) (fill none) (layer "F.CrtYd"))
    (fp_line (start -3.7745 -2.6995) (end -3.9755 -2.5005)
      (stroke (width 0.15) (type solid)) (layer "F.Fab"))
    (fp_rect (start 3.99 2.713) (end -3.992 -2.714)
      (stroke (width 0.15) (type solid)) (fill none) (layer "F.Fab"))
    (pad "1" smd rect (at -1.301 -2.376) (size 1.38 0.45) (layers "F.Cu" "F.Paste" "F.Mask")
      (net 27 "/Interfaces/VBus_Slave") (pinfunction "VBUS") (pintype "passive"))
    (pad "2" smd rect (at -0.652 -2.376) (size 1.38 0.45) (layers "F.Cu" "F.Paste" "F.Mask")
      (net 235 "/Interfaces/CONN_USB_N") (pinfunction "D-") (pintype "bidirectional"))
    (pad "3" smd rect (at -0.001 -2.376) (size 1.38 0.45) (layers "F.Cu" "F.Paste" "F.Mask")
      (net 236 "/Interfaces/CONN_USB_P") (pinfunction "D+") (pintype "bidirectional"))
    (pad "4" smd rect (at 0.652 -2.376) (size 1.38 0.45) (layers "F.Cu" "F.Paste" "F.Mask")
      (net 202 "unconnected-(J5-ID-Pad4)") (pinfunction "ID") (pintype "bidirectional+no_connect"))
    (pad "5" smd rect (at 1.3 -2.376) (size 1.38 0.45) (layers "F.Cu" "F.Paste" "F.Mask")
      (net 11 "GND") (pinfunction "GND") (pintype "power_in"))
    (pad "SH" smd rect (at -2.911 0.284) (size 1.9 2.375) (layers "F.Cu" "F.Paste" "F.Mask")
      (net 11 "GND") (pinfunction "SHIELD") (pintype "passive"))
    (pad "SH" smd rect (at -2.464 -2.016) (size 2.1 1.475) (layers "F.Cu" "F.Paste" "F.Mask")
      (net 11 "GND") (pinfunction "SHIELD") (pintype "passive"))
    (pad "SH" smd rect (at -0.836 0.284) (size 1.9 1.175) (layers "F.Cu" "F.Paste" "F.Mask")
      (net 11 "GND") (pinfunction "SHIELD") (pintype "passive"))
    (pad "SH" smd rect (at 0.836 0.284) (size 1.9 1.175) (layers "F.Cu" "F.Paste" "F.Mask")
      (net 11 "GND") (pinfunction "SHIELD") (pintype "passive"))
    (pad "SH" smd rect (at 2.463 -2.016) (size 2.1 1.475) (layers "F.Cu" "F.Paste" "F.Mask")
      (net 11 "GND") (pinfunction "SHIELD") (pintype "passive"))
    (pad "SH" smd rect (at 2.913 0.284) (size 1.9 2.375) (layers "F.Cu" "F.Paste" "F.Mask")
      (net 11 "GND") (pinfunction "SHIELD") (pintype "passive"))
  )

  (footprint "scalenode-cm4-baseboard-footprints:MP_Pad4.5mm_Drill2.2mm" (layer "F.Cu")
    (at 78.126 94.198)
    (property "Author" "Antmicro")
    (property "License" "Apache-2.0")
    (property "MPN" "")
    (property "Manufacturer" "")
    (property "Sheetfile" "expansion-connectors.kicad_sch")
    (property "Sheetname" "Expansion connectors")
    (property "exclude_from_bom" "")
    (property "ki_description" "Mechanical part")
    (property "ki_keywords" "MECHANICAL")
    (attr through_hole exclude_from_bom)
    (fp_text reference "MP1" (at 1.774 2.227) (layer "F.SilkS") hide
        (effects (font (size 0.7 0.7) (thickness 0.15)) (justify left bottom))
    )
    (fp_text value "MP_Pad4.5mm_Drill2.2mm" (at -0.153 -4.153) (layer "F.Fab")
        (effects (font (size 0.7 0.7) (thickness 0.15)) (justify left bottom))
    )
    (fp_text user "License: Apache-2.0" (at -0.178 8.425) (layer "F.Fab") hide
        (effects (font (size 0.7 0.7) (thickness 0.15)) (justify left bottom))
    )
    (fp_text user "Author: Antmicro" (at -0.178 7.225) (layer "F.Fab") hide
        (effects (font (size 0.7 0.7) (thickness 0.15)) (justify left bottom))
    )
    (fp_text user "${REFERENCE}" (at -0.178 6.025) (layer "F.Fab") hide
        (effects (font (size 0.7 0.7) (thickness 0.15)) (justify left bottom))
    )
    (pad "1" thru_hole circle (at 0 0) (size 4.5 4.5) (drill 2.2) (layers "*.Cu" "*.Mask")
      (net 229 "unconnected-(MP1-Pad1)") (pintype "passive+no_connect"))
  )

  (footprint "scalenode-cm4-baseboard-footprints:oshw-logo" (layer "F.Cu")
    (at 138.1 60.3)
    (descr "OSHW Logo")
    (tags "OSHW Logo")
    (property "Author" "Antmicro")
    (property "License" "Apache-2.0")
    (property "MPN" "")
    (property "Manufacturer" "")
    (property "Sheetfile" "scalenode-cm4-baseboard.kicad_sch")
    (property "Sheetname" "")
    (attr exclude_from_pos_files)
    (fp_text reference "N3" (at 2.175 -1.975) (layer "F.SilkS") hide
        (effects (font (size 0.7 0.7) (thickness 0.15)) (justify left bottom))
    )
    (fp_text value "oshw_logo" (at 0.1 -2.325) (layer "F.SilkS") hide
        (effects (font (size 0.7 0.7) (thickness 0.15)) (justify left bottom))
    )
    (fp_text user "License: Apache-2.0" (at -3.081 7.604) (layer "F.Fab") hide
        (effects (font (size 0.7 0.7) (thickness 0.15)) (justify left bottom))
    )
    (fp_text user "Author: Antmicro" (at -3.081 6.404) (layer "F.Fab") hide
        (effects (font (size 0.7 0.7) (thickness 0.15)) (justify left bottom))
    )
    (fp_text user "${REFERENCE}" (at -3.081 5.204) (layer "F.Fab") hide
        (effects (font (size 0.7 0.7) (thickness 0.15)) (justify left bottom))
    )
    (fp_poly
      (pts
        (xy -0.843 2.558)
        (xy -0.815 2.564)
        (xy -0.794 2.572)
        (xy -0.773 2.581)
        (xy -0.759 2.589)
        (xy -0.738 2.603)
        (xy -0.783 2.658)
        (xy -0.8 2.677)
        (xy -0.814 2.694)
        (xy -0.825 2.706)
        (xy -0.831 2.712)
        (xy -0.832 2.712)
        (xy -0.837 2.71)
        (xy -0.847 2.703)
        (xy -0.849 2.702)
        (xy -0.874 2.69)
        (xy -0.904 2.684)
        (xy -0.935 2.685)
        (xy -0.942 2.686)
        (xy -0.975 2.698)
        (xy -1.001 2.717)
        (xy -1.02 2.741)
        (xy -1.034 2.766)
        (xy -1.039 3.197)
        (xy -1.164 3.2)
        (xy -1.164 2.565)
        (xy -1.037 2.565)
        (xy -1.037 2.626)
        (xy -1.009 2.604)
        (xy -0.972 2.579)
        (xy -0.931 2.563)
        (xy -0.887 2.556)
        (xy -0.843 2.558)
      )

      (stroke (width 0.01) (type solid)) (fill solid) (layer "F.Cu"))
    (fp_poly
      (pts
        (xy 1.889 1.554)
        (xy 1.907 1.559)
        (xy 1.927 1.566)
        (xy 1.948 1.574)
        (xy 1.966 1.583)
        (xy 1.979 1.592)
        (xy 1.984 1.597)
        (xy 1.982 1.604)
        (xy 1.974 1.616)
        (xy 1.962 1.633)
        (xy 1.946 1.652)
        (xy 1.945 1.654)
        (xy 1.929 1.673)
        (xy 1.915 1.689)
        (xy 1.906 1.7)
        (xy 1.901 1.706)
        (xy 1.896 1.705)
        (xy 1.885 1.7)
        (xy 1.873 1.695)
        (xy 1.84 1.683)
        (xy 1.808 1.68)
        (xy 1.776 1.685)
        (xy 1.747 1.698)
        (xy 1.723 1.717)
        (xy 1.704 1.742)
        (xy 1.696 1.763)
        (xy 1.695 1.772)
        (xy 1.694 1.79)
        (xy 1.693 1.817)
        (xy 1.692 1.85)
        (xy 1.692 1.89)
        (xy 1.691 1.934)
        (xy 1.691 1.983)
        (xy 1.691 2.194)
        (xy 1.559 2.194)
        (xy 1.559 1.559)
        (xy 1.691 1.559)
        (xy 1.691 1.626)
        (xy 1.71 1.607)
        (xy 1.739 1.585)
        (xy 1.775 1.568)
        (xy 1.814 1.556)
        (xy 1.855 1.552)
        (xy 1.889 1.554)
      )

      (stroke (width 0.01) (type solid)) (fill solid) (layer "F.Cu"))
    (fp_poly
      (pts
        (xy -0.837 1.56)
        (xy -0.797 1.576)
        (xy -0.761 1.6)
        (xy -0.73 1.63)
        (xy -0.706 1.667)
        (xy -0.69 1.709)
        (xy -0.687 1.721)
        (xy -0.685 1.734)
        (xy -0.684 1.757)
        (xy -0.683 1.79)
        (xy -0.682 1.833)
        (xy -0.681 1.884)
        (xy -0.681 1.945)
        (xy -0.681 1.971)
        (xy -0.681 2.194)
        (xy -0.808 2.194)
        (xy -0.809 1.984)
        (xy -0.811 1.774)
        (xy -0.826 1.744)
        (xy -0.845 1.716)
        (xy -0.868 1.697)
        (xy -0.897 1.686)
        (xy -0.925 1.682)
        (xy -0.947 1.682)
        (xy -0.967 1.684)
        (xy -0.979 1.686)
        (xy -1.001 1.698)
        (xy -1.023 1.716)
        (xy -1.041 1.738)
        (xy -1.049 1.752)
        (xy -1.052 1.758)
        (xy -1.054 1.765)
        (xy -1.056 1.773)
        (xy -1.057 1.783)
        (xy -1.058 1.797)
        (xy -1.059 1.815)
        (xy -1.06 1.839)
        (xy -1.06 1.869)
        (xy -1.061 1.907)
        (xy -1.061 1.953)
        (xy -1.061 1.985)
        (xy -1.063 2.194)
        (xy -1.189 2.194)
        (xy -1.189 1.559)
        (xy -1.062 1.559)
        (xy -1.062 1.625)
        (xy -1.033 1.602)
        (xy -1.001 1.579)
        (xy -0.969 1.564)
        (xy -0.934 1.555)
        (xy -0.927 1.554)
        (xy -0.881 1.553)
        (xy -0.837 1.56)
      )

      (stroke (width 0.01) (type solid)) (fill solid) (layer "F.Cu"))
    (fp_poly
      (pts
        (xy 1.042 1.769)
        (xy 1.043 1.979)
        (xy 1.059 2.009)
        (xy 1.077 2.036)
        (xy 1.1 2.056)
        (xy 1.129 2.067)
        (xy 1.159 2.071)
        (xy 1.193 2.07)
        (xy 1.221 2.063)
        (xy 1.245 2.047)
        (xy 1.258 2.034)
        (xy 1.266 2.025)
        (xy 1.273 2.016)
        (xy 1.278 2.008)
        (xy 1.282 1.997)
        (xy 1.286 1.985)
        (xy 1.288 1.969)
        (xy 1.29 1.948)
        (xy 1.291 1.922)
        (xy 1.292 1.89)
        (xy 1.293 1.85)
        (xy 1.293 1.801)
        (xy 1.294 1.766)
        (xy 1.295 1.559)
        (xy 1.422 1.559)
        (xy 1.422 2.194)
        (xy 1.295 2.194)
        (xy 1.295 2.161)
        (xy 1.295 2.144)
        (xy 1.293 2.132)
        (xy 1.292 2.128)
        (xy 1.287 2.131)
        (xy 1.278 2.14)
        (xy 1.271 2.147)
        (xy 1.256 2.159)
        (xy 1.236 2.171)
        (xy 1.219 2.181)
        (xy 1.202 2.188)
        (xy 1.186 2.193)
        (xy 1.17 2.196)
        (xy 1.148 2.197)
        (xy 1.135 2.198)
        (xy 1.107 2.198)
        (xy 1.087 2.197)
        (xy 1.07 2.194)
        (xy 1.059 2.19)
        (xy 1.036 2.181)
        (xy 1.019 2.172)
        (xy 1.003 2.161)
        (xy 0.985 2.146)
        (xy 0.981 2.141)
        (xy 0.952 2.107)
        (xy 0.931 2.068)
        (xy 0.92 2.033)
        (xy 0.918 2.019)
        (xy 0.917 1.996)
        (xy 0.916 1.963)
        (xy 0.915 1.92)
        (xy 0.914 1.869)
        (xy 0.914 1.808)
        (xy 0.914 1.782)
        (xy 0.914 1.559)
        (xy 1.04 1.559)
        (xy 1.042 1.769)
      )

      (stroke (width 0.01) (type solid)) (fill solid) (layer "F.Cu"))
    (fp_poly
      (pts
        (xy 1.753 2.563)
        (xy 1.768 2.568)
        (xy 1.787 2.577)
        (xy 1.804 2.586)
        (xy 1.818 2.595)
        (xy 1.826 2.602)
        (xy 1.827 2.606)
        (xy 1.824 2.611)
        (xy 1.815 2.621)
        (xy 1.803 2.636)
        (xy 1.789 2.654)
        (xy 1.775 2.671)
        (xy 1.761 2.688)
        (xy 1.749 2.701)
        (xy 1.742 2.71)
        (xy 1.739 2.712)
        (xy 1.735 2.71)
        (xy 1.724 2.704)
        (xy 1.713 2.698)
        (xy 1.697 2.69)
        (xy 1.682 2.686)
        (xy 1.664 2.685)
        (xy 1.653 2.685)
        (xy 1.618 2.688)
        (xy 1.59 2.699)
        (xy 1.566 2.718)
        (xy 1.561 2.723)
        (xy 1.554 2.732)
        (xy 1.548 2.74)
        (xy 1.544 2.748)
        (xy 1.54 2.758)
        (xy 1.537 2.769)
        (xy 1.534 2.785)
        (xy 1.533 2.804)
        (xy 1.532 2.829)
        (xy 1.531 2.861)
        (xy 1.53 2.899)
        (xy 1.53 2.947)
        (xy 1.53 2.988)
        (xy 1.528 3.2)
        (xy 1.468 3.2)
        (xy 1.444 3.2)
        (xy 1.425 3.199)
        (xy 1.411 3.198)
        (xy 1.405 3.197)
        (xy 1.404 3.191)
        (xy 1.404 3.176)
        (xy 1.403 3.153)
        (xy 1.403 3.122)
        (xy 1.402 3.085)
        (xy 1.402 3.042)
        (xy 1.402 2.993)
        (xy 1.402 2.941)
        (xy 1.402 2.886)
        (xy 1.402 2.565)
        (xy 1.529 2.565)
        (xy 1.529 2.595)
        (xy 1.529 2.611)
        (xy 1.53 2.623)
        (xy 1.532 2.626)
        (xy 1.537 2.623)
        (xy 1.547 2.615)
        (xy 1.554 2.608)
        (xy 1.588 2.584)
        (xy 1.627 2.567)
        (xy 1.669 2.558)
        (xy 1.712 2.556)
        (xy 1.753 2.563)
      )

      (stroke (width 0.01) (type solid)) (fill solid) (layer "F.Cu"))
    (fp_poly
      (pts
        (xy 2.316 1.557)
        (xy 2.365 1.57)
        (xy 2.41 1.593)
        (xy 2.453 1.625)
        (xy 2.46 1.631)
        (xy 2.491 1.661)
        (xy 2.466 1.684)
        (xy 2.448 1.699)
        (xy 2.43 1.715)
        (xy 2.419 1.725)
        (xy 2.397 1.743)
        (xy 2.376 1.724)
        (xy 2.345 1.701)
        (xy 2.312 1.687)
        (xy 2.274 1.681)
        (xy 2.265 1.681)
        (xy 2.226 1.684)
        (xy 2.195 1.693)
        (xy 2.167 1.708)
        (xy 2.159 1.715)
        (xy 2.136 1.741)
        (xy 2.118 1.776)
        (xy 2.107 1.817)
        (xy 2.103 1.866)
        (xy 2.103 1.876)
        (xy 2.106 1.926)
        (xy 2.116 1.97)
        (xy 2.132 2.006)
        (xy 2.155 2.034)
        (xy 2.184 2.055)
        (xy 2.219 2.067)
        (xy 2.259 2.072)
        (xy 2.274 2.071)
        (xy 2.309 2.066)
        (xy 2.339 2.056)
        (xy 2.366 2.038)
        (xy 2.377 2.028)
        (xy 2.386 2.02)
        (xy 2.393 2.016)
        (xy 2.4 2.015)
        (xy 2.409 2.018)
        (xy 2.42 2.027)
        (xy 2.436 2.041)
        (xy 2.456 2.059)
        (xy 2.491 2.092)
        (xy 2.476 2.108)
        (xy 2.449 2.132)
        (xy 2.416 2.155)
        (xy 2.38 2.174)
        (xy 2.35 2.186)
        (xy 2.327 2.193)
        (xy 2.306 2.197)
        (xy 2.283 2.199)
        (xy 2.259 2.199)
        (xy 2.233 2.198)
        (xy 2.209 2.196)
        (xy 2.189 2.193)
        (xy 2.182 2.191)
        (xy 2.133 2.173)
        (xy 2.089 2.146)
        (xy 2.053 2.112)
        (xy 2.023 2.071)
        (xy 2.012 2.051)
        (xy 2 2.023)
        (xy 1.991 1.999)
        (xy 1.984 1.975)
        (xy 1.981 1.948)
        (xy 1.979 1.917)
        (xy 1.978 1.879)
        (xy 1.978 1.877)
        (xy 1.979 1.838)
        (xy 1.98 1.806)
        (xy 1.984 1.78)
        (xy 1.99 1.756)
        (xy 1.999 1.731)
        (xy 2.011 1.704)
        (xy 2.012 1.701)
        (xy 2.039 1.657)
        (xy 2.072 1.62)
        (xy 2.111 1.591)
        (xy 2.156 1.57)
        (xy 2.207 1.557)
        (xy 2.263 1.552)
        (xy 2.316 1.557)
      )

      (stroke (width 0.01) (type solid)) (fill solid) (layer "F.Cu"))
    (fp_poly
      (pts
        (xy -1.494 1.56)
        (xy -1.447 1.576)
        (xy -1.405 1.6)
        (xy -1.368 1.633)
        (xy -1.341 1.668)
        (xy -1.326 1.692)
        (xy -1.316 1.716)
        (xy -1.308 1.743)
        (xy -1.302 1.774)
        (xy -1.299 1.811)
        (xy -1.297 1.845)
        (xy -1.294 1.925)
        (xy -1.692 1.925)
        (xy -1.692 1.942)
        (xy -1.687 1.977)
        (xy -1.673 2.011)
        (xy -1.65 2.039)
        (xy -1.626 2.059)
        (xy -1.601 2.071)
        (xy -1.572 2.078)
        (xy -1.537 2.079)
        (xy -1.497 2.074)
        (xy -1.458 2.06)
        (xy -1.422 2.036)
        (xy -1.421 2.036)
        (xy -1.402 2.021)
        (xy -1.359 2.057)
        (xy -1.342 2.072)
        (xy -1.327 2.085)
        (xy -1.317 2.094)
        (xy -1.314 2.098)
        (xy -1.316 2.103)
        (xy -1.324 2.113)
        (xy -1.338 2.126)
        (xy -1.354 2.139)
        (xy -1.372 2.152)
        (xy -1.389 2.163)
        (xy -1.399 2.168)
        (xy -1.421 2.178)
        (xy -1.445 2.187)
        (xy -1.461 2.191)
        (xy -1.488 2.196)
        (xy -1.522 2.199)
        (xy -1.557 2.199)
        (xy -1.591 2.196)
        (xy -1.62 2.192)
        (xy -1.629 2.19)
        (xy -1.677 2.171)
        (xy -1.718 2.146)
        (xy -1.752 2.114)
        (xy -1.779 2.074)
        (xy -1.8 2.026)
        (xy -1.802 2.02)
        (xy -1.81 1.989)
        (xy -1.815 1.951)
        (xy -1.818 1.908)
        (xy -1.819 1.865)
        (xy -1.818 1.823)
        (xy -1.816 1.804)
        (xy -1.692 1.804)
        (xy -1.692 1.818)
        (xy -1.428 1.818)
        (xy -1.428 1.801)
        (xy -1.432 1.775)
        (xy -1.442 1.748)
        (xy -1.457 1.722)
        (xy -1.469 1.707)
        (xy -1.495 1.688)
        (xy -1.526 1.676)
        (xy -1.56 1.672)
        (xy -1.593 1.676)
        (xy -1.619 1.685)
        (xy -1.646 1.704)
        (xy -1.668 1.73)
        (xy -1.683 1.76)
        (xy -1.691 1.792)
        (xy -1.692 1.804)
        (xy -1.816 1.804)
        (xy -1.814 1.786)
        (xy -1.812 1.777)
        (xy -1.797 1.724)
        (xy -1.775 1.676)
        (xy -1.747 1.636)
        (xy -1.713 1.603)
        (xy -1.673 1.578)
        (xy -1.629 1.561)
        (xy -1.597 1.554)
        (xy -1.544 1.552)
        (xy -1.494 1.56)
      )

      (stroke (width 0.01) (type solid)) (fill solid) (layer "F.Cu"))
    (fp_poly
      (pts
        (xy 2.835 1.557)
        (xy 2.883 1.57)
        (xy 2.926 1.592)
        (xy 2.964 1.621)
        (xy 2.996 1.657)
        (xy 3.021 1.699)
        (xy 3.038 1.747)
        (xy 3.04 1.757)
        (xy 3.043 1.776)
        (xy 3.045 1.802)
        (xy 3.047 1.832)
        (xy 3.047 1.858)
        (xy 3.047 1.925)
        (xy 2.65 1.925)
        (xy 2.653 1.951)
        (xy 2.663 1.991)
        (xy 2.68 2.024)
        (xy 2.703 2.049)
        (xy 2.733 2.067)
        (xy 2.77 2.077)
        (xy 2.801 2.079)
        (xy 2.845 2.075)
        (xy 2.883 2.063)
        (xy 2.916 2.042)
        (xy 2.92 2.039)
        (xy 2.929 2.031)
        (xy 2.935 2.026)
        (xy 2.941 2.025)
        (xy 2.949 2.027)
        (xy 2.959 2.034)
        (xy 2.974 2.047)
        (xy 2.994 2.064)
        (xy 3.01 2.078)
        (xy 3.023 2.088)
        (xy 3.03 2.095)
        (xy 3.032 2.096)
        (xy 3.03 2.1)
        (xy 3.022 2.11)
        (xy 3.01 2.122)
        (xy 3.009 2.123)
        (xy 2.98 2.147)
        (xy 2.945 2.169)
        (xy 2.906 2.185)
        (xy 2.887 2.191)
        (xy 2.861 2.196)
        (xy 2.828 2.198)
        (xy 2.793 2.198)
        (xy 2.759 2.197)
        (xy 2.729 2.193)
        (xy 2.721 2.191)
        (xy 2.675 2.175)
        (xy 2.634 2.15)
        (xy 2.599 2.118)
        (xy 2.569 2.077)
        (xy 2.547 2.029)
        (xy 2.536 1.996)
        (xy 2.532 1.973)
        (xy 2.529 1.942)
        (xy 2.527 1.906)
        (xy 2.527 1.869)
        (xy 2.528 1.832)
        (xy 2.529 1.818)
        (xy 2.65 1.818)
        (xy 2.922 1.818)
        (xy 2.918 1.799)
        (xy 2.908 1.758)
        (xy 2.891 1.725)
        (xy 2.869 1.7)
        (xy 2.84 1.683)
        (xy 2.826 1.678)
        (xy 2.788 1.672)
        (xy 2.753 1.675)
        (xy 2.722 1.687)
        (xy 2.695 1.706)
        (xy 2.674 1.734)
        (xy 2.659 1.768)
        (xy 2.654 1.794)
        (xy 2.65 1.818)
        (xy 2.529 1.818)
        (xy 2.53 1.798)
        (xy 2.534 1.769)
        (xy 2.536 1.76)
        (xy 2.554 1.707)
        (xy 2.578 1.662)
        (xy 2.609 1.624)
        (xy 2.645 1.593)
        (xy 2.687 1.571)
        (xy 2.734 1.557)
        (xy 2.783 1.553)
        (xy 2.835 1.557)
      )

      (stroke (width 0.01) (type solid)) (fill solid) (layer "F.Cu"))
    (fp_poly
      (pts
        (xy -2.733 1.557)
        (xy -2.685 1.57)
        (xy -2.642 1.592)
        (xy -2.604 1.622)
        (xy -2.581 1.649)
        (xy -2.562 1.676)
        (xy -2.548 1.706)
        (xy -2.537 1.739)
        (xy -2.53 1.777)
        (xy -2.527 1.821)
        (xy -2.526 1.873)
        (xy -2.527 1.907)
        (xy -2.529 1.956)
        (xy -2.534 1.997)
        (xy -2.542 2.031)
        (xy -2.553 2.06)
        (xy -2.567 2.086)
        (xy -2.587 2.111)
        (xy -2.603 2.129)
        (xy -2.637 2.158)
        (xy -2.673 2.178)
        (xy -2.714 2.192)
        (xy -2.76 2.198)
        (xy -2.789 2.199)
        (xy -2.813 2.198)
        (xy -2.835 2.196)
        (xy -2.852 2.194)
        (xy -2.857 2.194)
        (xy -2.898 2.179)
        (xy -2.937 2.155)
        (xy -2.97 2.126)
        (xy -2.993 2.101)
        (xy -3.011 2.077)
        (xy -3.024 2.051)
        (xy -3.034 2.022)
        (xy -3.041 1.988)
        (xy -3.045 1.947)
        (xy -3.047 1.91)
        (xy -3.047 1.882)
        (xy -2.919 1.882)
        (xy -2.919 1.968)
        (xy -2.903 2.001)
        (xy -2.885 2.031)
        (xy -2.863 2.051)
        (xy -2.837 2.064)
        (xy -2.804 2.07)
        (xy -2.779 2.07)
        (xy -2.755 2.069)
        (xy -2.737 2.065)
        (xy -2.722 2.058)
        (xy -2.717 2.055)
        (xy -2.697 2.041)
        (xy -2.681 2.025)
        (xy -2.67 2.004)
        (xy -2.662 1.978)
        (xy -2.657 1.945)
        (xy -2.654 1.903)
        (xy -2.654 1.899)
        (xy -2.653 1.848)
        (xy -2.656 1.806)
        (xy -2.662 1.772)
        (xy -2.673 1.744)
        (xy -2.687 1.722)
        (xy -2.707 1.705)
        (xy -2.723 1.695)
        (xy -2.755 1.684)
        (xy -2.788 1.68)
        (xy -2.821 1.684)
        (xy -2.851 1.695)
        (xy -2.877 1.713)
        (xy -2.892 1.729)
        (xy -2.901 1.745)
        (xy -2.908 1.76)
        (xy -2.913 1.778)
        (xy -2.916 1.8)
        (xy -2.918 1.828)
        (xy -2.919 1.864)
        (xy -2.919 1.882)
        (xy -3.047 1.882)
        (xy -3.048 1.844)
        (xy -3.043 1.786)
        (xy -3.034 1.736)
        (xy -3.021 1.695)
        (xy -3.004 1.664)
        (xy -2.972 1.624)
        (xy -2.935 1.594)
        (xy -2.893 1.571)
        (xy -2.846 1.558)
        (xy -2.794 1.553)
        (xy -2.787 1.553)
        (xy -2.733 1.557)
      )

      (stroke (width 0.01) (type solid)) (fill solid) (layer "F.Cu"))
    (fp_poly
      (pts
        (xy 2.148 2.561)
        (xy 2.193 2.574)
        (xy 2.235 2.595)
        (xy 2.273 2.623)
        (xy 2.304 2.657)
        (xy 2.326 2.691)
        (xy 2.338 2.718)
        (xy 2.346 2.745)
        (xy 2.352 2.774)
        (xy 2.355 2.808)
        (xy 2.357 2.85)
        (xy 2.357 2.858)
        (xy 2.357 2.931)
        (xy 1.96 2.931)
        (xy 1.963 2.955)
        (xy 1.973 2.993)
        (xy 1.991 3.026)
        (xy 2.015 3.053)
        (xy 2.039 3.069)
        (xy 2.057 3.076)
        (xy 2.08 3.08)
        (xy 2.103 3.082)
        (xy 2.144 3.081)
        (xy 2.18 3.071)
        (xy 2.214 3.054)
        (xy 2.227 3.045)
        (xy 2.24 3.035)
        (xy 2.25 3.029)
        (xy 2.253 3.027)
        (xy 2.258 3.03)
        (xy 2.269 3.039)
        (xy 2.284 3.05)
        (xy 2.3 3.064)
        (xy 2.315 3.078)
        (xy 2.329 3.09)
        (xy 2.338 3.099)
        (xy 2.341 3.103)
        (xy 2.337 3.11)
        (xy 2.327 3.121)
        (xy 2.312 3.134)
        (xy 2.294 3.148)
        (xy 2.276 3.161)
        (xy 2.259 3.171)
        (xy 2.252 3.175)
        (xy 2.204 3.192)
        (xy 2.152 3.202)
        (xy 2.098 3.204)
        (xy 2.046 3.198)
        (xy 2.032 3.195)
        (xy 1.984 3.178)
        (xy 1.943 3.154)
        (xy 1.909 3.123)
        (xy 1.881 3.084)
        (xy 1.859 3.037)
        (xy 1.847 3.003)
        (xy 1.841 2.972)
        (xy 1.838 2.934)
        (xy 1.836 2.893)
        (xy 1.837 2.851)
        (xy 1.839 2.824)
        (xy 1.96 2.824)
        (xy 2.23 2.824)
        (xy 2.23 2.813)
        (xy 2.225 2.783)
        (xy 2.214 2.753)
        (xy 2.196 2.725)
        (xy 2.175 2.702)
        (xy 2.151 2.686)
        (xy 2.128 2.68)
        (xy 2.101 2.677)
        (xy 2.072 2.678)
        (xy 2.051 2.683)
        (xy 2.023 2.696)
        (xy 2 2.717)
        (xy 1.981 2.746)
        (xy 1.968 2.779)
        (xy 1.963 2.8)
        (xy 1.96 2.824)
        (xy 1.839 2.824)
        (xy 1.839 2.811)
        (xy 1.844 2.776)
        (xy 1.848 2.76)
        (xy 1.866 2.708)
        (xy 1.889 2.663)
        (xy 1.919 2.627)
        (xy 1.954 2.598)
        (xy 1.996 2.575)
        (xy 2.007 2.571)
        (xy 2.054 2.559)
        (xy 2.101 2.556)
        (xy 2.148 2.561)
      )

      (stroke (width 0.01) (type solid)) (fill solid) (layer "F.Cu"))
    (fp_poly
      (pts
        (xy -0.229 3.2)
        (xy -0.354 3.197)
        (xy -0.355 3.165)
        (xy -0.357 3.133)
        (xy -0.374 3.148)
        (xy -0.411 3.175)
        (xy -0.453 3.193)
        (xy -0.497 3.203)
        (xy -0.542 3.204)
        (xy -0.585 3.195)
        (xy -0.586 3.195)
        (xy -0.621 3.181)
        (xy -0.651 3.16)
        (xy -0.673 3.141)
        (xy -0.689 3.123)
        (xy -0.702 3.106)
        (xy -0.712 3.086)
        (xy -0.72 3.064)
        (xy -0.726 3.038)
        (xy -0.73 3.007)
        (xy -0.732 2.968)
        (xy -0.733 2.922)
        (xy -0.733 2.88)
        (xy -0.602 2.88)
        (xy -0.602 2.915)
        (xy -0.602 2.942)
        (xy -0.601 2.962)
        (xy -0.6 2.977)
        (xy -0.598 2.988)
        (xy -0.596 2.998)
        (xy -0.592 3.007)
        (xy -0.591 3.01)
        (xy -0.574 3.039)
        (xy -0.552 3.059)
        (xy -0.525 3.071)
        (xy -0.492 3.076)
        (xy -0.472 3.076)
        (xy -0.442 3.072)
        (xy -0.418 3.063)
        (xy -0.398 3.048)
        (xy -0.382 3.029)
        (xy -0.371 3.004)
        (xy -0.363 2.972)
        (xy -0.358 2.933)
        (xy -0.356 2.885)
        (xy -0.356 2.88)
        (xy -0.358 2.828)
        (xy -0.363 2.785)
        (xy -0.373 2.75)
        (xy -0.387 2.724)
        (xy -0.406 2.704)
        (xy -0.43 2.692)
        (xy -0.46 2.686)
        (xy -0.483 2.685)
        (xy -0.517 2.687)
        (xy -0.544 2.696)
        (xy -0.565 2.711)
        (xy -0.583 2.734)
        (xy -0.591 2.751)
        (xy -0.595 2.76)
        (xy -0.598 2.769)
        (xy -0.6 2.779)
        (xy -0.601 2.793)
        (xy -0.602 2.811)
        (xy -0.602 2.836)
        (xy -0.602 2.869)
        (xy -0.602 2.88)
        (xy -0.733 2.88)
        (xy -0.733 2.827)
        (xy -0.732 2.783)
        (xy -0.729 2.746)
        (xy -0.725 2.716)
        (xy -0.719 2.691)
        (xy -0.71 2.67)
        (xy -0.699 2.651)
        (xy -0.685 2.633)
        (xy -0.668 2.616)
        (xy -0.668 2.615)
        (xy -0.632 2.587)
        (xy -0.592 2.567)
        (xy -0.55 2.557)
        (xy -0.506 2.556)
        (xy -0.463 2.564)
        (xy -0.421 2.582)
        (xy -0.411 2.587)
        (xy -0.394 2.598)
        (xy -0.377 2.61)
        (xy -0.373 2.614)
        (xy -0.356 2.627)
        (xy -0.356 2.306)
        (xy -0.229 2.306)
        (xy -0.229 3.2)
      )

      (stroke (width 0.01) (type solid)) (fill solid) (layer "F.Cu"))
    (fp_poly
      (pts
        (xy 0.605 1.558)
        (xy 0.651 1.574)
        (xy 0.694 1.598)
        (xy 0.728 1.627)
        (xy 0.75 1.652)
        (xy 0.768 1.678)
        (xy 0.781 1.707)
        (xy 0.791 1.739)
        (xy 0.797 1.777)
        (xy 0.801 1.822)
        (xy 0.802 1.876)
        (xy 0.802 1.877)
        (xy 0.801 1.929)
        (xy 0.798 1.973)
        (xy 0.792 2.009)
        (xy 0.784 2.04)
        (xy 0.774 2.062)
        (xy 0.748 2.103)
        (xy 0.715 2.139)
        (xy 0.675 2.167)
        (xy 0.632 2.187)
        (xy 0.626 2.189)
        (xy 0.599 2.195)
        (xy 0.567 2.198)
        (xy 0.532 2.199)
        (xy 0.499 2.197)
        (xy 0.471 2.193)
        (xy 0.466 2.192)
        (xy 0.428 2.177)
        (xy 0.391 2.155)
        (xy 0.359 2.129)
        (xy 0.354 2.123)
        (xy 0.332 2.098)
        (xy 0.316 2.073)
        (xy 0.303 2.047)
        (xy 0.294 2.017)
        (xy 0.287 1.983)
        (xy 0.284 1.943)
        (xy 0.282 1.894)
        (xy 0.282 1.877)
        (xy 0.409 1.877)
        (xy 0.41 1.918)
        (xy 0.412 1.95)
        (xy 0.416 1.976)
        (xy 0.423 1.997)
        (xy 0.432 2.015)
        (xy 0.445 2.03)
        (xy 0.451 2.037)
        (xy 0.471 2.054)
        (xy 0.491 2.064)
        (xy 0.514 2.07)
        (xy 0.543 2.072)
        (xy 0.569 2.07)
        (xy 0.59 2.065)
        (xy 0.601 2.06)
        (xy 0.625 2.047)
        (xy 0.642 2.031)
        (xy 0.656 2.009)
        (xy 0.661 1.998)
        (xy 0.665 1.989)
        (xy 0.668 1.98)
        (xy 0.67 1.969)
        (xy 0.671 1.954)
        (xy 0.672 1.935)
        (xy 0.673 1.909)
        (xy 0.673 1.877)
        (xy 0.673 1.842)
        (xy 0.672 1.817)
        (xy 0.671 1.798)
        (xy 0.67 1.784)
        (xy 0.668 1.773)
        (xy 0.665 1.764)
        (xy 0.661 1.755)
        (xy 0.647 1.73)
        (xy 0.632 1.712)
        (xy 0.612 1.698)
        (xy 0.601 1.693)
        (xy 0.569 1.683)
        (xy 0.535 1.681)
        (xy 0.501 1.686)
        (xy 0.471 1.7)
        (xy 0.447 1.719)
        (xy 0.434 1.736)
        (xy 0.424 1.753)
        (xy 0.417 1.774)
        (xy 0.412 1.8)
        (xy 0.41 1.833)
        (xy 0.409 1.873)
        (xy 0.409 1.877)
        (xy 0.282 1.877)
        (xy 0.283 1.824)
        (xy 0.286 1.78)
        (xy 0.292 1.742)
        (xy 0.301 1.711)
        (xy 0.313 1.683)
        (xy 0.33 1.657)
        (xy 0.35 1.633)
        (xy 0.351 1.632)
        (xy 0.385 1.601)
        (xy 0.42 1.578)
        (xy 0.46 1.563)
        (xy 0.505 1.554)
        (xy 0.555 1.551)
        (xy 0.605 1.558)
      )

      (stroke (width 0.01) (type solid)) (fill solid) (layer "F.Cu"))
    (fp_poly
      (pts
        (xy 0.004 1.556)
        (xy 0.054 1.566)
        (xy 0.102 1.582)
        (xy 0.146 1.605)
        (xy 0.154 1.61)
        (xy 0.193 1.636)
        (xy 0.178 1.655)
        (xy 0.166 1.668)
        (xy 0.152 1.686)
        (xy 0.138 1.7)
        (xy 0.114 1.727)
        (xy 0.07 1.705)
        (xy 0.032 1.688)
        (xy -0.007 1.677)
        (xy -0.044 1.672)
        (xy -0.079 1.672)
        (xy -0.11 1.678)
        (xy -0.136 1.69)
        (xy -0.154 1.707)
        (xy -0.162 1.724)
        (xy -0.164 1.745)
        (xy -0.164 1.761)
        (xy -0.159 1.772)
        (xy -0.15 1.782)
        (xy -0.149 1.783)
        (xy -0.139 1.791)
        (xy -0.128 1.797)
        (xy -0.114 1.802)
        (xy -0.095 1.805)
        (xy -0.07 1.808)
        (xy -0.037 1.811)
        (xy -0.02 1.813)
        (xy 0.027 1.817)
        (xy 0.065 1.823)
        (xy 0.096 1.832)
        (xy 0.122 1.842)
        (xy 0.14 1.854)
        (xy 0.166 1.879)
        (xy 0.186 1.91)
        (xy 0.2 1.947)
        (xy 0.206 1.987)
        (xy 0.206 2.018)
        (xy 0.198 2.06)
        (xy 0.181 2.097)
        (xy 0.155 2.129)
        (xy 0.122 2.156)
        (xy 0.08 2.177)
        (xy 0.042 2.189)
        (xy 0.005 2.196)
        (xy -0.038 2.199)
        (xy -0.083 2.198)
        (xy -0.125 2.194)
        (xy -0.153 2.189)
        (xy -0.177 2.181)
        (xy -0.204 2.171)
        (xy -0.229 2.16)
        (xy -0.232 2.159)
        (xy -0.251 2.148)
        (xy -0.272 2.136)
        (xy -0.292 2.122)
        (xy -0.309 2.109)
        (xy -0.323 2.098)
        (xy -0.33 2.09)
        (xy -0.331 2.088)
        (xy -0.327 2.084)
        (xy -0.318 2.073)
        (xy -0.304 2.059)
        (xy -0.288 2.043)
        (xy -0.246 2)
        (xy -0.221 2.021)
        (xy -0.184 2.047)
        (xy -0.145 2.065)
        (xy -0.102 2.075)
        (xy -0.053 2.079)
        (xy -0.049 2.079)
        (xy -0.023 2.079)
        (xy -0.004 2.078)
        (xy 0.011 2.074)
        (xy 0.025 2.069)
        (xy 0.029 2.068)
        (xy 0.054 2.052)
        (xy 0.071 2.033)
        (xy 0.079 2.01)
        (xy 0.078 1.986)
        (xy 0.074 1.975)
        (xy 0.068 1.964)
        (xy 0.06 1.956)
        (xy 0.048 1.949)
        (xy 0.031 1.944)
        (xy 0.007 1.939)
        (xy -0.024 1.935)
        (xy -0.052 1.932)
        (xy -0.089 1.929)
        (xy -0.119 1.925)
        (xy -0.142 1.921)
        (xy -0.16 1.917)
        (xy -0.176 1.912)
        (xy -0.192 1.906)
        (xy -0.201 1.901)
        (xy -0.235 1.879)
        (xy -0.262 1.85)
        (xy -0.28 1.816)
        (xy -0.29 1.776)
        (xy -0.292 1.75)
        (xy -0.291 1.727)
        (xy -0.289 1.705)
        (xy -0.286 1.689)
        (xy -0.286 1.688)
        (xy -0.273 1.659)
        (xy -0.253 1.63)
        (xy -0.229 1.604)
        (xy -0.221 1.599)
        (xy -0.185 1.577)
        (xy -0.143 1.562)
        (xy -0.096 1.554)
        (xy -0.047 1.552)
        (xy 0.004 1.556)
      )

      (stroke (width 0.01) (type solid)) (fill solid) (layer "F.Cu"))
    (fp_poly
      (pts
        (xy 1.038 2.556)
        (xy 1.091 2.563)
        (xy 1.137 2.576)
        (xy 1.177 2.595)
        (xy 1.209 2.62)
        (xy 1.234 2.65)
        (xy 1.242 2.665)
        (xy 1.247 2.677)
        (xy 1.251 2.691)
        (xy 1.255 2.708)
        (xy 1.258 2.727)
        (xy 1.26 2.751)
        (xy 1.262 2.78)
        (xy 1.263 2.815)
        (xy 1.263 2.858)
        (xy 1.264 2.908)
        (xy 1.263 2.967)
        (xy 1.263 2.989)
        (xy 1.262 3.197)
        (xy 1.135 3.197)
        (xy 1.133 3.171)
        (xy 1.132 3.144)
        (xy 1.119 3.159)
        (xy 1.096 3.179)
        (xy 1.065 3.193)
        (xy 1.026 3.202)
        (xy 0.98 3.204)
        (xy 0.976 3.204)
        (xy 0.955 3.204)
        (xy 0.937 3.203)
        (xy 0.925 3.202)
        (xy 0.924 3.201)
        (xy 0.879 3.189)
        (xy 0.839 3.17)
        (xy 0.806 3.144)
        (xy 0.781 3.113)
        (xy 0.763 3.077)
        (xy 0.753 3.037)
        (xy 0.753 3.005)
        (xy 0.873 3.005)
        (xy 0.874 3.023)
        (xy 0.878 3.035)
        (xy 0.887 3.047)
        (xy 0.89 3.05)
        (xy 0.903 3.063)
        (xy 0.917 3.072)
        (xy 0.935 3.078)
        (xy 0.957 3.081)
        (xy 0.986 3.082)
        (xy 1.013 3.082)
        (xy 1.043 3.081)
        (xy 1.065 3.079)
        (xy 1.08 3.077)
        (xy 1.091 3.073)
        (xy 1.096 3.071)
        (xy 1.112 3.058)
        (xy 1.123 3.039)
        (xy 1.13 3.012)
        (xy 1.132 2.977)
        (xy 1.132 2.975)
        (xy 1.132 2.931)
        (xy 1.035 2.931)
        (xy 0.999 2.931)
        (xy 0.973 2.931)
        (xy 0.953 2.932)
        (xy 0.939 2.934)
        (xy 0.928 2.936)
        (xy 0.919 2.939)
        (xy 0.916 2.94)
        (xy 0.893 2.954)
        (xy 0.88 2.971)
        (xy 0.874 2.994)
        (xy 0.873 3.005)
        (xy 0.753 3.005)
        (xy 0.753 2.994)
        (xy 0.761 2.951)
        (xy 0.768 2.931)
        (xy 0.776 2.915)
        (xy 0.786 2.901)
        (xy 0.802 2.884)
        (xy 0.804 2.882)
        (xy 0.82 2.867)
        (xy 0.835 2.854)
        (xy 0.85 2.845)
        (xy 0.867 2.838)
        (xy 0.887 2.833)
        (xy 0.912 2.829)
        (xy 0.943 2.827)
        (xy 0.982 2.826)
        (xy 1.015 2.825)
        (xy 1.133 2.823)
        (xy 1.132 2.771)
        (xy 1.131 2.746)
        (xy 1.129 2.73)
        (xy 1.127 2.719)
        (xy 1.123 2.711)
        (xy 1.117 2.705)
        (xy 1.098 2.691)
        (xy 1.07 2.682)
        (xy 1.032 2.677)
        (xy 1.006 2.677)
        (xy 0.972 2.678)
        (xy 0.945 2.682)
        (xy 0.924 2.688)
        (xy 0.907 2.699)
        (xy 0.9 2.706)
        (xy 0.882 2.723)
        (xy 0.834 2.686)
        (xy 0.816 2.672)
        (xy 0.801 2.66)
        (xy 0.79 2.652)
        (xy 0.787 2.648)
        (xy 0.791 2.639)
        (xy 0.801 2.626)
        (xy 0.816 2.612)
        (xy 0.832 2.6)
        (xy 0.864 2.581)
        (xy 0.902 2.568)
        (xy 0.946 2.559)
        (xy 0.98 2.556)
        (xy 1.038 2.556)
      )

      (stroke (width 0.01) (type solid)) (fill solid) (layer "F.Cu"))
    (fp_poly
      (pts
        (xy -1.521 2.559)
        (xy -1.485 2.562)
        (xy -1.454 2.568)
        (xy -1.427 2.577)
        (xy -1.401 2.589)
        (xy -1.371 2.61)
        (xy -1.345 2.639)
        (xy -1.325 2.67)
        (xy -1.321 2.679)
        (xy -1.309 2.71)
        (xy -1.309 3.197)
        (xy -1.433 3.2)
        (xy -1.433 3.172)
        (xy -1.434 3.157)
        (xy -1.435 3.147)
        (xy -1.436 3.144)
        (xy -1.44 3.147)
        (xy -1.449 3.156)
        (xy -1.453 3.161)
        (xy -1.472 3.178)
        (xy -1.496 3.19)
        (xy -1.526 3.198)
        (xy -1.563 3.202)
        (xy -1.578 3.203)
        (xy -1.603 3.203)
        (xy -1.627 3.203)
        (xy -1.647 3.201)
        (xy -1.656 3.2)
        (xy -1.686 3.191)
        (xy -1.717 3.176)
        (xy -1.746 3.159)
        (xy -1.765 3.143)
        (xy -1.79 3.111)
        (xy -1.807 3.075)
        (xy -1.816 3.037)
        (xy -1.817 2.998)
        (xy -1.817 2.997)
        (xy -1.697 2.997)
        (xy -1.696 3.02)
        (xy -1.687 3.042)
        (xy -1.67 3.06)
        (xy -1.668 3.062)
        (xy -1.654 3.07)
        (xy -1.64 3.076)
        (xy -1.624 3.08)
        (xy -1.602 3.081)
        (xy -1.574 3.082)
        (xy -1.558 3.082)
        (xy -1.529 3.081)
        (xy -1.508 3.08)
        (xy -1.494 3.078)
        (xy -1.483 3.075)
        (xy -1.474 3.07)
        (xy -1.458 3.058)
        (xy -1.447 3.041)
        (xy -1.44 3.017)
        (xy -1.435 2.985)
        (xy -1.435 2.977)
        (xy -1.432 2.931)
        (xy -1.533 2.931)
        (xy -1.568 2.931)
        (xy -1.595 2.931)
        (xy -1.615 2.932)
        (xy -1.63 2.934)
        (xy -1.641 2.936)
        (xy -1.65 2.938)
        (xy -1.655 2.941)
        (xy -1.676 2.955)
        (xy -1.69 2.974)
        (xy -1.697 2.997)
        (xy -1.817 2.997)
        (xy -1.811 2.96)
        (xy -1.797 2.924)
        (xy -1.775 2.892)
        (xy -1.747 2.864)
        (xy -1.715 2.845)
        (xy -1.7 2.838)
        (xy -1.685 2.833)
        (xy -1.668 2.83)
        (xy -1.648 2.827)
        (xy -1.623 2.825)
        (xy -1.591 2.824)
        (xy -1.551 2.824)
        (xy -1.54 2.824)
        (xy -1.432 2.824)
        (xy -1.434 2.776)
        (xy -1.436 2.747)
        (xy -1.441 2.726)
        (xy -1.448 2.711)
        (xy -1.46 2.699)
        (xy -1.474 2.689)
        (xy -1.483 2.685)
        (xy -1.492 2.682)
        (xy -1.505 2.68)
        (xy -1.524 2.68)
        (xy -1.55 2.679)
        (xy -1.56 2.679)
        (xy -1.594 2.68)
        (xy -1.62 2.682)
        (xy -1.639 2.686)
        (xy -1.654 2.692)
        (xy -1.666 2.701)
        (xy -1.675 2.711)
        (xy -1.686 2.724)
        (xy -1.735 2.686)
        (xy -1.754 2.672)
        (xy -1.769 2.659)
        (xy -1.78 2.65)
        (xy -1.784 2.646)
        (xy -1.78 2.64)
        (xy -1.77 2.629)
        (xy -1.756 2.616)
        (xy -1.74 2.604)
        (xy -1.724 2.592)
        (xy -1.711 2.584)
        (xy -1.71 2.583)
        (xy -1.688 2.574)
        (xy -1.668 2.566)
        (xy -1.647 2.562)
        (xy -1.623 2.559)
        (xy -1.593 2.558)
        (xy -1.565 2.558)
        (xy -1.521 2.559)
      )

      (stroke (width 0.01) (type solid)) (fill solid) (layer "F.Cu"))
    (fp_poly
      (pts
        (xy 0.035 2.777)
        (xy 0.047 2.822)
        (xy 0.059 2.864)
        (xy 0.069 2.903)
        (xy 0.078 2.936)
        (xy 0.086 2.963)
        (xy 0.092 2.984)
        (xy 0.095 2.996)
        (xy 0.096 2.999)
        (xy 0.098 2.999)
        (xy 0.103 2.991)
        (xy 0.109 2.975)
        (xy 0.118 2.95)
        (xy 0.129 2.917)
        (xy 0.143 2.874)
        (xy 0.152 2.849)
        (xy 0.165 2.807)
        (xy 0.179 2.766)
        (xy 0.192 2.726)
        (xy 0.204 2.689)
        (xy 0.214 2.658)
        (xy 0.221 2.634)
        (xy 0.224 2.627)
        (xy 0.244 2.565)
        (xy 0.338 2.565)
        (xy 0.406 2.774)
        (xy 0.42 2.819)
        (xy 0.434 2.861)
        (xy 0.446 2.899)
        (xy 0.457 2.932)
        (xy 0.466 2.96)
        (xy 0.473 2.981)
        (xy 0.477 2.993)
        (xy 0.478 2.997)
        (xy 0.48 2.998)
        (xy 0.482 2.996)
        (xy 0.485 2.99)
        (xy 0.49 2.978)
        (xy 0.495 2.96)
        (xy 0.502 2.936)
        (xy 0.511 2.905)
        (xy 0.523 2.865)
        (xy 0.536 2.817)
        (xy 0.543 2.789)
        (xy 0.556 2.744)
        (xy 0.568 2.701)
        (xy 0.578 2.663)
        (xy 0.587 2.629)
        (xy 0.595 2.602)
        (xy 0.601 2.582)
        (xy 0.605 2.57)
        (xy 0.606 2.567)
        (xy 0.611 2.566)
        (xy 0.625 2.566)
        (xy 0.645 2.566)
        (xy 0.669 2.566)
        (xy 0.673 2.566)
        (xy 0.739 2.567)
        (xy 0.656 2.827)
        (xy 0.64 2.878)
        (xy 0.624 2.928)
        (xy 0.609 2.976)
        (xy 0.595 3.02)
        (xy 0.582 3.06)
        (xy 0.571 3.094)
        (xy 0.563 3.121)
        (xy 0.557 3.139)
        (xy 0.556 3.143)
        (xy 0.538 3.2)
        (xy 0.425 3.197)
        (xy 0.358 2.975)
        (xy 0.341 2.917)
        (xy 0.327 2.87)
        (xy 0.315 2.831)
        (xy 0.305 2.801)
        (xy 0.297 2.78)
        (xy 0.292 2.766)
        (xy 0.289 2.761)
        (xy 0.288 2.761)
        (xy 0.286 2.768)
        (xy 0.281 2.783)
        (xy 0.274 2.806)
        (xy 0.265 2.836)
        (xy 0.254 2.871)
        (xy 0.242 2.911)
        (xy 0.23 2.953)
        (xy 0.223 2.976)
        (xy 0.21 3.02)
        (xy 0.197 3.062)
        (xy 0.186 3.099)
        (xy 0.177 3.132)
        (xy 0.169 3.158)
        (xy 0.163 3.177)
        (xy 0.16 3.189)
        (xy 0.159 3.191)
        (xy 0.157 3.195)
        (xy 0.151 3.198)
        (xy 0.141 3.199)
        (xy 0.124 3.2)
        (xy 0.101 3.2)
        (xy 0.073 3.199)
        (xy 0.055 3.198)
        (xy 0.045 3.196)
        (xy 0.043 3.194)
        (xy 0.041 3.188)
        (xy 0.036 3.173)
        (xy 0.029 3.15)
        (xy 0.019 3.121)
        (xy 0.008 3.084)
        (xy -0.006 3.043)
        (xy -0.02 2.996)
        (xy -0.036 2.946)
        (xy -0.053 2.893)
        (xy -0.057 2.883)
        (xy -0.074 2.83)
        (xy -0.09 2.779)
        (xy -0.105 2.732)
        (xy -0.119 2.689)
        (xy -0.131 2.652)
        (xy -0.141 2.621)
        (xy -0.148 2.596)
        (xy -0.154 2.58)
        (xy -0.156 2.572)
        (xy -0.156 2.569)
        (xy -0.151 2.567)
        (xy -0.14 2.566)
        (xy -0.123 2.565)
        (xy -0.096 2.565)
        (xy -0.091 2.565)
        (xy -0.023 2.565)
        (xy 0.035 2.777)
      )

      (stroke (width 0.01) (type solid)) (fill solid) (layer "F.Cu"))
    (fp_poly
      (pts
        (xy -2.065 1.559)
        (xy -2.024 1.576)
        (xy -1.986 1.601)
        (xy -1.973 1.612)
        (xy -1.957 1.63)
        (xy -1.943 1.649)
        (xy -1.932 1.668)
        (xy -1.924 1.69)
        (xy -1.918 1.716)
        (xy -1.914 1.747)
        (xy -1.911 1.785)
        (xy -1.91 1.831)
        (xy -1.91 1.877)
        (xy -1.91 1.93)
        (xy -1.912 1.974)
        (xy -1.914 2.011)
        (xy -1.919 2.041)
        (xy -1.925 2.067)
        (xy -1.934 2.088)
        (xy -1.945 2.107)
        (xy -1.959 2.125)
        (xy -1.972 2.139)
        (xy -1.993 2.157)
        (xy -2.018 2.173)
        (xy -2.031 2.18)
        (xy -2.047 2.188)
        (xy -2.06 2.192)
        (xy -2.074 2.195)
        (xy -2.091 2.196)
        (xy -2.114 2.197)
        (xy -2.122 2.197)
        (xy -2.147 2.196)
        (xy -2.165 2.195)
        (xy -2.179 2.193)
        (xy -2.191 2.189)
        (xy -2.205 2.183)
        (xy -2.21 2.18)
        (xy -2.231 2.169)
        (xy -2.251 2.156)
        (xy -2.265 2.146)
        (xy -2.286 2.127)
        (xy -2.286 2.627)
        (xy -2.266 2.608)
        (xy -2.248 2.595)
        (xy -2.227 2.582)
        (xy -2.217 2.577)
        (xy -2.173 2.562)
        (xy -2.129 2.556)
        (xy -2.086 2.559)
        (xy -2.045 2.57)
        (xy -2.007 2.589)
        (xy -1.974 2.616)
        (xy -1.946 2.648)
        (xy -1.926 2.687)
        (xy -1.919 2.707)
        (xy -1.917 2.715)
        (xy -1.915 2.724)
        (xy -1.914 2.737)
        (xy -1.913 2.753)
        (xy -1.912 2.774)
        (xy -1.911 2.8)
        (xy -1.911 2.833)
        (xy -1.911 2.874)
        (xy -1.911 2.923)
        (xy -1.911 2.967)
        (xy -1.911 3.2)
        (xy -2.035 3.197)
        (xy -2.038 2.984)
        (xy -2.038 2.932)
        (xy -2.039 2.889)
        (xy -2.039 2.854)
        (xy -2.04 2.826)
        (xy -2.041 2.805)
        (xy -2.042 2.788)
        (xy -2.043 2.776)
        (xy -2.045 2.767)
        (xy -2.046 2.76)
        (xy -2.049 2.755)
        (xy -2.051 2.75)
        (xy -2.072 2.721)
        (xy -2.098 2.701)
        (xy -2.128 2.688)
        (xy -2.161 2.683)
        (xy -2.195 2.687)
        (xy -2.22 2.697)
        (xy -2.24 2.71)
        (xy -2.259 2.729)
        (xy -2.274 2.75)
        (xy -2.278 2.757)
        (xy -2.28 2.765)
        (xy -2.281 2.781)
        (xy -2.283 2.806)
        (xy -2.284 2.839)
        (xy -2.285 2.881)
        (xy -2.286 2.933)
        (xy -2.286 2.984)
        (xy -2.289 3.197)
        (xy -2.413 3.2)
        (xy -2.413 1.877)
        (xy -2.286 1.877)
        (xy -2.285 1.926)
        (xy -2.281 1.966)
        (xy -2.274 1.998)
        (xy -2.262 2.024)
        (xy -2.247 2.043)
        (xy -2.228 2.058)
        (xy -2.215 2.064)
        (xy -2.194 2.07)
        (xy -2.168 2.072)
        (xy -2.141 2.071)
        (xy -2.117 2.066)
        (xy -2.106 2.063)
        (xy -2.079 2.044)
        (xy -2.058 2.019)
        (xy -2.05 2.001)
        (xy -2.045 1.984)
        (xy -2.042 1.959)
        (xy -2.04 1.929)
        (xy -2.038 1.895)
        (xy -2.038 1.861)
        (xy -2.039 1.829)
        (xy -2.041 1.8)
        (xy -2.044 1.777)
        (xy -2.045 1.772)
        (xy -2.057 1.738)
        (xy -2.073 1.712)
        (xy -2.094 1.695)
        (xy -2.122 1.684)
        (xy -2.156 1.681)
        (xy -2.159 1.681)
        (xy -2.192 1.683)
        (xy -2.22 1.691)
        (xy -2.243 1.705)
        (xy -2.26 1.725)
        (xy -2.273 1.753)
        (xy -2.281 1.788)
        (xy -2.285 1.832)
        (xy -2.286 1.877)
        (xy -2.413 1.877)
        (xy -2.413 1.559)
        (xy -2.286 1.559)
        (xy -2.286 1.62)
        (xy -2.26 1.6)
        (xy -2.225 1.577)
        (xy -2.19 1.563)
        (xy -2.154 1.554)
        (xy -2.109 1.552)
        (xy -2.065 1.559)
      )

      (stroke (width 0.01) (type solid)) (fill solid) (layer "F.Cu"))
    (fp_poly
      (pts
        (xy 0.063 -3.201)
        (xy 0.118 -3.201)
        (xy 0.164 -3.201)
        (xy 0.202 -3.2)
        (xy 0.233 -3.2)
        (xy 0.258 -3.2)
        (xy 0.277 -3.199)
        (xy 0.292 -3.198)
        (xy 0.302 -3.197)
        (xy 0.309 -3.196)
        (xy 0.314 -3.195)
        (xy 0.317 -3.193)
        (xy 0.319 -3.192)
        (xy 0.321 -3.189)
        (xy 0.324 -3.183)
        (xy 0.327 -3.174)
        (xy 0.33 -3.161)
        (xy 0.334 -3.144)
        (xy 0.339 -3.12)
        (xy 0.345 -3.091)
        (xy 0.352 -3.054)
        (xy 0.361 -3.01)
        (xy 0.371 -2.958)
        (xy 0.382 -2.897)
        (xy 0.385 -2.878)
        (xy 0.395 -2.824)
        (xy 0.405 -2.772)
        (xy 0.414 -2.724)
        (xy 0.423 -2.68)
        (xy 0.43 -2.642)
        (xy 0.437 -2.61)
        (xy 0.442 -2.586)
        (xy 0.446 -2.569)
        (xy 0.448 -2.562)
        (xy 0.456 -2.55)
        (xy 0.464 -2.544)
        (xy 0.476 -2.539)
        (xy 0.495 -2.53)
        (xy 0.521 -2.519)
        (xy 0.552 -2.506)
        (xy 0.587 -2.492)
        (xy 0.624 -2.477)
        (xy 0.664 -2.461)
        (xy 0.704 -2.445)
        (xy 0.743 -2.43)
        (xy 0.78 -2.415)
        (xy 0.814 -2.402)
        (xy 0.843 -2.391)
        (xy 0.868 -2.382)
        (xy 0.885 -2.376)
        (xy 0.895 -2.373)
        (xy 0.896 -2.373)
        (xy 0.911 -2.376)
        (xy 0.931 -2.386)
        (xy 0.948 -2.397)
        (xy 0.962 -2.406)
        (xy 0.983 -2.421)
        (xy 1.011 -2.44)
        (xy 1.043 -2.462)
        (xy 1.079 -2.487)
        (xy 1.118 -2.513)
        (xy 1.158 -2.541)
        (xy 1.198 -2.568)
        (xy 1.238 -2.595)
        (xy 1.275 -2.621)
        (xy 1.309 -2.644)
        (xy 1.338 -2.665)
        (xy 1.362 -2.681)
        (xy 1.377 -2.691)
        (xy 1.398 -2.705)
        (xy 1.418 -2.717)
        (xy 1.433 -2.725)
        (xy 1.442 -2.728)
        (xy 1.443 -2.728)
        (xy 1.448 -2.726)
        (xy 1.456 -2.72)
        (xy 1.468 -2.71)
        (xy 1.486 -2.694)
        (xy 1.508 -2.673)
        (xy 1.535 -2.647)
        (xy 1.568 -2.614)
        (xy 1.608 -2.575)
        (xy 1.654 -2.53)
        (xy 1.675 -2.509)
        (xy 1.721 -2.462)
        (xy 1.761 -2.422)
        (xy 1.794 -2.388)
        (xy 1.822 -2.36)
        (xy 1.844 -2.337)
        (xy 1.862 -2.318)
        (xy 1.875 -2.304)
        (xy 1.884 -2.293)
        (xy 1.89 -2.284)
        (xy 1.893 -2.279)
        (xy 1.894 -2.275)
        (xy 1.892 -2.269)
        (xy 1.886 -2.257)
        (xy 1.875 -2.239)
        (xy 1.86 -2.215)
        (xy 1.839 -2.183)
        (xy 1.814 -2.145)
        (xy 1.783 -2.1)
        (xy 1.747 -2.046)
        (xy 1.721 -2.009)
        (xy 1.69 -1.964)
        (xy 1.661 -1.921)
        (xy 1.634 -1.88)
        (xy 1.609 -1.844)
        (xy 1.588 -1.811)
        (xy 1.57 -1.785)
        (xy 1.557 -1.764)
        (xy 1.549 -1.75)
        (xy 1.546 -1.743)
        (xy 1.547 -1.735)
        (xy 1.552 -1.719)
        (xy 1.56 -1.696)
        (xy 1.571 -1.667)
        (xy 1.585 -1.634)
        (xy 1.6 -1.597)
        (xy 1.616 -1.557)
        (xy 1.633 -1.516)
        (xy 1.651 -1.476)
        (xy 1.668 -1.436)
        (xy 1.685 -1.398)
        (xy 1.701 -1.363)
        (xy 1.715 -1.333)
        (xy 1.727 -1.309)
        (xy 1.736 -1.291)
        (xy 1.742 -1.281)
        (xy 1.744 -1.279)
        (xy 1.751 -1.277)
        (xy 1.767 -1.273)
        (xy 1.791 -1.268)
        (xy 1.822 -1.261)
        (xy 1.86 -1.254)
        (xy 1.903 -1.245)
        (xy 1.951 -1.236)
        (xy 2.002 -1.226)
        (xy 2.049 -1.217)
        (xy 2.103 -1.207)
        (xy 2.154 -1.198)
        (xy 2.201 -1.188)
        (xy 2.244 -1.18)
        (xy 2.281 -1.173)
        (xy 2.311 -1.166)
        (xy 2.335 -1.161)
        (xy 2.35 -1.157)
        (xy 2.355 -1.156)
        (xy 2.367 -1.148)
        (xy 2.367 -0.834)
        (xy 2.367 -0.768)
        (xy 2.367 -0.712)
        (xy 2.367 -0.664)
        (xy 2.366 -0.625)
        (xy 2.366 -0.592)
        (xy 2.365 -0.566)
        (xy 2.364 -0.546)
        (xy 2.363 -0.531)
        (xy 2.361 -0.52)
        (xy 2.358 -0.512)
        (xy 2.355 -0.507)
        (xy 2.352 -0.504)
        (xy 2.348 -0.503)
        (xy 2.343 -0.501)
        (xy 2.34 -0.501)
        (xy 2.333 -0.499)
        (xy 2.317 -0.496)
        (xy 2.293 -0.492)
        (xy 2.261 -0.486)
        (xy 2.224 -0.479)
        (xy 2.181 -0.471)
        (xy 2.134 -0.462)
        (xy 2.084 -0.453)
        (xy 2.054 -0.448)
        (xy 2.002 -0.438)
        (xy 1.953 -0.429)
        (xy 1.907 -0.42)
        (xy 1.866 -0.412)
        (xy 1.831 -0.404)
        (xy 1.802 -0.398)
        (xy 1.78 -0.394)
        (xy 1.767 -0.391)
        (xy 1.764 -0.39)
        (xy 1.76 -0.387)
        (xy 1.757 -0.384)
        (xy 1.753 -0.379)
        (xy 1.748 -0.371)
        (xy 1.742 -0.36)
        (xy 1.735 -0.344)
        (xy 1.726 -0.324)
        (xy 1.715 -0.297)
        (xy 1.701 -0.264)
        (xy 1.685 -0.223)
        (xy 1.665 -0.174)
        (xy 1.653 -0.145)
        (xy 1.63 -0.086)
        (xy 1.61 -0.037)
        (xy 1.594 0.005)
        (xy 1.582 0.038)
        (xy 1.572 0.064)
        (xy 1.566 0.084)
        (xy 1.562 0.097)
        (xy 1.561 0.104)
        (xy 1.562 0.105)
        (xy 1.565 0.111)
        (xy 1.574 0.125)
        (xy 1.587 0.146)
        (xy 1.604 0.173)
        (xy 1.626 0.205)
        (xy 1.65 0.241)
        (xy 1.677 0.281)
        (xy 1.706 0.324)
        (xy 1.729 0.358)
        (xy 1.768 0.413)
        (xy 1.8 0.461)
        (xy 1.827 0.502)
        (xy 1.85 0.535)
        (xy 1.867 0.562)
        (xy 1.88 0.583)
        (xy 1.889 0.598)
        (xy 1.893 0.608)
        (xy 1.894 0.612)
        (xy 1.893 0.616)
        (xy 1.89 0.622)
        (xy 1.885 0.63)
        (xy 1.876 0.64)
        (xy 1.863 0.655)
        (xy 1.846 0.673)
        (xy 1.825 0.695)
        (xy 1.798 0.723)
        (xy 1.765 0.756)
        (xy 1.727 0.795)
        (xy 1.682 0.839)
        (xy 1.635 0.886)
        (xy 1.595 0.926)
        (xy 1.561 0.96)
        (xy 1.532 0.989)
        (xy 1.508 1.012)
        (xy 1.488 1.03)
        (xy 1.473 1.044)
        (xy 1.461 1.054)
        (xy 1.452 1.061)
        (xy 1.445 1.065)
        (xy 1.44 1.066)
        (xy 1.438 1.066)
        (xy 1.433 1.064)
        (xy 1.421 1.055)
        (xy 1.401 1.043)
        (xy 1.376 1.026)
        (xy 1.345 1.005)
        (xy 1.31 0.981)
        (xy 1.27 0.954)
        (xy 1.228 0.925)
        (xy 1.193 0.901)
        (xy 1.138 0.864)
        (xy 1.089 0.83)
        (xy 1.046 0.802)
        (xy 1.01 0.778)
        (xy 0.981 0.759)
        (xy 0.96 0.746)
        (xy 0.946 0.738)
        (xy 0.94 0.736)
        (xy 0.932 0.738)
        (xy 0.917 0.745)
        (xy 0.895 0.755)
        (xy 0.869 0.768)
        (xy 0.84 0.783)
        (xy 0.816 0.795)
        (xy 0.781 0.814)
        (xy 0.753 0.828)
        (xy 0.732 0.838)
        (xy 0.717 0.845)
        (xy 0.707 0.849)
        (xy 0.699 0.85)
        (xy 0.694 0.849)
        (xy 0.691 0.847)
        (xy 0.687 0.84)
        (xy 0.682 0.829)
        (xy 0.674 0.814)
        (xy 0.665 0.793)
        (xy 0.653 0.767)
        (xy 0.639 0.735)
        (xy 0.623 0.696)
        (xy 0.604 0.651)
        (xy 0.582 0.598)
        (xy 0.556 0.538)
        (xy 0.528 0.469)
        (xy 0.496 0.391)
        (xy 0.47 0.329)
        (xy 0.436 0.247)
        (xy 0.406 0.173)
        (xy 0.379 0.108)
        (xy 0.355 0.05)
        (xy 0.335 0)
        (xy 0.317 -0.043)
        (xy 0.303 -0.079)
        (xy 0.291 -0.11)
        (xy 0.281 -0.135)
        (xy 0.273 -0.155)
        (xy 0.268 -0.171)
        (xy 0.264 -0.183)
        (xy 0.262 -0.191)
        (xy 0.262 -0.196)
        (xy 0.262 -0.198)
        (xy 0.269 -0.207)
        (xy 0.283 -0.219)
        (xy 0.302 -0.233)
        (xy 0.303 -0.234)
        (xy 0.354 -0.268)
        (xy 0.398 -0.3)
        (xy 0.435 -0.331)
        (xy 0.469 -0.363)
        (xy 0.5 -0.397)
        (xy 0.507 -0.405)
        (xy 0.556 -0.472)
        (xy 0.596 -0.543)
        (xy 0.627 -0.619)
        (xy 0.643 -0.672)
        (xy 0.651 -0.718)
        (xy 0.657 -0.77)
        (xy 0.66 -0.824)
        (xy 0.659 -0.878)
        (xy 0.654 -0.927)
        (xy 0.652 -0.936)
        (xy 0.634 -1.015)
        (xy 0.607 -1.09)
        (xy 0.571 -1.161)
        (xy 0.528 -1.227)
        (xy 0.477 -1.287)
        (xy 0.419 -1.341)
        (xy 0.355 -1.387)
        (xy 0.285 -1.426)
        (xy 0.21 -1.456)
        (xy 0.205 -1.458)
        (xy 0.131 -1.477)
        (xy 0.054 -1.487)
        (xy -0.025 -1.489)
        (xy -0.103 -1.482)
        (xy -0.178 -1.466)
        (xy -0.206 -1.458)
        (xy -0.281 -1.428)
        (xy -0.351 -1.39)
        (xy -0.416 -1.344)
        (xy -0.474 -1.29)
        (xy -0.526 -1.23)
        (xy -0.571 -1.164)
        (xy -0.607 -1.093)
        (xy -0.63 -1.034)
        (xy -0.649 -0.96)
        (xy -0.659 -0.883)
        (xy -0.661 -0.804)
        (xy -0.654 -0.726)
        (xy -0.638 -0.651)
        (xy -0.63 -0.623)
        (xy -0.618 -0.591)
        (xy -0.602 -0.554)
        (xy -0.584 -0.518)
        (xy -0.566 -0.485)
        (xy -0.553 -0.463)
        (xy -0.509 -0.407)
        (xy -0.457 -0.352)
        (xy -0.397 -0.299)
        (xy -0.33 -0.25)
        (xy -0.289 -0.224)
        (xy -0.273 -0.212)
        (xy -0.263 -0.2)
        (xy -0.262 -0.197)
        (xy -0.263 -0.19)
        (xy -0.268 -0.175)
        (xy -0.277 -0.151)
        (xy -0.288 -0.121)
        (xy -0.302 -0.084)
        (xy -0.319 -0.042)
        (xy -0.338 0.005)
        (xy -0.358 0.056)
        (xy -0.381 0.111)
        (xy -0.404 0.168)
        (xy -0.428 0.228)
        (xy -0.453 0.288)
        (xy -0.478 0.349)
        (xy -0.504 0.41)
        (xy -0.529 0.47)
        (xy -0.553 0.527)
        (xy -0.576 0.583)
        (xy -0.598 0.635)
        (xy -0.619 0.683)
        (xy -0.638 0.727)
        (xy -0.655 0.765)
        (xy -0.669 0.797)
        (xy -0.68 0.822)
        (xy -0.689 0.839)
        (xy -0.694 0.848)
        (xy -0.695 0.849)
        (xy -0.699 0.85)
        (xy -0.706 0.849)
        (xy -0.717 0.845)
        (xy -0.732 0.839)
        (xy -0.752 0.829)
        (xy -0.779 0.815)
        (xy -0.814 0.797)
        (xy -0.817 0.795)
        (xy -0.848 0.779)
        (xy -0.877 0.764)
        (xy -0.902 0.752)
        (xy -0.922 0.743)
        (xy -0.936 0.737)
        (xy -0.941 0.736)
        (xy -0.949 0.739)
        (xy -0.964 0.748)
        (xy -0.987 0.761)
        (xy -1.015 0.78)
        (xy -1.05 0.803)
        (xy -1.072 0.818)
        (xy -1.138 0.863)
        (xy -1.195 0.903)
        (xy -1.245 0.937)
        (xy -1.289 0.966)
        (xy -1.325 0.991)
        (xy -1.356 1.012)
        (xy -1.381 1.029)
        (xy -1.401 1.042)
        (xy -1.416 1.052)
        (xy -1.427 1.059)
        (xy -1.435 1.064)
        (xy -1.439 1.066)
        (xy -1.44 1.066)
        (xy -1.449 1.064)
        (xy -1.453 1.061)
        (xy -1.458 1.057)
        (xy -1.47 1.046)
        (xy -1.487 1.029)
        (xy -1.509 1.007)
        (xy -1.537 0.98)
        (xy -1.568 0.95)
        (xy -1.602 0.915)
        (xy -1.639 0.879)
        (xy -1.678 0.84)
        (xy -1.678 0.839)
        (xy -1.726 0.792)
        (xy -1.767 0.751)
        (xy -1.801 0.716)
        (xy -1.829 0.687)
        (xy -1.852 0.663)
        (xy -1.869 0.644)
        (xy -1.882 0.63)
        (xy -1.89 0.62)
        (xy -1.894 0.613)
        (xy -1.895 0.61)
        (xy -1.892 0.603)
        (xy -1.884 0.588)
        (xy -1.87 0.565)
        (xy -1.85 0.536)
        (xy -1.826 0.499)
        (xy -1.797 0.455)
        (xy -1.763 0.405)
        (xy -1.73 0.358)
        (xy -1.7 0.313)
        (xy -1.671 0.271)
        (xy -1.645 0.232)
        (xy -1.621 0.197)
        (xy -1.601 0.166)
        (xy -1.584 0.141)
        (xy -1.572 0.121)
        (xy -1.565 0.109)
        (xy -1.563 0.105)
        (xy -1.563 0.099)
        (xy -1.566 0.087)
        (xy -1.572 0.07)
        (xy -1.58 0.045)
        (xy -1.592 0.013)
        (xy -1.607 -0.026)
        (xy -1.626 -0.074)
        (xy -1.648 -0.13)
        (xy -1.654 -0.145)
        (xy -1.676 -0.199)
        (xy -1.695 -0.245)
        (xy -1.71 -0.282)
        (xy -1.723 -0.313)
        (xy -1.733 -0.337)
        (xy -1.741 -0.356)
        (xy -1.748 -0.369)
        (xy -1.753 -0.379)
        (xy -1.758 -0.385)
        (xy -1.761 -0.388)
        (xy -1.763 -0.389)
        (xy -1.767 -0.39)
        (xy -1.774 -0.392)
        (xy -1.784 -0.395)
        (xy -1.799 -0.398)
        (xy -1.818 -0.402)
        (xy -1.843 -0.407)
        (xy -1.873 -0.413)
        (xy -1.91 -0.42)
        (xy -1.954 -0.429)
        (xy -2.005 -0.438)
        (xy -2.065 -0.449)
        (xy -2.133 -0.462)
        (xy -2.211 -0.477)
        (xy -2.22 -0.478)
        (xy -2.26 -0.486)
        (xy -2.29 -0.491)
        (xy -2.313 -0.496)
        (xy -2.33 -0.499)
        (xy -2.341 -0.502)
        (xy -2.349 -0.504)
        (xy -2.353 -0.506)
        (xy -2.356 -0.508)
        (xy -2.359 -0.51)
        (xy -2.36 -0.511)
        (xy -2.361 -0.514)
        (xy -2.363 -0.518)
        (xy -2.364 -0.526)
        (xy -2.365 -0.536)
        (xy -2.366 -0.551)
        (xy -2.366 -0.571)
        (xy -2.367 -0.597)
        (xy -2.367 -0.629)
        (xy -2.368 -0.668)
        (xy -2.368 -0.715)
        (xy -2.368 -0.771)
        (xy -2.368 -0.834)
        (xy -2.368 -1.148)
        (xy -2.356 -1.155)
        (xy -2.349 -1.158)
        (xy -2.333 -1.162)
        (xy -2.309 -1.167)
        (xy -2.278 -1.173)
        (xy -2.24 -1.181)
        (xy -2.197 -1.189)
        (xy -2.149 -1.198)
        (xy -2.098 -1.208)
        (xy -2.051 -1.217)
        (xy -1.996 -1.227)
        (xy -1.945 -1.237)
        (xy -1.897 -1.246)
        (xy -1.854 -1.254)
        (xy -1.817 -1.262)
        (xy -1.787 -1.268)
        (xy -1.764 -1.273)
        (xy -1.75 -1.277)
        (xy -1.745 -1.279)
        (xy -1.741 -1.285)
        (xy -1.733 -1.3)
        (xy -1.722 -1.322)
        (xy -1.709 -1.35)
        (xy -1.694 -1.382)
        (xy -1.677 -1.419)
        (xy -1.66 -1.458)
        (xy -1.642 -1.498)
        (xy -1.625 -1.539)
        (xy -1.608 -1.58)
        (xy -1.592 -1.618)
        (xy -1.578 -1.653)
        (xy -1.565 -1.684)
        (xy -1.556 -1.709)
        (xy -1.549 -1.729)
        (xy -1.546 -1.74)
        (xy -1.546 -1.742)
        (xy -1.549 -1.749)
        (xy -1.558 -1.763)
        (xy -1.571 -1.784)
        (xy -1.588 -1.811)
        (xy -1.61 -1.843)
        (xy -1.634 -1.88)
        (xy -1.661 -1.92)
        (xy -1.691 -1.963)
        (xy -1.722 -2.008)
        (xy -1.762 -2.067)
        (xy -1.796 -2.117)
        (xy -1.825 -2.16)
        (xy -1.848 -2.196)
        (xy -1.867 -2.225)
        (xy -1.881 -2.247)
        (xy -1.89 -2.262)
        (xy -1.895 -2.272)
        (xy -1.895 -2.275)
        (xy -1.894 -2.279)
        (xy -1.891 -2.285)
        (xy -1.884 -2.293)
        (xy -1.875 -2.305)
        (xy -1.861 -2.32)
        (xy -1.843 -2.339)
        (xy -1.82 -2.363)
        (xy -1.792 -2.392)
        (xy -1.758 -2.426)
        (xy -1.718 -2.466)
        (xy -1.676 -2.509)
        (xy -1.627 -2.557)
        (xy -1.585 -2.599)
        (xy -1.549 -2.634)
        (xy -1.52 -2.663)
        (xy -1.495 -2.686)
        (xy -1.476 -2.704)
        (xy -1.462 -2.716)
        (xy -1.452 -2.724)
        (xy -1.446 -2.728)
        (xy -1.444 -2.728)
        (xy -1.437 -2.726)
        (xy -1.423 -2.717)
        (xy -1.401 -2.703)
        (xy -1.372 -2.685)
        (xy -1.337 -2.661)
        (xy -1.295 -2.634)
        (xy -1.248 -2.602)
        (xy -1.196 -2.566)
        (xy -1.173 -2.551)
        (xy -1.118 -2.513)
        (xy -1.071 -2.481)
        (xy -1.031 -2.454)
        (xy -0.998 -2.432)
        (xy -0.97 -2.413)
        (xy -0.948 -2.399)
        (xy -0.931 -2.389)
        (xy -0.917 -2.381)
        (xy -0.907 -2.376)
        (xy -0.901 -2.373)
        (xy -0.897 -2.373)
        (xy -0.888 -2.375)
        (xy -0.87 -2.38)
        (xy -0.845 -2.39)
        (xy -0.813 -2.402)
        (xy -0.774 -2.417)
        (xy -0.73 -2.434)
        (xy -0.681 -2.454)
        (xy -0.629 -2.475)
        (xy -0.586 -2.493)
        (xy -0.55 -2.508)
        (xy -0.522 -2.52)
        (xy -0.499 -2.529)
        (xy -0.482 -2.537)
        (xy -0.47 -2.543)
        (xy -0.461 -2.548)
        (xy -0.455 -2.551)
        (xy -0.452 -2.554)
        (xy -0.449 -2.557)
        (xy -0.448 -2.56)
        (xy -0.447 -2.566)
        (xy -0.443 -2.582)
        (xy -0.438 -2.605)
        (xy -0.432 -2.637)
        (xy -0.425 -2.674)
        (xy -0.417 -2.717)
        (xy -0.407 -2.765)
        (xy -0.398 -2.817)
        (xy -0.388 -2.871)
        (xy -0.387 -2.876)
        (xy -0.375 -2.94)
        (xy -0.364 -2.995)
        (xy -0.356 -3.042)
        (xy -0.348 -3.081)
        (xy -0.342 -3.112)
        (xy -0.337 -3.137)
        (xy -0.332 -3.157)
        (xy -0.328 -3.171)
        (xy -0.325 -3.181)
        (xy -0.323 -3.188)
        (xy -0.32 -3.191)
        (xy -0.32 -3.192)
        (xy -0.317 -3.194)
        (xy -0.313 -3.195)
        (xy -0.307 -3.197)
        (xy -0.298 -3.198)
        (xy -0.286 -3.199)
        (xy -0.269 -3.199)
        (xy -0.247 -3.2)
        (xy -0.219 -3.2)
        (xy -0.184 -3.201)
        (xy -0.142 -3.201)
        (xy -0.092 -3.201)
        (xy -0.033 -3.201)
        (xy -0.001 -3.201)
        (xy 0.063 -3.201)
      )

      (stroke (width 0.01) (type solid)) (fill solid) (layer "F.Cu"))
    (fp_poly
      (pts
        (xy -0.843 2.558)
        (xy -0.815 2.564)
        (xy -0.794 2.572)
        (xy -0.773 2.581)
        (xy -0.759 2.589)
        (xy -0.738 2.603)
        (xy -0.783 2.658)
        (xy -0.8 2.677)
        (xy -0.814 2.694)
        (xy -0.825 2.706)
        (xy -0.831 2.712)
        (xy -0.832 2.712)
        (xy -0.837 2.71)
        (xy -0.847 2.703)
        (xy -0.849 2.702)
        (xy -0.874 2.69)
        (xy -0.904 2.684)
        (xy -0.935 2.685)
        (xy -0.942 2.686)
        (xy -0.975 2.698)
        (xy -1.001 2.717)
        (xy -1.02 2.741)
        (xy -1.034 2.766)
        (xy -1.039 3.197)
        (xy -1.164 3.2)
        (xy -1.164 2.565)
        (xy -1.037 2.565)
        (xy -1.037 2.626)
        (xy -1.009 2.604)
        (xy -0.972 2.579)
        (xy -0.931 2.563)
        (xy -0.887 2.556)
        (xy -0.843 2.558)
      )

      (stroke (width 0.01) (type solid)) (fill solid) (layer "F.Mask"))
    (fp_poly
      (pts
        (xy 1.889 1.554)
        (xy 1.907 1.559)
        (xy 1.927 1.566)
        (xy 1.948 1.574)
        (xy 1.966 1.583)
        (xy 1.979 1.592)
        (xy 1.984 1.597)
        (xy 1.982 1.604)
        (xy 1.974 1.616)
        (xy 1.962 1.633)
        (xy 1.946 1.652)
        (xy 1.945 1.654)
        (xy 1.929 1.673)
        (xy 1.915 1.689)
        (xy 1.906 1.7)
        (xy 1.901 1.706)
        (xy 1.896 1.705)
        (xy 1.885 1.7)
        (xy 1.873 1.695)
        (xy 1.84 1.683)
        (xy 1.808 1.68)
        (xy 1.776 1.685)
        (xy 1.747 1.698)
        (xy 1.723 1.717)
        (xy 1.704 1.742)
        (xy 1.696 1.763)
        (xy 1.695 1.772)
        (xy 1.694 1.79)
        (xy 1.693 1.817)
        (xy 1.692 1.85)
        (xy 1.692 1.89)
        (xy 1.691 1.934)
        (xy 1.691 1.983)
        (xy 1.691 2.194)
        (xy 1.559 2.194)
        (xy 1.559 1.559)
        (xy 1.691 1.559)
        (xy 1.691 1.626)
        (xy 1.71 1.607)
        (xy 1.739 1.585)
        (xy 1.775 1.568)
        (xy 1.814 1.556)
        (xy 1.855 1.552)
        (xy 1.889 1.554)
      )

      (stroke (width 0.01) (type solid)) (fill solid) (layer "F.Mask"))
    (fp_poly
      (pts
        (xy -0.837 1.56)
        (xy -0.797 1.576)
        (xy -0.761 1.6)
        (xy -0.73 1.63)
        (xy -0.706 1.667)
        (xy -0.69 1.709)
        (xy -0.687 1.721)
        (xy -0.685 1.734)
        (xy -0.684 1.757)
        (xy -0.683 1.79)
        (xy -0.682 1.833)
        (xy -0.681 1.884)
        (xy -0.681 1.945)
        (xy -0.681 1.971)
        (xy -0.681 2.194)
        (xy -0.808 2.194)
        (xy -0.809 1.984)
        (xy -0.811 1.774)
        (xy -0.826 1.744)
        (xy -0.845 1.716)
        (xy -0.868 1.697)
        (xy -0.897 1.686)
        (xy -0.925 1.682)
        (xy -0.947 1.682)
        (xy -0.967 1.684)
        (xy -0.979 1.686)
        (xy -1.001 1.698)
        (xy -1.023 1.716)
        (xy -1.041 1.738)
        (xy -1.049 1.752)
        (xy -1.052 1.758)
        (xy -1.054 1.765)
        (xy -1.056 1.773)
        (xy -1.057 1.783)
        (xy -1.058 1.797)
        (xy -1.059 1.815)
        (xy -1.06 1.839)
        (xy -1.06 1.869)
        (xy -1.061 1.907)
        (xy -1.061 1.953)
        (xy -1.061 1.985)
        (xy -1.063 2.194)
        (xy -1.189 2.194)
        (xy -1.189 1.559)
        (xy -1.062 1.559)
        (xy -1.062 1.625)
        (xy -1.033 1.602)
        (xy -1.001 1.579)
        (xy -0.969 1.564)
        (xy -0.934 1.555)
        (xy -0.927 1.554)
        (xy -0.881 1.553)
        (xy -0.837 1.56)
      )

      (stroke (width 0.01) (type solid)) (fill solid) (layer "F.Mask"))
    (fp_poly
      (pts
        (xy 1.042 1.769)
        (xy 1.043 1.979)
        (xy 1.059 2.009)
        (xy 1.077 2.036)
        (xy 1.1 2.056)
        (xy 1.129 2.067)
        (xy 1.159 2.071)
        (xy 1.193 2.07)
        (xy 1.221 2.063)
        (xy 1.245 2.047)
        (xy 1.258 2.034)
        (xy 1.266 2.025)
        (xy 1.273 2.016)
        (xy 1.278 2.008)
        (xy 1.282 1.997)
        (xy 1.286 1.985)
        (xy 1.288 1.969)
        (xy 1.29 1.948)
        (xy 1.291 1.922)
        (xy 1.292 1.89)
        (xy 1.293 1.85)
        (xy 1.293 1.801)
        (xy 1.294 1.766)
        (xy 1.295 1.559)
        (xy 1.422 1.559)
        (xy 1.422 2.194)
        (xy 1.295 2.194)
        (xy 1.295 2.161)
        (xy 1.295 2.144)
        (xy 1.293 2.132)
        (xy 1.292 2.128)
        (xy 1.287 2.131)
        (xy 1.278 2.14)
        (xy 1.271 2.147)
        (xy 1.256 2.159)
        (xy 1.236 2.171)
        (xy 1.219 2.181)
        (xy 1.202 2.188)
        (xy 1.186 2.193)
        (xy 1.17 2.196)
        (xy 1.148 2.197)
        (xy 1.135 2.198)
        (xy 1.107 2.198)
        (xy 1.087 2.197)
        (xy 1.07 2.194)
        (xy 1.059 2.19)
        (xy 1.036 2.181)
        (xy 1.019 2.172)
        (xy 1.003 2.161)
        (xy 0.985 2.146)
        (xy 0.981 2.141)
        (xy 0.952 2.107)
        (xy 0.931 2.068)
        (xy 0.92 2.033)
        (xy 0.918 2.019)
        (xy 0.917 1.996)
        (xy 0.916 1.963)
        (xy 0.915 1.92)
        (xy 0.914 1.869)
        (xy 0.914 1.808)
        (xy 0.914 1.782)
        (xy 0.914 1.559)
        (xy 1.04 1.559)
        (xy 1.042 1.769)
      )

      (stroke (width 0.01) (type solid)) (fill solid) (layer "F.Mask"))
    (fp_poly
      (pts
        (xy 1.753 2.563)
        (xy 1.768 2.568)
        (xy 1.787 2.577)
        (xy 1.804 2.586)
        (xy 1.818 2.595)
        (xy 1.826 2.602)
        (xy 1.827 2.606)
        (xy 1.824 2.611)
        (xy 1.815 2.621)
        (xy 1.803 2.636)
        (xy 1.789 2.654)
        (xy 1.775 2.671)
        (xy 1.761 2.688)
        (xy 1.749 2.701)
        (xy 1.742 2.71)
        (xy 1.739 2.712)
        (xy 1.735 2.71)
        (xy 1.724 2.704)
        (xy 1.713 2.698)
        (xy 1.697 2.69)
        (xy 1.682 2.686)
        (xy 1.664 2.685)
        (xy 1.653 2.685)
        (xy 1.618 2.688)
        (xy 1.59 2.699)
        (xy 1.566 2.718)
        (xy 1.561 2.723)
        (xy 1.554 2.732)
        (xy 1.548 2.74)
        (xy 1.544 2.748)
        (xy 1.54 2.758)
        (xy 1.537 2.769)
        (xy 1.534 2.785)
        (xy 1.533 2.804)
        (xy 1.532 2.829)
        (xy 1.531 2.861)
        (xy 1.53 2.899)
        (xy 1.53 2.947)
        (xy 1.53 2.988)
        (xy 1.528 3.2)
        (xy 1.468 3.2)
        (xy 1.444 3.2)
        (xy 1.425 3.199)
        (xy 1.411 3.198)
        (xy 1.405 3.197)
        (xy 1.404 3.191)
        (xy 1.404 3.176)
        (xy 1.403 3.153)
        (xy 1.403 3.122)
        (xy 1.402 3.085)
        (xy 1.402 3.042)
        (xy 1.402 2.993)
        (xy 1.402 2.941)
        (xy 1.402 2.886)
        (xy 1.402 2.565)
        (xy 1.529 2.565)
        (xy 1.529 2.595)
        (xy 1.529 2.611)
        (xy 1.53 2.623)
        (xy 1.532 2.626)
        (xy 1.537 2.623)
        (xy 1.547 2.615)
        (xy 1.554 2.608)
        (xy 1.588 2.584)
        (xy 1.627 2.567)
        (xy 1.669 2.558)
        (xy 1.712 2.556)
        (xy 1.753 2.563)
      )

      (stroke (width 0.01) (type solid)) (fill solid) (layer "F.Mask"))
    (fp_poly
      (pts
        (xy 2.316 1.557)
        (xy 2.365 1.57)
        (xy 2.41 1.593)
        (xy 2.453 1.625)
        (xy 2.46 1.631)
        (xy 2.491 1.661)
        (xy 2.466 1.684)
        (xy 2.448 1.699)
        (xy 2.43 1.715)
        (xy 2.419 1.725)
        (xy 2.397 1.743)
        (xy 2.376 1.724)
        (xy 2.345 1.701)
        (xy 2.312 1.687)
        (xy 2.274 1.681)
        (xy 2.265 1.681)
        (xy 2.226 1.684)
        (xy 2.195 1.693)
        (xy 2.167 1.708)
        (xy 2.159 1.715)
        (xy 2.136 1.741)
        (xy 2.118 1.776)
        (xy 2.107 1.817)
        (xy 2.103 1.866)
        (xy 2.103 1.876)
        (xy 2.106 1.926)
        (xy 2.116 1.97)
        (xy 2.132 2.006)
        (xy 2.155 2.034)
        (xy 2.184 2.055)
        (xy 2.219 2.067)
        (xy 2.259 2.072)
        (xy 2.274 2.071)
        (xy 2.309 2.066)
        (xy 2.339 2.056)
        (xy 2.366 2.038)
        (xy 2.377 2.028)
        (xy 2.386 2.02)
        (xy 2.393 2.016)
        (xy 2.4 2.015)
        (xy 2.409 2.018)
        (xy 2.42 2.027)
        (xy 2.436 2.041)
        (xy 2.456 2.059)
        (xy 2.491 2.092)
        (xy 2.476 2.108)
        (xy 2.449 2.132)
        (xy 2.416 2.155)
        (xy 2.38 2.174)
        (xy 2.35 2.186)
        (xy 2.327 2.193)
        (xy 2.306 2.197)
        (xy 2.283 2.199)
        (xy 2.259 2.199)
        (xy 2.233 2.198)
        (xy 2.209 2.196)
        (xy 2.189 2.193)
        (xy 2.182 2.191)
        (xy 2.133 2.173)
        (xy 2.089 2.146)
        (xy 2.053 2.112)
        (xy 2.023 2.071)
        (xy 2.012 2.051)
        (xy 2 2.023)
        (xy 1.991 1.999)
        (xy 1.984 1.975)
        (xy 1.981 1.948)
        (xy 1.979 1.917)
        (xy 1.978 1.879)
        (xy 1.978 1.877)
        (xy 1.979 1.838)
        (xy 1.98 1.806)
        (xy 1.984 1.78)
        (xy 1.99 1.756)
        (xy 1.999 1.731)
        (xy 2.011 1.704)
        (xy 2.012 1.701)
        (xy 2.039 1.657)
        (xy 2.072 1.62)
        (xy 2.111 1.591)
        (xy 2.156 1.57)
        (xy 2.207 1.557)
        (xy 2.263 1.552)
        (xy 2.316 1.557)
      )

      (stroke (width 0.01) (type solid)) (fill solid) (layer "F.Mask"))
    (fp_poly
      (pts
        (xy -1.494 1.56)
        (xy -1.447 1.576)
        (xy -1.405 1.6)
        (xy -1.368 1.633)
        (xy -1.341 1.668)
        (xy -1.326 1.692)
        (xy -1.316 1.716)
        (xy -1.308 1.743)
        (xy -1.302 1.774)
        (xy -1.299 1.811)
        (xy -1.297 1.845)
        (xy -1.294 1.925)
        (xy -1.692 1.925)
        (xy -1.692 1.942)
        (xy -1.687 1.977)
        (xy -1.673 2.011)
        (xy -1.65 2.039)
        (xy -1.626 2.059)
        (xy -1.601 2.071)
        (xy -1.572 2.078)
        (xy -1.537 2.079)
        (xy -1.497 2.074)
        (xy -1.458 2.06)
        (xy -1.422 2.036)
        (xy -1.421 2.036)
        (xy -1.402 2.021)
        (xy -1.359 2.057)
        (xy -1.342 2.072)
        (xy -1.327 2.085)
        (xy -1.317 2.094)
        (xy -1.314 2.098)
        (xy -1.316 2.103)
        (xy -1.324 2.113)
        (xy -1.338 2.126)
        (xy -1.354 2.139)
        (xy -1.372 2.152)
        (xy -1.389 2.163)
        (xy -1.399 2.168)
        (xy -1.421 2.178)
        (xy -1.445 2.187)
        (xy -1.461 2.191)
        (xy -1.488 2.196)
        (xy -1.522 2.199)
        (xy -1.557 2.199)
        (xy -1.591 2.196)
        (xy -1.62 2.192)
        (xy -1.629 2.19)
        (xy -1.677 2.171)
        (xy -1.718 2.146)
        (xy -1.752 2.114)
        (xy -1.779 2.074)
        (xy -1.8 2.026)
        (xy -1.802 2.02)
        (xy -1.81 1.989)
        (xy -1.815 1.951)
        (xy -1.818 1.908)
        (xy -1.819 1.865)
        (xy -1.818 1.823)
        (xy -1.816 1.804)
        (xy -1.692 1.804)
        (xy -1.692 1.818)
        (xy -1.428 1.818)
        (xy -1.428 1.801)
        (xy -1.432 1.775)
        (xy -1.442 1.748)
        (xy -1.457 1.722)
        (xy -1.469 1.707)
        (xy -1.495 1.688)
        (xy -1.526 1.676)
        (xy -1.56 1.672)
        (xy -1.593 1.676)
        (xy -1.619 1.685)
        (xy -1.646 1.704)
        (xy -1.668 1.73)
        (xy -1.683 1.76)
        (xy -1.691 1.792)
        (xy -1.692 1.804)
        (xy -1.816 1.804)
        (xy -1.814 1.786)
        (xy -1.812 1.777)
        (xy -1.797 1.724)
        (xy -1.775 1.676)
        (xy -1.747 1.636)
        (xy -1.713 1.603)
        (xy -1.673 1.578)
        (xy -1.629 1.561)
        (xy -1.597 1.554)
        (xy -1.544 1.552)
        (xy -1.494 1.56)
      )

      (stroke (width 0.01) (type solid)) (fill solid) (layer "F.Mask"))
    (fp_poly
      (pts
        (xy 2.835 1.557)
        (xy 2.883 1.57)
        (xy 2.926 1.592)
        (xy 2.964 1.621)
        (xy 2.996 1.657)
        (xy 3.021 1.699)
        (xy 3.038 1.747)
        (xy 3.04 1.757)
        (xy 3.043 1.776)
        (xy 3.045 1.802)
        (xy 3.047 1.832)
        (xy 3.047 1.858)
        (xy 3.047 1.925)
        (xy 2.65 1.925)
        (xy 2.653 1.951)
        (xy 2.663 1.991)
        (xy 2.68 2.024)
        (xy 2.703 2.049)
        (xy 2.733 2.067)
        (xy 2.77 2.077)
        (xy 2.801 2.079)
        (xy 2.845 2.075)
        (xy 2.883 2.063)
        (xy 2.916 2.042)
        (xy 2.92 2.039)
        (xy 2.929 2.031)
        (xy 2.935 2.026)
        (xy 2.941 2.025)
        (xy 2.949 2.027)
        (xy 2.959 2.034)
        (xy 2.974 2.047)
        (xy 2.994 2.064)
        (xy 3.01 2.078)
        (xy 3.023 2.088)
        (xy 3.03 2.095)
        (xy 3.032 2.096)
        (xy 3.03 2.1)
        (xy 3.022 2.11)
        (xy 3.01 2.122)
        (xy 3.009 2.123)
        (xy 2.98 2.147)
        (xy 2.945 2.169)
        (xy 2.906 2.185)
        (xy 2.887 2.191)
        (xy 2.861 2.196)
        (xy 2.828 2.198)
        (xy 2.793 2.198)
        (xy 2.759 2.197)
        (xy 2.729 2.193)
        (xy 2.721 2.191)
        (xy 2.675 2.175)
        (xy 2.634 2.15)
        (xy 2.599 2.118)
        (xy 2.569 2.077)
        (xy 2.547 2.029)
        (xy 2.536 1.996)
        (xy 2.532 1.973)
        (xy 2.529 1.942)
        (xy 2.527 1.906)
        (xy 2.527 1.869)
        (xy 2.528 1.832)
        (xy 2.529 1.818)
        (xy 2.65 1.818)
        (xy 2.922 1.818)
        (xy 2.918 1.799)
        (xy 2.908 1.758)
        (xy 2.891 1.725)
        (xy 2.869 1.7)
        (xy 2.84 1.683)
        (xy 2.826 1.678)
        (xy 2.788 1.672)
        (xy 2.753 1.675)
        (xy 2.722 1.687)
        (xy 2.695 1.706)
        (xy 2.674 1.734)
        (xy 2.659 1.768)
        (xy 2.654 1.794)
        (xy 2.65 1.818)
        (xy 2.529 1.818)
        (xy 2.53 1.798)
        (xy 2.534 1.769)
        (xy 2.536 1.76)
        (xy 2.554 1.707)
        (xy 2.578 1.662)
        (xy 2.609 1.624)
        (xy 2.645 1.593)
        (xy 2.687 1.571)
        (xy 2.734 1.557)
        (xy 2.783 1.553)
        (xy 2.835 1.557)
      )

      (stroke (width 0.01) (type solid)) (fill solid) (layer "F.Mask"))
    (fp_poly
      (pts
        (xy -2.733 1.557)
        (xy -2.685 1.57)
        (xy -2.642 1.592)
        (xy -2.604 1.622)
        (xy -2.581 1.649)
        (xy -2.562 1.676)
        (xy -2.548 1.706)
        (xy -2.537 1.739)
        (xy -2.53 1.777)
        (xy -2.527 1.821)
        (xy -2.526 1.873)
        (xy -2.527 1.907)
        (xy -2.529 1.956)
        (xy -2.534 1.997)
        (xy -2.542 2.031)
        (xy -2.553 2.06)
        (xy -2.567 2.086)
        (xy -2.587 2.111)
        (xy -2.603 2.129)
        (xy -2.637 2.158)
        (xy -2.673 2.178)
        (xy -2.714 2.192)
        (xy -2.76 2.198)
        (xy -2.789 2.199)
        (xy -2.813 2.198)
        (xy -2.835 2.196)
        (xy -2.852 2.194)
        (xy -2.857 2.194)
        (xy -2.898 2.179)
        (xy -2.937 2.155)
        (xy -2.97 2.126)
        (xy -2.993 2.101)
        (xy -3.011 2.077)
        (xy -3.024 2.051)
        (xy -3.034 2.022)
        (xy -3.041 1.988)
        (xy -3.045 1.947)
        (xy -3.047 1.91)
        (xy -3.047 1.882)
        (xy -2.919 1.882)
        (xy -2.919 1.968)
        (xy -2.903 2.001)
        (xy -2.885 2.031)
        (xy -2.863 2.051)
        (xy -2.837 2.064)
        (xy -2.804 2.07)
        (xy -2.779 2.07)
        (xy -2.755 2.069)
        (xy -2.737 2.065)
        (xy -2.722 2.058)
        (xy -2.717 2.055)
        (xy -2.697 2.041)
        (xy -2.681 2.025)
        (xy -2.67 2.004)
        (xy -2.662 1.978)
        (xy -2.657 1.945)
        (xy -2.654 1.903)
        (xy -2.654 1.899)
        (xy -2.653 1.848)
        (xy -2.656 1.806)
        (xy -2.662 1.772)
        (xy -2.673 1.744)
        (xy -2.687 1.722)
        (xy -2.707 1.705)
        (xy -2.723 1.695)
        (xy -2.755 1.684)
        (xy -2.788 1.68)
        (xy -2.821 1.684)
        (xy -2.851 1.695)
        (xy -2.877 1.713)
        (xy -2.892 1.729)
        (xy -2.901 1.745)
        (xy -2.908 1.76)
        (xy -2.913 1.778)
        (xy -2.916 1.8)
        (xy -2.918 1.828)
        (xy -2.919 1.864)
        (xy -2.919 1.882)
        (xy -3.047 1.882)
        (xy -3.048 1.844)
        (xy -3.043 1.786)
        (xy -3.034 1.736)
        (xy -3.021 1.695)
        (xy -3.004 1.664)
        (xy -2.972 1.624)
        (xy -2.935 1.594)
        (xy -2.893 1.571)
        (xy -2.846 1.558)
        (xy -2.794 1.553)
        (xy -2.787 1.553)
        (xy -2.733 1.557)
      )

      (stroke (width 0.01) (type solid)) (fill solid) (layer "F.Mask"))
    (fp_poly
      (pts
        (xy 2.148 2.561)
        (xy 2.193 2.574)
        (xy 2.235 2.595)
        (xy 2.273 2.623)
        (xy 2.304 2.657)
        (xy 2.326 2.691)
        (xy 2.338 2.718)
        (xy 2.346 2.745)
        (xy 2.352 2.774)
        (xy 2.355 2.808)
        (xy 2.357 2.85)
        (xy 2.357 2.858)
        (xy 2.357 2.931)
        (xy 1.96 2.931)
        (xy 1.963 2.955)
        (xy 1.973 2.993)
        (xy 1.991 3.026)
        (xy 2.015 3.053)
        (xy 2.039 3.069)
        (xy 2.057 3.076)
        (xy 2.08 3.08)
        (xy 2.103 3.082)
        (xy 2.144 3.081)
        (xy 2.18 3.071)
        (xy 2.214 3.054)
        (xy 2.227 3.045)
        (xy 2.24 3.035)
        (xy 2.25 3.029)
        (xy 2.253 3.027)
        (xy 2.258 3.03)
        (xy 2.269 3.039)
        (xy 2.284 3.05)
        (xy 2.3 3.064)
        (xy 2.315 3.078)
        (xy 2.329 3.09)
        (xy 2.338 3.099)
        (xy 2.341 3.103)
        (xy 2.337 3.11)
        (xy 2.327 3.121)
        (xy 2.312 3.134)
        (xy 2.294 3.148)
        (xy 2.276 3.161)
        (xy 2.259 3.171)
        (xy 2.252 3.175)
        (xy 2.204 3.192)
        (xy 2.152 3.202)
        (xy 2.098 3.204)
        (xy 2.046 3.198)
        (xy 2.032 3.195)
        (xy 1.984 3.178)
        (xy 1.943 3.154)
        (xy 1.909 3.123)
        (xy 1.881 3.084)
        (xy 1.859 3.037)
        (xy 1.847 3.003)
        (xy 1.841 2.972)
        (xy 1.838 2.934)
        (xy 1.836 2.893)
        (xy 1.837 2.851)
        (xy 1.839 2.824)
        (xy 1.96 2.824)
        (xy 2.23 2.824)
        (xy 2.23 2.813)
        (xy 2.225 2.783)
        (xy 2.214 2.753)
        (xy 2.196 2.725)
        (xy 2.175 2.702)
        (xy 2.151 2.686)
        (xy 2.128 2.68)
        (xy 2.101 2.677)
        (xy 2.072 2.678)
        (xy 2.051 2.683)
        (xy 2.023 2.696)
        (xy 2 2.717)
        (xy 1.981 2.746)
        (xy 1.968 2.779)
        (xy 1.963 2.8)
        (xy 1.96 2.824)
        (xy 1.839 2.824)
        (xy 1.839 2.811)
        (xy 1.844 2.776)
        (xy 1.848 2.76)
        (xy 1.866 2.708)
        (xy 1.889 2.663)
        (xy 1.919 2.627)
        (xy 1.954 2.598)
        (xy 1.996 2.575)
        (xy 2.007 2.571)
        (xy 2.054 2.559)
        (xy 2.101 2.556)
        (xy 2.148 2.561)
      )

      (stroke (width 0.01) (type solid)) (fill solid) (layer "F.Mask"))
    (fp_poly
      (pts
        (xy -0.229 3.2)
        (xy -0.354 3.197)
        (xy -0.355 3.165)
        (xy -0.357 3.133)
        (xy -0.374 3.148)
        (xy -0.411 3.175)
        (xy -0.453 3.193)
        (xy -0.497 3.203)
        (xy -0.542 3.204)
        (xy -0.585 3.195)
        (xy -0.586 3.195)
        (xy -0.621 3.181)
        (xy -0.651 3.16)
        (xy -0.673 3.141)
        (xy -0.689 3.123)
        (xy -0.702 3.106)
        (xy -0.712 3.086)
        (xy -0.72 3.064)
        (xy -0.726 3.038)
        (xy -0.73 3.007)
        (xy -0.732 2.968)
        (xy -0.733 2.922)
        (xy -0.733 2.88)
        (xy -0.602 2.88)
        (xy -0.602 2.915)
        (xy -0.602 2.942)
        (xy -0.601 2.962)
        (xy -0.6 2.977)
        (xy -0.598 2.988)
        (xy -0.596 2.998)
        (xy -0.592 3.007)
        (xy -0.591 3.01)
        (xy -0.574 3.039)
        (xy -0.552 3.059)
        (xy -0.525 3.071)
        (xy -0.492 3.076)
        (xy -0.472 3.076)
        (xy -0.442 3.072)
        (xy -0.418 3.063)
        (xy -0.398 3.048)
        (xy -0.382 3.029)
        (xy -0.371 3.004)
        (xy -0.363 2.972)
        (xy -0.358 2.933)
        (xy -0.356 2.885)
        (xy -0.356 2.88)
        (xy -0.358 2.828)
        (xy -0.363 2.785)
        (xy -0.373 2.75)
        (xy -0.387 2.724)
        (xy -0.406 2.704)
        (xy -0.43 2.692)
        (xy -0.46 2.686)
        (xy -0.483 2.685)
        (xy -0.517 2.687)
        (xy -0.544 2.696)
        (xy -0.565 2.711)
        (xy -0.583 2.734)
        (xy -0.591 2.751)
        (xy -0.595 2.76)
        (xy -0.598 2.769)
        (xy -0.6 2.779)
        (xy -0.601 2.793)
        (xy -0.602 2.811)
        (xy -0.602 2.836)
        (xy -0.602 2.869)
        (xy -0.602 2.88)
        (xy -0.733 2.88)
        (xy -0.733 2.827)
        (xy -0.732 2.783)
        (xy -0.729 2.746)
        (xy -0.725 2.716)
        (xy -0.719 2.691)
        (xy -0.71 2.67)
        (xy -0.699 2.651)
        (xy -0.685 2.633)
        (xy -0.668 2.616)
        (xy -0.668 2.615)
        (xy -0.632 2.587)
        (xy -0.592 2.567)
        (xy -0.55 2.557)
        (xy -0.506 2.556)
        (xy -0.463 2.564)
        (xy -0.421 2.582)
        (xy -0.411 2.587)
        (xy -0.394 2.598)
        (xy -0.377 2.61)
        (xy -0.373 2.614)
        (xy -0.356 2.627)
        (xy -0.356 2.306)
        (xy -0.229 2.306)
        (xy -0.229 3.2)
      )

      (stroke (width 0.01) (type solid)) (fill solid) (layer "F.Mask"))
    (fp_poly
      (pts
        (xy 0.605 1.558)
        (xy 0.651 1.574)
        (xy 0.694 1.598)
        (xy 0.728 1.627)
        (xy 0.75 1.652)
        (xy 0.768 1.678)
        (xy 0.781 1.707)
        (xy 0.791 1.739)
        (xy 0.797 1.777)
        (xy 0.801 1.822)
        (xy 0.802 1.876)
        (xy 0.802 1.877)
        (xy 0.801 1.929)
        (xy 0.798 1.973)
        (xy 0.792 2.009)
        (xy 0.784 2.04)
        (xy 0.774 2.062)
        (xy 0.748 2.103)
        (xy 0.715 2.139)
        (xy 0.675 2.167)
        (xy 0.632 2.187)
        (xy 0.626 2.189)
        (xy 0.599 2.195)
        (xy 0.567 2.198)
        (xy 0.532 2.199)
        (xy 0.499 2.197)
        (xy 0.471 2.193)
        (xy 0.466 2.192)
        (xy 0.428 2.177)
        (xy 0.391 2.155)
        (xy 0.359 2.129)
        (xy 0.354 2.123)
        (xy 0.332 2.098)
        (xy 0.316 2.073)
        (xy 0.303 2.047)
        (xy 0.294 2.017)
        (xy 0.287 1.983)
        (xy 0.284 1.943)
        (xy 0.282 1.894)
        (xy 0.282 1.877)
        (xy 0.409 1.877)
        (xy 0.41 1.918)
        (xy 0.412 1.95)
        (xy 0.416 1.976)
        (xy 0.423 1.997)
        (xy 0.432 2.015)
        (xy 0.445 2.03)
        (xy 0.451 2.037)
        (xy 0.471 2.054)
        (xy 0.491 2.064)
        (xy 0.514 2.07)
        (xy 0.543 2.072)
        (xy 0.569 2.07)
        (xy 0.59 2.065)
        (xy 0.601 2.06)
        (xy 0.625 2.047)
        (xy 0.642 2.031)
        (xy 0.656 2.009)
        (xy 0.661 1.998)
        (xy 0.665 1.989)
        (xy 0.668 1.98)
        (xy 0.67 1.969)
        (xy 0.671 1.954)
        (xy 0.672 1.935)
        (xy 0.673 1.909)
        (xy 0.673 1.877)
        (xy 0.673 1.842)
        (xy 0.672 1.817)
        (xy 0.671 1.798)
        (xy 0.67 1.784)
        (xy 0.668 1.773)
        (xy 0.665 1.764)
        (xy 0.661 1.755)
        (xy 0.647 1.73)
        (xy 0.632 1.712)
        (xy 0.612 1.698)
        (xy 0.601 1.693)
        (xy 0.569 1.683)
        (xy 0.535 1.681)
        (xy 0.501 1.686)
        (xy 0.471 1.7)
        (xy 0.447 1.719)
        (xy 0.434 1.736)
        (xy 0.424 1.753)
        (xy 0.417 1.774)
        (xy 0.412 1.8)
        (xy 0.41 1.833)
        (xy 0.409 1.873)
        (xy 0.409 1.877)
        (xy 0.282 1.877)
        (xy 0.283 1.824)
        (xy 0.286 1.78)
        (xy 0.292 1.742)
        (xy 0.301 1.711)
        (xy 0.313 1.683)
        (xy 0.33 1.657)
        (xy 0.35 1.633)
        (xy 0.351 1.632)
        (xy 0.385 1.601)
        (xy 0.42 1.578)
        (xy 0.46 1.563)
        (xy 0.505 1.554)
        (xy 0.555 1.551)
        (xy 0.605 1.558)
      )

      (stroke (width 0.01) (type solid)) (fill solid) (layer "F.Mask"))
    (fp_poly
      (pts
        (xy 0.004 1.556)
        (xy 0.054 1.566)
        (xy 0.102 1.582)
        (xy 0.146 1.605)
        (xy 0.154 1.61)
        (xy 0.193 1.636)
        (xy 0.178 1.655)
        (xy 0.166 1.668)
        (xy 0.152 1.686)
        (xy 0.138 1.7)
        (xy 0.114 1.727)
        (xy 0.07 1.705)
        (xy 0.032 1.688)
        (xy -0.007 1.677)
        (xy -0.044 1.672)
        (xy -0.079 1.672)
        (xy -0.11 1.678)
        (xy -0.136 1.69)
        (xy -0.154 1.707)
        (xy -0.162 1.724)
        (xy -0.164 1.745)
        (xy -0.164 1.761)
        (xy -0.159 1.772)
        (xy -0.15 1.782)
        (xy -0.149 1.783)
        (xy -0.139 1.791)
        (xy -0.128 1.797)
        (xy -0.114 1.802)
        (xy -0.095 1.805)
        (xy -0.07 1.808)
        (xy -0.037 1.811)
        (xy -0.02 1.813)
        (xy 0.027 1.817)
        (xy 0.065 1.823)
        (xy 0.096 1.832)
        (xy 0.122 1.842)
        (xy 0.14 1.854)
        (xy 0.166 1.879)
        (xy 0.186 1.91)
        (xy 0.2 1.947)
        (xy 0.206 1.987)
        (xy 0.206 2.018)
        (xy 0.198 2.06)
        (xy 0.181 2.097)
        (xy 0.155 2.129)
        (xy 0.122 2.156)
        (xy 0.08 2.177)
        (xy 0.042 2.189)
        (xy 0.005 2.196)
        (xy -0.038 2.199)
        (xy -0.083 2.198)
        (xy -0.125 2.194)
        (xy -0.153 2.189)
        (xy -0.177 2.181)
        (xy -0.204 2.171)
        (xy -0.229 2.16)
        (xy -0.232 2.159)
        (xy -0.251 2.148)
        (xy -0.272 2.136)
        (xy -0.292 2.122)
        (xy -0.309 2.109)
        (xy -0.323 2.098)
        (xy -0.33 2.09)
        (xy -0.331 2.088)
        (xy -0.327 2.084)
        (xy -0.318 2.073)
        (xy -0.304 2.059)
        (xy -0.288 2.043)
        (xy -0.246 2)
        (xy -0.221 2.021)
        (xy -0.184 2.047)
        (xy -0.145 2.065)
        (xy -0.102 2.075)
        (xy -0.053 2.079)
        (xy -0.049 2.079)
        (xy -0.023 2.079)
        (xy -0.004 2.078)
        (xy 0.011 2.074)
        (xy 0.025 2.069)
        (xy 0.029 2.068)
        (xy 0.054 2.052)
        (xy 0.071 2.033)
        (xy 0.079 2.01)
        (xy 0.078 1.986)
        (xy 0.074 1.975)
        (xy 0.068 1.964)
        (xy 0.06 1.956)
        (xy 0.048 1.949)
        (xy 0.031 1.944)
        (xy 0.007 1.939)
        (xy -0.024 1.935)
        (xy -0.052 1.932)
        (xy -0.089 1.929)
        (xy -0.119 1.925)
        (xy -0.142 1.921)
        (xy -0.16 1.917)
        (xy -0.176 1.912)
        (xy -0.192 1.906)
        (xy -0.201 1.901)
        (xy -0.235 1.879)
        (xy -0.262 1.85)
        (xy -0.28 1.816)
        (xy -0.29 1.776)
        (xy -0.292 1.75)
        (xy -0.291 1.727)
        (xy -0.289 1.705)
        (xy -0.286 1.689)
        (xy -0.286 1.688)
        (xy -0.273 1.659)
        (xy -0.253 1.63)
        (xy -0.229 1.604)
        (xy -0.221 1.599)
        (xy -0.185 1.577)
        (xy -0.143 1.562)
        (xy -0.096 1.554)
        (xy -0.047 1.552)
        (xy 0.004 1.556)
      )

      (stroke (width 0.01) (type solid)) (fill solid) (layer "F.Mask"))
    (fp_poly
      (pts
        (xy 1.038 2.556)
        (xy 1.091 2.563)
        (xy 1.137 2.576)
        (xy 1.177 2.595)
        (xy 1.209 2.62)
        (xy 1.234 2.65)
        (xy 1.242 2.665)
        (xy 1.247 2.677)
        (xy 1.251 2.691)
        (xy 1.255 2.708)
        (xy 1.258 2.727)
        (xy 1.26 2.751)
        (xy 1.262 2.78)
        (xy 1.263 2.815)
        (xy 1.263 2.858)
        (xy 1.264 2.908)
        (xy 1.263 2.967)
        (xy 1.263 2.989)
        (xy 1.262 3.197)
        (xy 1.135 3.197)
        (xy 1.133 3.171)
        (xy 1.132 3.144)
        (xy 1.119 3.159)
        (xy 1.096 3.179)
        (xy 1.065 3.193)
        (xy 1.026 3.202)
        (xy 0.98 3.204)
        (xy 0.976 3.204)
        (xy 0.955 3.204)
        (xy 0.937 3.203)
        (xy 0.925 3.202)
        (xy 0.924 3.201)
        (xy 0.879 3.189)
        (xy 0.839 3.17)
        (xy 0.806 3.144)
        (xy 0.781 3.113)
        (xy 0.763 3.077)
        (xy 0.753 3.037)
        (xy 0.753 3.005)
        (xy 0.873 3.005)
        (xy 0.874 3.023)
        (xy 0.878 3.035)
        (xy 0.887 3.047)
        (xy 0.89 3.05)
        (xy 0.903 3.063)
        (xy 0.917 3.072)
        (xy 0.935 3.078)
        (xy 0.957 3.081)
        (xy 0.986 3.082)
        (xy 1.013 3.082)
        (xy 1.043 3.081)
        (xy 1.065 3.079)
        (xy 1.08 3.077)
        (xy 1.091 3.073)
        (xy 1.096 3.071)
        (xy 1.112 3.058)
        (xy 1.123 3.039)
        (xy 1.13 3.012)
        (xy 1.132 2.977)
        (xy 1.132 2.975)
        (xy 1.132 2.931)
        (xy 1.035 2.931)
        (xy 0.999 2.931)
        (xy 0.973 2.931)
        (xy 0.953 2.932)
        (xy 0.939 2.934)
        (xy 0.928 2.936)
        (xy 0.919 2.939)
        (xy 0.916 2.94)
        (xy 0.893 2.954)
        (xy 0.88 2.971)
        (xy 0.874 2.994)
        (xy 0.873 3.005)
        (xy 0.753 3.005)
        (xy 0.753 2.994)
        (xy 0.761 2.951)
        (xy 0.768 2.931)
        (xy 0.776 2.915)
        (xy 0.786 2.901)
        (xy 0.802 2.884)
        (xy 0.804 2.882)
        (xy 0.82 2.867)
        (xy 0.835 2.854)
        (xy 0.85 2.845)
        (xy 0.867 2.838)
        (xy 0.887 2.833)
        (xy 0.912 2.829)
        (xy 0.943 2.827)
        (xy 0.982 2.826)
        (xy 1.015 2.825)
        (xy 1.133 2.823)
        (xy 1.132 2.771)
        (xy 1.131 2.746)
        (xy 1.129 2.73)
        (xy 1.127 2.719)
        (xy 1.123 2.711)
        (xy 1.117 2.705)
        (xy 1.098 2.691)
        (xy 1.07 2.682)
        (xy 1.032 2.677)
        (xy 1.006 2.677)
        (xy 0.972 2.678)
        (xy 0.945 2.682)
        (xy 0.924 2.688)
        (xy 0.907 2.699)
        (xy 0.9 2.706)
        (xy 0.882 2.723)
        (xy 0.834 2.686)
        (xy 0.816 2.672)
        (xy 0.801 2.66)
        (xy 0.79 2.652)
        (xy 0.787 2.648)
        (xy 0.791 2.639)
        (xy 0.801 2.626)
        (xy 0.816 2.612)
        (xy 0.832 2.6)
        (xy 0.864 2.581)
        (xy 0.902 2.568)
        (xy 0.946 2.559)
        (xy 0.98 2.556)
        (xy 1.038 2.556)
      )

      (stroke (width 0.01) (type solid)) (fill solid) (layer "F.Mask"))
    (fp_poly
      (pts
        (xy -1.521 2.559)
        (xy -1.485 2.562)
        (xy -1.454 2.568)
        (xy -1.427 2.577)
        (xy -1.401 2.589)
        (xy -1.371 2.61)
        (xy -1.345 2.639)
        (xy -1.325 2.67)
        (xy -1.321 2.679)
        (xy -1.309 2.71)
        (xy -1.309 3.197)
        (xy -1.433 3.2)
        (xy -1.433 3.172)
        (xy -1.434 3.157)
        (xy -1.435 3.147)
        (xy -1.436 3.144)
        (xy -1.44 3.147)
        (xy -1.449 3.156)
        (xy -1.453 3.161)
        (xy -1.472 3.178)
        (xy -1.496 3.19)
        (xy -1.526 3.198)
        (xy -1.563 3.202)
        (xy -1.578 3.203)
        (xy -1.603 3.203)
        (xy -1.627 3.203)
        (xy -1.647 3.201)
        (xy -1.656 3.2)
        (xy -1.686 3.191)
        (xy -1.717 3.176)
        (xy -1.746 3.159)
        (xy -1.765 3.143)
        (xy -1.79 3.111)
        (xy -1.807 3.075)
        (xy -1.816 3.037)
        (xy -1.817 2.998)
        (xy -1.817 2.997)
        (xy -1.697 2.997)
        (xy -1.696 3.02)
        (xy -1.687 3.042)
        (xy -1.67 3.06)
        (xy -1.668 3.062)
        (xy -1.654 3.07)
        (xy -1.64 3.076)
        (xy -1.624 3.08)
        (xy -1.602 3.081)
        (xy -1.574 3.082)
        (xy -1.558 3.082)
        (xy -1.529 3.081)
        (xy -1.508 3.08)
        (xy -1.494 3.078)
        (xy -1.483 3.075)
        (xy -1.474 3.07)
        (xy -1.458 3.058)
        (xy -1.447 3.041)
        (xy -1.44 3.017)
        (xy -1.435 2.985)
        (xy -1.435 2.977)
        (xy -1.432 2.931)
        (xy -1.533 2.931)
        (xy -1.568 2.931)
        (xy -1.595 2.931)
        (xy -1.615 2.932)
        (xy -1.63 2.934)
        (xy -1.641 2.936)
        (xy -1.65 2.938)
        (xy -1.655 2.941)
        (xy -1.676 2.955)
        (xy -1.69 2.974)
        (xy -1.697 2.997)
        (xy -1.817 2.997)
        (xy -1.811 2.96)
        (xy -1.797 2.924)
        (xy -1.775 2.892)
        (xy -1.747 2.864)
        (xy -1.715 2.845)
        (xy -1.7 2.838)
        (xy -1.685 2.833)
        (xy -1.668 2.83)
        (xy -1.648 2.827)
        (xy -1.623 2.825)
        (xy -1.591 2.824)
        (xy -1.551 2.824)
        (xy -1.54 2.824)
        (xy -1.432 2.824)
        (xy -1.434 2.776)
        (xy -1.436 2.747)
        (xy -1.441 2.726)
        (xy -1.448 2.711)
        (xy -1.46 2.699)
        (xy -1.474 2.689)
        (xy -1.483 2.685)
        (xy -1.492 2.682)
        (xy -1.505 2.68)
        (xy -1.524 2.68)
        (xy -1.55 2.679)
        (xy -1.56 2.679)
        (xy -1.594 2.68)
        (xy -1.62 2.682)
        (xy -1.639 2.686)
        (xy -1.654 2.692)
        (xy -1.666 2.701)
        (xy -1.675 2.711)
        (xy -1.686 2.724)
        (xy -1.735 2.686)
        (xy -1.754 2.672)
        (xy -1.769 2.659)
        (xy -1.78 2.65)
        (xy -1.784 2.646)
        (xy -1.78 2.64)
        (xy -1.77 2.629)
        (xy -1.756 2.616)
        (xy -1.74 2.604)
        (xy -1.724 2.592)
        (xy -1.711 2.584)
        (xy -1.71 2.583)
        (xy -1.688 2.574)
        (xy -1.668 2.566)
        (xy -1.647 2.562)
        (xy -1.623 2.559)
        (xy -1.593 2.558)
        (xy -1.565 2.558)
        (xy -1.521 2.559)
      )

      (stroke (width 0.01) (type solid)) (fill solid) (layer "F.Mask"))
    (fp_poly
      (pts
        (xy 0.035 2.777)
        (xy 0.047 2.822)
        (xy 0.059 2.864)
        (xy 0.069 2.903)
        (xy 0.078 2.936)
        (xy 0.086 2.963)
        (xy 0.092 2.984)
        (xy 0.095 2.996)
        (xy 0.096 2.999)
        (xy 0.098 2.999)
        (xy 0.103 2.991)
        (xy 0.109 2.975)
        (xy 0.118 2.95)
        (xy 0.129 2.917)
        (xy 0.143 2.874)
        (xy 0.152 2.849)
        (xy 0.165 2.807)
        (xy 0.179 2.766)
        (xy 0.192 2.726)
        (xy 0.204 2.689)
        (xy 0.214 2.658)
        (xy 0.221 2.634)
        (xy 0.224 2.627)
        (xy 0.244 2.565)
        (xy 0.338 2.565)
        (xy 0.406 2.774)
        (xy 0.42 2.819)
        (xy 0.434 2.861)
        (xy 0.446 2.899)
        (xy 0.457 2.932)
        (xy 0.466 2.96)
        (xy 0.473 2.981)
        (xy 0.477 2.993)
        (xy 0.478 2.997)
        (xy 0.48 2.998)
        (xy 0.482 2.996)
        (xy 0.485 2.99)
        (xy 0.49 2.978)
        (xy 0.495 2.96)
        (xy 0.502 2.936)
        (xy 0.511 2.905)
        (xy 0.523 2.865)
        (xy 0.536 2.817)
        (xy 0.543 2.789)
        (xy 0.556 2.744)
        (xy 0.568 2.701)
        (xy 0.578 2.663)
        (xy 0.587 2.629)
        (xy 0.595 2.602)
        (xy 0.601 2.582)
        (xy 0.605 2.57)
        (xy 0.606 2.567)
        (xy 0.611 2.566)
        (xy 0.625 2.566)
        (xy 0.645 2.566)
        (xy 0.669 2.566)
        (xy 0.673 2.566)
        (xy 0.739 2.567)
        (xy 0.656 2.827)
        (xy 0.64 2.878)
        (xy 0.624 2.928)
        (xy 0.609 2.976)
        (xy 0.595 3.02)
        (xy 0.582 3.06)
        (xy 0.571 3.094)
        (xy 0.563 3.121)
        (xy 0.557 3.139)
        (xy 0.556 3.143)
        (xy 0.538 3.2)
        (xy 0.425 3.197)
        (xy 0.358 2.975)
        (xy 0.341 2.917)
        (xy 0.327 2.87)
        (xy 0.315 2.831)
        (xy 0.305 2.801)
        (xy 0.297 2.78)
        (xy 0.292 2.766)
        (xy 0.289 2.761)
        (xy 0.288 2.761)
        (xy 0.286 2.768)
        (xy 0.281 2.783)
        (xy 0.274 2.806)
        (xy 0.265 2.836)
        (xy 0.254 2.871)
        (xy 0.242 2.911)
        (xy 0.23 2.953)
        (xy 0.223 2.976)
        (xy 0.21 3.02)
        (xy 0.197 3.062)
        (xy 0.186 3.099)
        (xy 0.177 3.132)
        (xy 0.169 3.158)
        (xy 0.163 3.177)
        (xy 0.16 3.189)
        (xy 0.159 3.191)
        (xy 0.157 3.195)
        (xy 0.151 3.198)
        (xy 0.141 3.199)
        (xy 0.124 3.2)
        (xy 0.101 3.2)
        (xy 0.073 3.199)
        (xy 0.055 3.198)
        (xy 0.045 3.196)
        (xy 0.043 3.194)
        (xy 0.041 3.188)
        (xy 0.036 3.173)
        (xy 0.029 3.15)
        (xy 0.019 3.121)
        (xy 0.008 3.084)
        (xy -0.006 3.043)
        (xy -0.02 2.996)
        (xy -0.036 2.946)
        (xy -0.053 2.893)
        (xy -0.057 2.883)
        (xy -0.074 2.83)
        (xy -0.09 2.779)
        (xy -0.105 2.732)
        (xy -0.119 2.689)
        (xy -0.131 2.652)
        (xy -0.141 2.621)
        (xy -0.148 2.596)
        (xy -0.154 2.58)
        (xy -0.156 2.572)
        (xy -0.156 2.569)
        (xy -0.151 2.567)
        (xy -0.14 2.566)
        (xy -0.123 2.565)
        (xy -0.096 2.565)
        (xy -0.091 2.565)
        (xy -0.023 2.565)
        (xy 0.035 2.777)
      )

      (stroke (width 0.01) (type solid)) (fill solid) (layer "F.Mask"))
    (fp_poly
      (pts
        (xy -2.065 1.559)
        (xy -2.024 1.576)
        (xy -1.986 1.601)
        (xy -1.973 1.612)
        (xy -1.957 1.63)
        (xy -1.943 1.649)
        (xy -1.932 1.668)
        (xy -1.924 1.69)
        (xy -1.918 1.716)
        (xy -1.914 1.747)
        (xy -1.911 1.785)
        (xy -1.91 1.831)
        (xy -1.91 1.877)
        (xy -1.91 1.93)
        (xy -1.912 1.974)
        (xy -1.914 2.011)
        (xy -1.919 2.041)
        (xy -1.925 2.067)
        (xy -1.934 2.088)
        (xy -1.945 2.107)
        (xy -1.959 2.125)
        (xy -1.972 2.139)
        (xy -1.993 2.157)
        (xy -2.018 2.173)
        (xy -2.031 2.18)
        (xy -2.047 2.188)
        (xy -2.06 2.192)
        (xy -2.074 2.195)
        (xy -2.091 2.196)
        (xy -2.114 2.197)
        (xy -2.122 2.197)
        (xy -2.147 2.196)
        (xy -2.165 2.195)
        (xy -2.179 2.193)
        (xy -2.191 2.189)
        (xy -2.205 2.183)
        (xy -2.21 2.18)
        (xy -2.231 2.169)
        (xy -2.251 2.156)
        (xy -2.265 2.146)
        (xy -2.286 2.127)
        (xy -2.286 2.627)
        (xy -2.266 2.608)
        (xy -2.248 2.595)
        (xy -2.227 2.582)
        (xy -2.217 2.577)
        (xy -2.173 2.562)
        (xy -2.129 2.556)
        (xy -2.086 2.559)
        (xy -2.045 2.57)
        (xy -2.007 2.589)
        (xy -1.974 2.616)
        (xy -1.946 2.648)
        (xy -1.926 2.687)
        (xy -1.919 2.707)
        (xy -1.917 2.715)
        (xy -1.915 2.724)
        (xy -1.914 2.737)
        (xy -1.913 2.753)
        (xy -1.912 2.774)
        (xy -1.911 2.8)
        (xy -1.911 2.833)
        (xy -1.911 2.874)
        (xy -1.911 2.923)
        (xy -1.911 2.967)
        (xy -1.911 3.2)
        (xy -2.035 3.197)
        (xy -2.038 2.984)
        (xy -2.038 2.932)
        (xy -2.039 2.889)
        (xy -2.039 2.854)
        (xy -2.04 2.826)
        (xy -2.041 2.805)
        (xy -2.042 2.788)
        (xy -2.043 2.776)
        (xy -2.045 2.767)
        (xy -2.046 2.76)
        (xy -2.049 2.755)
        (xy -2.051 2.75)
        (xy -2.072 2.721)
        (xy -2.098 2.701)
        (xy -2.128 2.688)
        (xy -2.161 2.683)
        (xy -2.195 2.687)
        (xy -2.22 2.697)
        (xy -2.24 2.71)
        (xy -2.259 2.729)
        (xy -2.274 2.75)
        (xy -2.278 2.757)
        (xy -2.28 2.765)
        (xy -2.281 2.781)
        (xy -2.283 2.806)
        (xy -2.284 2.839)
        (xy -2.285 2.881)
        (xy -2.286 2.933)
        (xy -2.286 2.984)
        (xy -2.289 3.197)
        (xy -2.413 3.2)
        (xy -2.413 1.877)
        (xy -2.286 1.877)
        (xy -2.285 1.926)
        (xy -2.281 1.966)
        (xy -2.274 1.998)
        (xy -2.262 2.024)
        (xy -2.247 2.043)
        (xy -2.228 2.058)
        (xy -2.215 2.064)
        (xy -2.194 2.07)
        (xy -2.168 2.072)
        (xy -2.141 2.071)
        (xy -2.117 2.066)
        (xy -2.106 2.063)
        (xy -2.079 2.044)
        (xy -2.058 2.019)
        (xy -2.05 2.001)
        (xy -2.045 1.984)
        (xy -2.042 1.959)
        (xy -2.04 1.929)
        (xy -2.038 1.895)
        (xy -2.038 1.861)
        (xy -2.039 1.829)
        (xy -2.041 1.8)
        (xy -2.044 1.777)
        (xy -2.045 1.772)
        (xy -2.057 1.738)
        (xy -2.073 1.712)
        (xy -2.094 1.695)
        (xy -2.122 1.684)
        (xy -2.156 1.681)
        (xy -2.159 1.681)
        (xy -2.192 1.683)
        (xy -2.22 1.691)
        (xy -2.243 1.705)
        (xy -2.26 1.725)
        (xy -2.273 1.753)
        (xy -2.281 1.788)
        (xy -2.285 1.832)
        (xy -2.286 1.877)
        (xy -2.413 1.877)
        (xy -2.413 1.559)
        (xy -2.286 1.559)
        (xy -2.286 1.62)
        (xy -2.26 1.6)
        (xy -2.225 1.577)
        (xy -2.19 1.563)
        (xy -2.154 1.554)
        (xy -2.109 1.552)
        (xy -2.065 1.559)
      )

      (stroke (width 0.01) (type solid)) (fill solid) (layer "F.Mask"))
    (fp_poly
      (pts
        (xy 0.063 -3.201)
        (xy 0.118 -3.201)
        (xy 0.164 -3.201)
        (xy 0.202 -3.2)
        (xy 0.233 -3.2)
        (xy 0.258 -3.2)
        (xy 0.277 -3.199)
        (xy 0.292 -3.198)
        (xy 0.302 -3.197)
        (xy 0.309 -3.196)
        (xy 0.314 -3.195)
        (xy 0.317 -3.193)
        (xy 0.319 -3.192)
        (xy 0.321 -3.189)
        (xy 0.324 -3.183)
        (xy 0.327 -3.174)
        (xy 0.33 -3.161)
        (xy 0.334 -3.144)
        (xy 0.339 -3.12)
        (xy 0.345 -3.091)
        (xy 0.352 -3.054)
        (xy 0.361 -3.01)
        (xy 0.371 -2.958)
        (xy 0.382 -2.897)
        (xy 0.385 -2.878)
        (xy 0.395 -2.824)
        (xy 0.405 -2.772)
        (xy 0.414 -2.724)
        (xy 0.423 -2.68)
        (xy 0.43 -2.642)
        (xy 0.437 -2.61)
        (xy 0.442 -2.586)
        (xy 0.446 -2.569)
        (xy 0.448 -2.562)
        (xy 0.456 -2.55)
        (xy 0.464 -2.544)
        (xy 0.476 -2.539)
        (xy 0.495 -2.53)
        (xy 0.521 -2.519)
        (xy 0.552 -2.506)
        (xy 0.587 -2.492)
        (xy 0.624 -2.477)
        (xy 0.664 -2.461)
        (xy 0.704 -2.445)
        (xy 0.743 -2.43)
        (xy 0.78 -2.415)
        (xy 0.814 -2.402)
        (xy 0.843 -2.391)
        (xy 0.868 -2.382)
        (xy 0.885 -2.376)
        (xy 0.895 -2.373)
        (xy 0.896 -2.373)
        (xy 0.911 -2.376)
        (xy 0.931 -2.386)
        (xy 0.948 -2.397)
        (xy 0.962 -2.406)
        (xy 0.983 -2.421)
        (xy 1.011 -2.44)
        (xy 1.043 -2.462)
        (xy 1.079 -2.487)
        (xy 1.118 -2.513)
        (xy 1.158 -2.541)
        (xy 1.198 -2.568)
        (xy 1.238 -2.595)
        (xy 1.275 -2.621)
        (xy 1.309 -2.644)
        (xy 1.338 -2.665)
        (xy 1.362 -2.681)
        (xy 1.377 -2.691)
        (xy 1.398 -2.705)
        (xy 1.418 -2.717)
        (xy 1.433 -2.725)
        (xy 1.442 -2.728)
        (xy 1.443 -2.728)
        (xy 1.448 -2.726)
        (xy 1.456 -2.72)
        (xy 1.468 -2.71)
        (xy 1.486 -2.694)
        (xy 1.508 -2.673)
        (xy 1.535 -2.647)
        (xy 1.568 -2.614)
        (xy 1.608 -2.575)
        (xy 1.654 -2.53)
        (xy 1.675 -2.509)
        (xy 1.721 -2.462)
        (xy 1.761 -2.422)
        (xy 1.794 -2.388)
        (xy 1.822 -2.36)
        (xy 1.844 -2.337)
        (xy 1.862 -2.318)
        (xy 1.875 -2.304)
        (xy 1.884 -2.293)
        (xy 1.89 -2.284)
        (xy 1.893 -2.279)
        (xy 1.894 -2.275)
        (xy 1.892 -2.269)
        (xy 1.886 -2.257)
        (xy 1.875 -2.239)
        (xy 1.86 -2.215)
        (xy 1.839 -2.183)
        (xy 1.814 -2.145)
        (xy 1.783 -2.1)
        (xy 1.747 -2.046)
        (xy 1.721 -2.009)
        (xy 1.69 -1.964)
        (xy 1.661 -1.921)
        (xy 1.634 -1.88)
        (xy 1.609 -1.844)
        (xy 1.588 -1.811)
        (xy 1.57 -1.785)
        (xy 1.557 -1.764)
        (xy 1.549 -1.75)
        (xy 1.546 -1.743)
        (xy 1.547 -1.735)
        (xy 1.552 -1.719)
        (xy 1.56 -1.696)
        (xy 1.571 -1.667)
        (xy 1.585 -1.634)
        (xy 1.6 -1.597)
        (xy 1.616 -1.557)
        (xy 1.633 -1.516)
        (xy 1.651 -1.476)
        (xy 1.668 -1.436)
        (xy 1.685 -1.398)
        (xy 1.701 -1.363)
        (xy 1.715 -1.333)
        (xy 1.727 -1.309)
        (xy 1.736 -1.291)
        (xy 1.742 -1.281)
        (xy 1.744 -1.279)
        (xy 1.751 -1.277)
        (xy 1.767 -1.273)
        (xy 1.791 -1.268)
        (xy 1.822 -1.261)
        (xy 1.86 -1.254)
        (xy 1.903 -1.245)
        (xy 1.951 -1.236)
        (xy 2.002 -1.226)
        (xy 2.049 -1.217)
        (xy 2.103 -1.207)
        (xy 2.154 -1.198)
        (xy 2.201 -1.188)
        (xy 2.244 -1.18)
        (xy 2.281 -1.173)
        (xy 2.311 -1.166)
        (xy 2.335 -1.161)
        (xy 2.35 -1.157)
        (xy 2.355 -1.156)
        (xy 2.367 -1.148)
        (xy 2.367 -0.834)
        (xy 2.367 -0.768)
        (xy 2.367 -0.712)
        (xy 2.367 -0.664)
        (xy 2.366 -0.625)
        (xy 2.366 -0.592)
        (xy 2.365 -0.566)
        (xy 2.364 -0.546)
        (xy 2.363 -0.531)
        (xy 2.361 -0.52)
        (xy 2.358 -0.512)
        (xy 2.355 -0.507)
        (xy 2.352 -0.504)
        (xy 2.348 -0.503)
        (xy 2.343 -0.501)
        (xy 2.34 -0.501)
        (xy 2.333 -0.499)
        (xy 2.317 -0.496)
        (xy 2.293 -0.492)
        (xy 2.261 -0.486)
        (xy 2.224 -0.479)
        (xy 2.181 -0.471)
        (xy 2.134 -0.462)
        (xy 2.084 -0.453)
        (xy 2.054 -0.448)
        (xy 2.002 -0.438)
        (xy 1.953 -0.429)
        (xy 1.907 -0.42)
        (xy 1.866 -0.412)
        (xy 1.831 -0.404)
        (xy 1.802 -0.398)
        (xy 1.78 -0.394)
        (xy 1.767 -0.391)
        (xy 1.764 -0.39)
        (xy 1.76 -0.387)
        (xy 1.757 -0.384)
        (xy 1.753 -0.379)
        (xy 1.748 -0.371)
        (xy 1.742 -0.36)
        (xy 1.735 -0.344)
        (xy 1.726 -0.324)
        (xy 1.715 -0.297)
        (xy 1.701 -0.264)
        (xy 1.685 -0.223)
        (xy 1.665 -0.174)
        (xy 1.653 -0.145)
        (xy 1.63 -0.086)
        (xy 1.61 -0.037)
        (xy 1.594 0.005)
        (xy 1.582 0.038)
        (xy 1.572 0.064)
        (xy 1.566 0.084)
        (xy 1.562 0.097)
        (xy 1.561 0.104)
        (xy 1.562 0.105)
        (xy 1.565 0.111)
        (xy 1.574 0.125)
        (xy 1.587 0.146)
        (xy 1.604 0.173)
        (xy 1.626 0.205)
        (xy 1.65 0.241)
        (xy 1.677 0.281)
        (xy 1.706 0.324)
        (xy 1.729 0.358)
        (xy 1.768 0.413)
        (xy 1.8 0.461)
        (xy 1.827 0.502)
        (xy 1.85 0.535)
        (xy 1.867 0.562)
        (xy 1.88 0.583)
        (xy 1.889 0.598)
        (xy 1.893 0.608)
        (xy 1.894 0.612)
        (xy 1.893 0.616)
        (xy 1.89 0.622)
        (xy 1.885 0.63)
        (xy 1.876 0.64)
        (xy 1.863 0.655)
        (xy 1.846 0.673)
        (xy 1.825 0.695)
        (xy 1.798 0.723)
        (xy 1.765 0.756)
        (xy 1.727 0.795)
        (xy 1.682 0.839)
        (xy 1.635 0.886)
        (xy 1.595 0.926)
        (xy 1.561 0.96)
        (xy 1.532 0.989)
        (xy 1.508 1.012)
        (xy 1.488 1.03)
        (xy 1.473 1.044)
        (xy 1.461 1.054)
        (xy 1.452 1.061)
        (xy 1.445 1.065)
        (xy 1.44 1.066)
        (xy 1.438 1.066)
        (xy 1.433 1.064)
        (xy 1.421 1.055)
        (xy 1.401 1.043)
        (xy 1.376 1.026)
        (xy 1.345 1.005)
        (xy 1.31 0.981)
        (xy 1.27 0.954)
        (xy 1.228 0.925)
        (xy 1.193 0.901)
        (xy 1.138 0.864)
        (xy 1.089 0.83)
        (xy 1.046 0.802)
        (xy 1.01 0.778)
        (xy 0.981 0.759)
        (xy 0.96 0.746)
        (xy 0.946 0.738)
        (xy 0.94 0.736)
        (xy 0.932 0.738)
        (xy 0.917 0.745)
        (xy 0.895 0.755)
        (xy 0.869 0.768)
        (xy 0.84 0.783)
        (xy 0.816 0.795)
        (xy 0.781 0.814)
        (xy 0.753 0.828)
        (xy 0.732 0.838)
        (xy 0.717 0.845)
        (xy 0.707 0.849)
        (xy 0.699 0.85)
        (xy 0.694 0.849)
        (xy 0.691 0.847)
        (xy 0.687 0.84)
        (xy 0.682 0.829)
        (xy 0.674 0.814)
        (xy 0.665 0.793)
        (xy 0.653 0.767)
        (xy 0.639 0.735)
        (xy 0.623 0.696)
        (xy 0.604 0.651)
        (xy 0.582 0.598)
        (xy 0.556 0.538)
        (xy 0.528 0.469)
        (xy 0.496 0.391)
        (xy 0.47 0.329)
        (xy 0.436 0.247)
        (xy 0.406 0.173)
        (xy 0.379 0.108)
        (xy 0.355 0.05)
        (xy 0.335 0)
        (xy 0.317 -0.043)
        (xy 0.303 -0.079)
        (xy 0.291 -0.11)
        (xy 0.281 -0.135)
        (xy 0.273 -0.155)
        (xy 0.268 -0.171)
        (xy 0.264 -0.183)
        (xy 0.262 -0.191)
        (xy 0.262 -0.196)
        (xy 0.262 -0.198)
        (xy 0.269 -0.207)
        (xy 0.283 -0.219)
        (xy 0.302 -0.233)
        (xy 0.303 -0.234)
        (xy 0.354 -0.268)
        (xy 0.398 -0.3)
        (xy 0.435 -0.331)
        (xy 0.469 -0.363)
        (xy 0.5 -0.397)
        (xy 0.507 -0.405)
        (xy 0.556 -0.472)
        (xy 0.596 -0.543)
        (xy 0.627 -0.619)
        (xy 0.643 -0.672)
        (xy 0.651 -0.718)
        (xy 0.657 -0.77)
        (xy 0.66 -0.824)
        (xy 0.659 -0.878)
        (xy 0.654 -0.927)
        (xy 0.652 -0.936)
        (xy 0.634 -1.015)
        (xy 0.607 -1.09)
        (xy 0.571 -1.161)
        (xy 0.528 -1.227)
        (xy 0.477 -1.287)
        (xy 0.419 -1.341)
        (xy 0.355 -1.387)
        (xy 0.285 -1.426)
        (xy 0.21 -1.456)
        (xy 0.205 -1.458)
        (xy 0.131 -1.477)
        (xy 0.054 -1.487)
        (xy -0.025 -1.489)
        (xy -0.103 -1.482)
        (xy -0.178 -1.466)
        (xy -0.206 -1.458)
        (xy -0.281 -1.428)
        (xy -0.351 -1.39)
        (xy -0.416 -1.344)
        (xy -0.474 -1.29)
        (xy -0.526 -1.23)
        (xy -0.571 -1.164)
        (xy -0.607 -1.093)
        (xy -0.63 -1.034)
        (xy -0.649 -0.96)
        (xy -0.659 -0.883)
        (xy -0.661 -0.804)
        (xy -0.654 -0.726)
        (xy -0.638 -0.651)
        (xy -0.63 -0.623)
        (xy -0.618 -0.591)
        (xy -0.602 -0.554)
        (xy -0.584 -0.518)
        (xy -0.566 -0.485)
        (xy -0.553 -0.463)
        (xy -0.509 -0.407)
        (xy -0.457 -0.352)
        (xy -0.397 -0.299)
        (xy -0.33 -0.25)
        (xy -0.289 -0.224)
        (xy -0.273 -0.212)
        (xy -0.263 -0.2)
        (xy -0.262 -0.197)
        (xy -0.263 -0.19)
        (xy -0.268 -0.175)
        (xy -0.277 -0.151)
        (xy -0.288 -0.121)
        (xy -0.302 -0.084)
        (xy -0.319 -0.042)
        (xy -0.338 0.005)
        (xy -0.358 0.056)
        (xy -0.381 0.111)
        (xy -0.404 0.168)
        (xy -0.428 0.228)
        (xy -0.453 0.288)
        (xy -0.478 0.349)
        (xy -0.504 0.41)
        (xy -0.529 0.47)
        (xy -0.553 0.527)
        (xy -0.576 0.583)
        (xy -0.598 0.635)
        (xy -0.619 0.683)
        (xy -0.638 0.727)
        (xy -0.655 0.765)
        (xy -0.669 0.797)
        (xy -0.68 0.822)
        (xy -0.689 0.839)
        (xy -0.694 0.848)
        (xy -0.695 0.849)
        (xy -0.699 0.85)
        (xy -0.706 0.849)
        (xy -0.717 0.845)
        (xy -0.732 0.839)
        (xy -0.752 0.829)
        (xy -0.779 0.815)
        (xy -0.814 0.797)
        (xy -0.817 0.795)
        (xy -0.848 0.779)
        (xy -0.877 0.764)
        (xy -0.902 0.752)
        (xy -0.922 0.743)
        (xy -0.936 0.737)
        (xy -0.941 0.736)
        (xy -0.949 0.739)
        (xy -0.964 0.748)
        (xy -0.987 0.761)
        (xy -1.015 0.78)
        (xy -1.05 0.803)
        (xy -1.072 0.818)
        (xy -1.138 0.863)
        (xy -1.195 0.903)
        (xy -1.245 0.937)
        (xy -1.289 0.966)
        (xy -1.325 0.991)
        (xy -1.356 1.012)
        (xy -1.381 1.029)
        (xy -1.401 1.042)
        (xy -1.416 1.052)
        (xy -1.427 1.059)
        (xy -1.435 1.064)
        (xy -1.439 1.066)
        (xy -1.44 1.066)
        (xy -1.449 1.064)
        (xy -1.453 1.061)
        (xy -1.458 1.057)
        (xy -1.47 1.046)
        (xy -1.487 1.029)
        (xy -1.509 1.007)
        (xy -1.537 0.98)
        (xy -1.568 0.95)
        (xy -1.602 0.915)
        (xy -1.639 0.879)
        (xy -1.678 0.84)
        (xy -1.678 0.839)
        (xy -1.726 0.792)
        (xy -1.767 0.751)
        (xy -1.801 0.716)
        (xy -1.829 0.687)
        (xy -1.852 0.663)
        (xy -1.869 0.644)
        (xy -1.882 0.63)
        (xy -1.89 0.62)
        (xy -1.894 0.613)
        (xy -1.895 0.61)
        (xy -1.892 0.603)
        (xy -1.884 0.588)
        (xy -1.87 0.565)
        (xy -1.85 0.536)
        (xy -1.826 0.499)
        (xy -1.797 0.455)
        (xy -1.763 0.405)
        (xy -1.73 0.358)
        (xy -1.7 0.313)
        (xy -1.671 0.271)
        (xy -1.645 0.232)
        (xy -1.621 0.197)
        (xy -1.601 0.166)
        (xy -1.584 0.141)
        (xy -1.572 0.121)
        (xy -1.565 0.109)
        (xy -1.563 0.105)
        (xy -1.563 0.099)
        (xy -1.566 0.087)
        (xy -1.572 0.07)
        (xy -1.58 0.045)
        (xy -1.592 0.013)
        (xy -1.607 -0.026)
        (xy -1.626 -0.074)
        (xy -1.648 -0.13)
        (xy -1.654 -0.145)
        (xy -1.676 -0.199)
        (xy -1.695 -0.245)
        (xy -1.71 -0.282)
        (xy -1.723 -0.313)
        (xy -1.733 -0.337)
        (xy -1.741 -0.356)
        (xy -1.748 -0.369)
        (xy -1.753 -0.379)
        (xy -1.758 -0.385)
        (xy -1.761 -0.388)
        (xy -1.763 -0.389)
        (xy -1.767 -0.39)
        (xy -1.774 -0.392)
        (xy -1.784 -0.395)
        (xy -1.799 -0.398)
        (xy -1.818 -0.402)
        (xy -1.843 -0.407)
        (xy -1.873 -0.413)
        (xy -1.91 -0.42)
        (xy -1.954 -0.429)
        (xy -2.005 -0.438)
        (xy -2.065 -0.449)
        (xy -2.133 -0.462)
        (xy -2.211 -0.477)
        (xy -2.22 -0.478)
        (xy -2.26 -0.486)
        (xy -2.29 -0.491)
        (xy -2.313 -0.496)
        (xy -2.33 -0.499)
        (xy -2.341 -0.502)
        (xy -2.349 -0.504)
        (xy -2.353 -0.506)
        (xy -2.356 -0.508)
        (xy -2.359 -0.51)
        (xy -2.36 -0.511)
        (xy -2.361 -0.514)
        (xy -2.363 -0.518)
        (xy -2.364 -0.526)
        (xy -2.365 -0.536)
        (xy -2.366 -0.551)
        (xy -2.366 -0.571)
        (xy -2.367 -0.597)
        (xy -2.367 -0.629)
        (xy -2.368 -0.668)
        (xy -2.368 -0.715)
        (xy -2.368 -0.771)
        (xy -2.368 -0.834)
        (xy -2.368 -1.148)
        (xy -2.356 -1.155)
        (xy -2.349 -1.158)
        (xy -2.333 -1.162)
        (xy -2.309 -1.167)
        (xy -2.278 -1.173)
        (xy -2.24 -1.181)
        (xy -2.197 -1.189)
        (xy -2.149 -1.198)
        (xy -2.098 -1.208)
        (xy -2.051 -1.217)
        (xy -1.996 -1.227)
        (xy -1.945 -1.237)
        (xy -1.897 -1.246)
        (xy -1.854 -1.254)
        (xy -1.817 -1.262)
        (xy -1.787 -1.268)
        (xy -1.764 -1.273)
        (xy -1.75 -1.277)
        (xy -1.745 -1.279)
        (xy -1.741 -1.285)
        (xy -1.733 -1.3)
        (xy -1.722 -1.322)
        (xy -1.709 -1.35)
        (xy -1.694 -1.382)
        (xy -1.677 -1.419)
        (xy -1.66 -1.458)
        (xy -1.642 -1.498)
        (xy -1.625 -1.539)
        (xy -1.608 -1.58)
        (xy -1.592 -1.618)
        (xy -1.578 -1.653)
        (xy -1.565 -1.684)
        (xy -1.556 -1.709)
        (xy -1.549 -1.729)
        (xy -1.546 -1.74)
        (xy -1.546 -1.742)
        (xy -1.549 -1.749)
        (xy -1.558 -1.763)
        (xy -1.571 -1.784)
        (xy -1.588 -1.811)
        (xy -1.61 -1.843)
        (xy -1.634 -1.88)
        (xy -1.661 -1.92)
        (xy -1.691 -1.963)
        (xy -1.722 -2.008)
        (xy -1.762 -2.067)
        (xy -1.796 -2.117)
        (xy -1.825 -2.16)
        (xy -1.848 -2.196)
        (xy -1.867 -2.225)
        (xy -1.881 -2.247)
        (xy -1.89 -2.262)
        (xy -1.895 -2.272)
        (xy -1.895 -2.275)
        (xy -1.894 -2.279)
        (xy -1.891 -2.285)
        (xy -1.884 -2.293)
        (xy -1.875 -2.305)
        (xy -1.861 -2.32)
        (xy -1.843 -2.339)
        (xy -1.82 -2.363)
        (xy -1.792 -2.392)
        (xy -1.758 -2.426)
        (xy -1.718 -2.466)
        (xy -1.676 -2.509)
        (xy -1.627 -2.557)
        (xy -1.585 -2.599)
        (xy -1.549 -2.634)
        (xy -1.52 -2.663)
        (xy -1.495 -2.686)
        (xy -1.476 -2.704)
        (xy -1.462 -2.716)
        (xy -1.452 -2.724)
        (xy -1.446 -2.728)
        (xy -1.444 -2.728)
        (xy -1.437 -2.726)
        (xy -1.423 -2.717)
        (xy -1.401 -2.703)
        (xy -1.372 -2.685)
        (xy -1.337 -2.661)
        (xy -1.295 -2.634)
        (xy -1.248 -2.602)
        (xy -1.196 -2.566)
        (xy -1.173 -2.551)
        (xy -1.118 -2.513)
        (xy -1.071 -2.481)
        (xy -1.031 -2.454)
        (xy -0.998 -2.432)
        (xy -0.97 -2.413)
        (xy -0.948 -2.399)
        (xy -0.931 -2.389)
        (xy -0.917 -2.381)
        (xy -0.907 -2.376)
        (xy -0.901 -2.373)
        (xy -0.897 -2.373)
        (xy -0.888 -2.375)
        (xy -0.87 -2.38)
        (xy -0.845 -2.39)
        (xy -0.813 -2.402)
        (xy -0.774 -2.417)
        (xy -0.73 -2.434)
        (xy -0.681 -2.454)
        (xy -0.629 -2.475)
        (xy -0.586 -2.493)
        (xy -0.55 -2.508)
        (xy -0.522 -2.52)
        (xy -0.499 -2.529)
        (xy -0.482 -2.537)
        (xy -0.47 -2.543)
        (xy -0.461 -2.548)
        (xy -0.455 -2.551)
        (xy -0.452 -2.554)
        (xy -0.449 -2.557)
        (xy -0.448 -2.56)
        (xy -0.447 -2.566)
        (xy -0.443 -2.582)
        (xy -0.438 -2.605)
        (xy -0.432 -2.637)
        (xy -0.425 -2.674)
        (xy -0.417 -2.717)
        (xy -0.407 -2.765)
        (xy -0.398 -2.817)
        (xy -0.388 -2.871)
        (xy -0.387 -2.876)
        (xy -0.375 -2.94)
        (xy -0.364 -2.995)
        (xy -0.356 -3.042)
        (xy -0.348 -3.081)
        (xy -0.342 -3.112)
        (xy -0.337 -3.137)
        (xy -0.332 -3.157)
        (xy -0.328 -3.171)
        (xy -0.325 -3.181)
        (xy -0.323 -3.188)
        (xy -0.32 -3.191)
        (xy -0.32 -3.192)
        (xy -0.317 -3.194)
        (xy -0.313 -3.195)
        (xy -0.307 -3.197)
        (xy -0.298 -3.198)
        (xy -0.286 -3.199)
        (xy -0.269 -3.199)
        (xy -0.247 -3.2)
        (xy -0.219 -3.2)
        (xy -0.184 -3.201)
        (xy -0.142 -3.201)
        (xy -0.092 -3.201)
        (xy -0.033 -3.201)
        (xy -0.001 -3.201)
        (xy 0.063 -3.201)
      )

      (stroke (width 0.01) (type solid)) (fill solid) (layer "F.Mask"))
  )

  (footprint "scalenode-cm4-baseboard-footprints:Switch_Slide_CAS-120TA" (layer "F.Cu")
    (at 120.6 59.4 180)
    (property "Author" "Antmicro")
    (property "License" "Apache-2.0")
    (property "MPN" "CAS-120TA")
    (property "Manufacturer" "Nidec Components")
    (property "Sheetfile" "interfaces.kicad_sch")
    (property "Sheetname" "Interfaces")
    (attr smd)
    (fp_text reference "S1" (at -1.25 -2.851 180) (layer "F.SilkS")
        (effects (font (size 0.7 0.7) (thickness 0.15)) (justify left bottom))
    )
    (fp_text value "CAS-120TA" (at 5.85 -0.325 180) (layer "F.Fab")
        (effects (font (size 0.7 0.7) (thickness 0.15)) (justify left bottom))
    )
    (fp_text user "License: Apache-2.0" (at -3.15 7.6 180) (layer "F.Fab") hide
        (effects (font (size 0.7 0.7) (thickness 0.15)) (justify left bottom))
    )
    (fp_text user "Author: Antmicro" (at -3.15 6.4 180) (layer "F.Fab") hide
        (effects (font (size 0.7 0.7) (thickness 0.15)) (justify left bottom))
    )
    (fp_text user "${REFERENCE}" (at -3.15 5.2 180) (layer "F.Fab") hide
        (effects (font (size 0.7 0.7) (thickness 0.15)) (justify left bottom))
    )
    (fp_circle (center -3.502 1.148) (end -3.452 1.148)
      (stroke (width 0.15) (type solid)) (fill solid) (layer "F.SilkS"))
    (fp_rect (start -3.202 -1.901) (end 3.2 1.898)
      (stroke (width 0.05) (type solid)) (fill none) (layer "F.CrtYd"))
    (fp_line (start -2.9 1.148) (end -2.9 -1.151)
      (stroke (width 0.15) (type solid)) (layer "F.Fab"))
    (fp_line (start -2.9 1.148) (end 2.898 1.148)
      (stroke (width 0.15) (type solid)) (layer "F.Fab"))
    (fp_line (start 2.898 -1.151) (end -2.9 -1.151)
      (stroke (width 0.15) (type solid)) (layer "F.Fab"))
    (fp_line (start 2.898 -1.151) (end 2.898 1.148)
      (stroke (width 0.15) (type solid)) (layer "F.Fab"))
    (pad "1" smd rect (at -1.75 1.148 180) (size 1 1.6) (layers "F.Cu" "F.Paste" "F.Mask")
      (net 27 "/Interfaces/VBus_Slave") (pinfunction "1") (pintype "passive"))
    (pad "2" smd rect (at 0 -1.151 180) (size 1 1.6) (layers "F.Cu" "F.Paste" "F.Mask")
      (net 244 "PROG_MODE") (pinfunction "2") (pintype "passive"))
    (pad "3" smd rect (at 1.749 1.148 180) (size 1 1.6) (layers "F.Cu" "F.Paste" "F.Mask")
      (net 215 "unconnected-(S1-Pad3)") (pinfunction "3") (pintype "passive+no_connect"))
  )

  (footprint "scalenode-cm4-baseboard-footprints:C_0402_1005Metric" (layer "F.Cu")
    (at 81.745 85.296 90)
    (descr "Capacitor SMD 0402")
    (tags "capacitor SMD 0402")
    (property "Author" "Antmicro")
    (property "Dielectric" "X5R")
    (property "License" "Apache-2.0")
    (property "MPN" "GRM155R61H104KE14D")
    (property "Manufacturer" "Murata")
    (property "Sheetfile" "interfaces.kicad_sch")
    (property "Sheetname" "Interfaces")
    (property "Val" "100n")
    (property "Voltage" "50V")
    (property "ki_description" " ")
    (attr smd)
    (fp_text reference "C56" (at -1.029 1.43 90) (layer "F.SilkS")
        (effects (font (size 0.7 0.7) (thickness 0.15)) (justify left bottom))
    )
    (fp_text value "C_100n_0402" (at 0 1.4 90) (layer "F.Fab")
        (effects (font (size 0.7 0.7) (thickness 0.15)) (justify left bottom))
    )
    (fp_text user "Author: Antmicro" (at -0.932 4.17 90) (layer "F.Fab") hide
        (effects (font (size 0.7 0.7) (thickness 0.15)) (justify left bottom))
    )
    (fp_text user "License: Apache-2.0" (at -0.932 5.17 90) (layer "F.Fab") hide
        (effects (font (size 0.7 0.7) (thickness 0.15)) (justify left bottom))
    )
    (fp_text user "${REFERENCE}" (at -0.932 3.168 90) (layer "F.Fab") hide
        (effects (font (size 0.7 0.7) (thickness 0.15)) (justify left bottom))
    )
    (fp_rect (start -0.94 -0.47) (end 0.94 0.47)
      (stroke (width 0.05) (type solid)) (fill none) (layer "F.CrtYd"))
    (fp_rect (start -0.499 -0.249) (end 0.499 0.249)
      (stroke (width 0.15) (type solid)) (fill none) (layer "F.Fab"))
    (pad "1" smd roundrect (at -0.484 0 90) (size 0.59 0.64) (layers "F.Cu" "F.Paste" "F.Mask") (roundrect_rratio 0.25)
      (net 27 "/Interfaces/VBus_Slave") (pintype "passive"))
    (pad "2" smd roundrect (at 0.484 0 90) (size 0.59 0.64) (layers "F.Cu" "F.Paste" "F.Mask") (roundrect_rratio 0.25)
      (net 11 "GND") (pintype "passive"))
  )

  (footprint "scalenode-cm4-baseboard-footprints:LED_0603_1608Metric_G" (layer "F.Cu")
    (at 76.1 81.541 -90)
    (descr "LED SMD 0603 Red")
    (tags "LED SMD 0603 Red")
    (property "Author" "Antmicro")
    (property "License" "Apache-2.0")
    (property "MPN" "598-8D80-107F")
    (property "Manufacturer" "Dialight")
    (property "Sheetfile" "compute-module.kicad_sch")
    (property "Sheetname" "Compute module")
    (attr smd)
    (fp_text reference "D11" (at 1.079 -1.37 -90) (layer "F.SilkS")
        (effects (font (size 0.7 0.7) (thickness 0.15)) (justify left bottom))
    )
    (fp_text value "LED_G_0603_598-8D80-107F" (at -5.041 -0.825 -90) (layer "F.Fab")
        (effects (font (size 0.7 0.7) (thickness 0.15)) (justify left bottom))
    )
    (fp_text user "Author: Antmicro" (at -1.31 4.769 -90) (layer "F.Fab") hide
        (effects (font (size 0.7 0.7) (thickness 0.15)) (justify left bottom))
    )
    (fp_text user "${REFERENCE}" (at -1.31 3.769 -90) (layer "F.Fab") hide
        (effects (font (size 0.7 0.7) (thickness 0.15)) (justify left bottom))
    )
    (fp_text user "License: Apache-2.0" (at -1.31 5.769 -90) (layer "F.Fab") hide
        (effects (font (size 0.7 0.7) (thickness 0.15)) (justify left bottom))
    )
    (fp_line (start -0.27 -0.3) (end 0.27 -0.3)
      (stroke (width 0.15) (type solid)) (layer "F.SilkS"))
    (fp_line (start -0.27 0.3) (end 0.27 0.3)
      (stroke (width 0.15) (type solid)) (layer "F.SilkS"))
    (fp_line (start 1.25 0.5) (end 1.25 -0.498)
      (stroke (width 0.15) (type solid)) (layer "F.SilkS"))
    (fp_rect (start 1.31 0.7) (end -1.31 -0.7)
      (stroke (width 0.05) (type solid)) (fill none) (layer "F.CrtYd"))
    (fp_line (start -0.599 0) (end -0.201 0)
      (stroke (width 0.15) (type solid)) (layer "F.Fab"))
    (fp_line (start -0.201 -0.2) (end -0.201 0)
      (stroke (width 0.15) (type solid)) (layer "F.Fab"))
    (fp_line (start -0.201 0) (end -0.201 0.202)
      (stroke (width 0.15) (type solid)) (layer "F.Fab"))
    (fp_line (start -0.201 0.202) (end 0.101 0)
      (stroke (width 0.15) (type solid)) (layer "F.Fab"))
    (fp_line (start 0.101 0) (end -0.201 -0.2)
      (stroke (width 0.15) (type solid)) (layer "F.Fab"))
    (fp_line (start 0.199 -0.2) (end 0.199 -0.1)
      (stroke (width 0.15) (type solid)) (layer "F.Fab"))
    (fp_line (start 0.199 0) (end 0.597 0)
      (stroke (width 0.15) (type solid)) (layer "F.Fab"))
    (fp_line (start 0.199 0.202) (end 0.199 -0.1)
      (stroke (width 0.15) (type solid)) (layer "F.Fab"))
    (fp_rect (start -0.848 -0.4) (end 0.85 0.402)
      (stroke (width 0.15) (type solid)) (fill none) (layer "F.Fab"))
    (pad "1" smd rect (at -0.75 0 90) (size 0.8 0.8) (layers "F.Cu" "F.Paste" "F.Mask")
      (net 232 "3V3_RPi") (pinfunction "1") (pintype "passive"))
    (pad "2" smd rect (at 0.75 0 90) (size 0.8 0.8) (layers "F.Cu" "F.Paste" "F.Mask")
      (net 233 "Net-(D11-Pad2)") (pinfunction "2") (pintype "passive"))
  )

  (footprint "scalenode-cm4-baseboard-footprints:UFDFN-6_1.45x1mm" (layer "F.Cu")
    (at 82.225 87.306 -90)
    (property "Author" "Antmicro")
    (property "License" "Apache-2.0")
    (property "MPN" "TPD4S012DRYR")
    (property "Manufacturer" "Texas Instruments")
    (property "Sheetfile" "interfaces.kicad_sch")
    (property "Sheetname" "Interfaces")
    (attr smd)
    (fp_text reference "D3" (at 0.444 -1.775 -90) (layer "F.SilkS")
        (effects (font (size 0.7 0.7) (thickness 0.15)) (justify left bottom))
    )
    (fp_text value "TPD4S012DRYR" (at 0 1.929 -90) (layer "F.Fab")
        (effects (font (size 0.7 0.7) (thickness 0.15)) (justify left bottom))
    )
    (fp_text user "${REFERENCE}" (at -0.98 3.929 -90) (layer "F.Fab") hide
        (effects (font (size 0.7 0.7) (thickness 0.15)) (justify left bottom))
    )
    (fp_text user "Author: Antmicro" (at -0.98 5.129 -90) (layer "F.Fab") hide
        (effects (font (size 0.7 0.7) (thickness 0.15)) (justify left bottom))
    )
    (fp_text user "License: Apache-2.0" (at -0.98 6.328 -90) (layer "F.Fab") hide
        (effects (font (size 0.7 0.7) (thickness 0.15)) (justify left bottom))
    )
    (fp_line (start -0.802 -0.6) (end -0.802 -0.5)
      (stroke (width 0.15) (type solid)) (layer "F.SilkS"))
    (fp_line (start -0.802 0.4) (end -0.802 0.598)
      (stroke (width 0.15) (type solid)) (layer "F.SilkS"))
    (fp_line (start -0.802 0.598) (end -0.701 0.598)
      (stroke (width 0.15) (type solid)) (layer "F.SilkS"))
    (fp_line (start -0.701 -0.6) (end -0.802 -0.6)
      (stroke (width 0.15) (type solid)) (layer "F.SilkS"))
    (fp_line (start -0.701 0.598) (end -0.701 0.699)
      (stroke (width 0.15) (type solid)) (layer "F.SilkS"))
    (fp_line (start 0.699 -0.6) (end 0.8 -0.6)
      (stroke (width 0.15) (type solid)) (layer "F.SilkS"))
    (fp_line (start 0.699 0.598) (end 0.8 0.598)
      (stroke (width 0.15) (type solid)) (layer "F.SilkS"))
    (fp_line (start 0.8 -0.6) (end 0.8 -0.5)
      (stroke (width 0.15) (type solid)) (layer "F.SilkS"))
    (fp_line (start 0.8 0.598) (end 0.8 0.498)
      (stroke (width 0.15) (type solid)) (layer "F.SilkS"))
    (fp_circle (center -1.526 0.39) (end -1.476 0.39)
      (stroke (width 0.15) (type solid)) (fill solid) (layer "F.SilkS"))
    (fp_line (start -0.98 -0.87) (end 0.96 -0.87)
      (stroke (width 0.05) (type solid)) (layer "F.CrtYd"))
    (fp_line (start -0.98 0.9) (end -0.98 -0.87)
      (stroke (width 0.05) (type solid)) (layer "F.CrtYd"))
    (fp_line (start -0.98 0.9) (end 0.96 0.9)
      (stroke (width 0.05) (type solid)) (layer "F.CrtYd"))
    (fp_line (start 0.96 0.9) (end 0.96 -0.87)
      (stroke (width 0.05) (type solid)) (layer "F.CrtYd"))
    (fp_line (start -0.725 0.4) (end -0.725 -0.5)
      (stroke (width 0.15) (type solid)) (layer "F.Fab"))
    (fp_line (start -0.725 0.4) (end -0.6 0.498)
      (stroke (width 0.15) (type solid)) (layer "F.Fab"))
    (fp_line (start -0.72 -0.5) (end 0.718 -0.5)
      (stroke (width 0.15) (type solid)) (layer "F.Fab"))
    (fp_line (start -0.6 0.498) (end 0.718 0.498)
      (stroke (width 0.15) (type solid)) (layer "F.Fab"))
    (fp_line (start 0.723 0.498) (end 0.723 -0.5)
      (stroke (width 0.15) (type solid)) (layer "F.Fab"))
    (pad "1" smd rect (at -0.5 0.39 270) (size 0.3 0.52) (layers "F.Cu" "F.Paste" "F.Mask")
      (net 235 "/Interfaces/CONN_USB_N") (pinfunction "D+") (pintype "input") (solder_mask_margin 0.05))
    (pad "2" smd rect (at 0 0.373 270) (size 0.3 0.49) (layers "F.Cu" "F.Paste" "F.Mask")
      (net 236 "/Interfaces/CONN_USB_P") (pinfunction "D-") (pintype "output") (solder_mask_margin 0.05))
    (pad "3" smd rect (at 0.498 0.373 270) (size 0.3 0.49) (layers "F.Cu" "F.Paste" "F.Mask")
      (net 35 "unconnected-(D3-ID-Pad3)") (pinfunction "ID") (pintype "input+no_connect") (solder_mask_margin 0.05))
    (pad "4" smd rect (at 0.498 -0.375 270) (size 0.3 0.49) (layers "F.Cu" "F.Paste" "F.Mask")
      (net 11 "GND") (pinfunction "GND") (pintype "power_in") (solder_mask_margin 0.05))
    (pad "5" smd rect (at 0 -0.375 270) (size 0.3 0.49) (layers "F.Cu" "F.Paste" "F.Mask")
      (net 161 "unconnected-(D3-NC-Pad5)") (pinfunction "NC") (pintype "no_connect") (solder_mask_margin 0.05))
    (pad "6" smd rect (at -0.5 -0.375 270) (size 0.3 0.49) (layers "F.Cu" "F.Paste" "F.Mask")
      (net 27 "/Interfaces/VBus_Slave") (pinfunction "V_{BUS}") (pintype "power_in") (solder_mask_margin 0.05))
  )

  (footprint "scalenode-cm4-baseboard-footprints:R_0603_1608Metric" (layer "F.Cu")
    (at 79.22 81.76 180)
    (descr "Resistor SMD 0603")
    (tags "resistor SMD 0603")
    (property "Author" "Antmicro")
    (property "License" "Apache-2.0")
    (property "MPN" "CR0603-FX-1001ELF")
    (property "Manufacturer" "Bourns")
    (property "Sheetfile" "compute-module.kicad_sch")
    (property "Sheetname" "Compute module")
    (property "Tolerance" "1%")
    (property "Val" "1k")
    (property "ki_description" "1k resistor in 0603 package with 1% tolerance")
    (attr smd)
    (fp_text reference "R42" (at 1.03 0.73) (layer "F.SilkS")
        (effects (font (size 0.7 0.7) (thickness 0.15)) (justify left bottom))
    )
    (fp_text value "R_1k_0603" (at 0 1.6 180) (layer "F.Fab")
        (effects (font (size 0.7 0.7) (thickness 0.15)) (justify left bottom))
    )
    (fp_text user "Author: Antmicro" (at -1.25 4.9 180) (layer "F.Fab") hide
        (effects (font (size 0.7 0.7) (thickness 0.15)) (justify left bottom))
    )
    (fp_text user "License: Apache-2.0" (at -1.25 5.9 180) (layer "F.Fab") hide
        (effects (font (size 0.7 0.7) (thickness 0.15)) (justify left bottom))
    )
    (fp_text user "${REFERENCE}" (at -1.25 3.898 180) (layer "F.Fab") hide
        (effects (font (size 0.7 0.7) (thickness 0.15)) (justify left bottom))
    )
    (fp_line (start -0.3 -0.3) (end 0.3 -0.3)
      (stroke (width 0.15) (type solid)) (layer "F.SilkS"))
    (fp_line (start -0.3 0.3) (end 0.3 0.3)
      (stroke (width 0.15) (type solid)) (layer "F.SilkS"))
    (fp_rect (start -1.25 -0.7) (end 1.25 0.7)
      (stroke (width 0.05) (type solid)) (fill none) (layer "F.CrtYd"))
    (fp_rect (start -0.8 -0.4) (end 0.8 0.4)
      (stroke (width 0.15) (type solid)) (fill none) (layer "F.Fab"))
    (pad "1" smd roundrect (at -0.7 0 180) (size 0.6 0.8) (layers "F.Cu" "F.Paste" "F.Mask") (roundrect_rratio 0.2)
      (net 227 "Net-(J7-Pad21)") (pintype "passive"))
    (pad "2" smd roundrect (at 0.7 0 180) (size 0.6 0.8) (layers "F.Cu" "F.Paste" "F.Mask") (roundrect_rratio 0.2)
      (net 233 "Net-(D11-Pad2)") (pintype "passive"))
  )

  (footprint "scalenode-cm4-baseboard-footprints:TP_SMD_1mm" (layer "F.Cu")
    (at 138.8 69)
    (property "Author" "Antmicro")
    (property "License" "Apache-2.0")
    (property "MPN" "")
    (property "Manufacturer" "")
    (property "Sheetfile" "supply.kicad_sch")
    (property "Sheetname" "Supply")
    (property "ki_description" "Test Point 1mm")
    (attr exclude_from_pos_files)
    (fp_text reference "TP7" (at 0 -0.731898) (layer "F.SilkS") hide
        (effects (font (size 0.7 0.7) (thickness 0.15)) (justify left bottom))
    )
    (fp_text value "TP_1mm_SMD" (at 0 1.4) (layer "F.Fab")
        (effects (font (size 0.7 0.7) (thickness 0.15)) (justify left bottom))
    )
    (fp_text user "${REFERENCE}" (at -0.5 2.8) (layer "F.Fab") hide
        (effects (font (size 0.7 0.7) (thickness 0.15)) (justify left bottom))
    )
    (fp_text user "License: Apache-2.0" (at -0.5 5.2) (layer "F.Fab") hide
        (effects (font (size 0.7 0.7) (thickness 0.15)) (justify left bottom))
    )
    (fp_text user "Author: Antmicro" (at -0.5 4) (layer "F.Fab") hide
        (effects (font (size 0.7 0.7) (thickness 0.15)) (justify left bottom))
    )
    (pad "1" smd circle (at 0 0) (size 1 1) (layers "F.Cu" "F.Mask")
      (net 170 "3V3_SSD") (pinfunction "1") (pintype "passive"))
  )

  (footprint "scalenode-cm4-baseboard-footprints:C_2220_5650Metric" (layer "F.Cu")
    (at 110.4 92.06)
    (descr "Capacitor SMD 2220")
    (tags "capacitor SMD 2220")
    (property "Author" "Antmicro")
    (property "Dielectric" "X7S")
    (property "License" "Apache-2.0")
    (property "MPN" "C5750X7S2A226M280KB")
    (property "Manufacturer" "TDK")
    (property "Sheetfile" "poe.kicad_sch")
    (property "Sheetname" "PoE")
    (property "Val" "22u")
    (property "Voltage" "100V")
    (property "ki_description" " ")
    (attr smd)
    (fp_text reference "C29" (at -1.15 3.69) (layer "F.SilkS")
        (effects (font (size 0.7 0.7) (thickness 0.15)) (justify left bottom))
    )
    (fp_text value "C_22u_100V_2220" (at 0 3.9) (layer "F.Fab")
        (effects (font (size 0.7 0.7) (thickness 0.15)) (justify left bottom))
    )
    (fp_text user "Author: Antmicro" (at -3.7 7.9) (layer "F.Fab") hide
        (effects (font (size 0.7 0.7) (thickness 0.15)) (justify left bottom))
    )
    (fp_text user "License: Apache-2.0" (at -3.7 6.9) (layer "F.Fab") hide
        (effects (font (size 0.7 0.7) (thickness 0.15)) (justify left bottom))
    )
    (fp_text user "${REFERENCE}" (at -3.7 5.9) (layer "F.Fab") hide
        (effects (font (size 0.7 0.7) (thickness 0.15)) (justify left bottom))
    )
    (fp_line (start -1.415 -2.61) (end 1.415 -2.61)
      (stroke (width 0.15) (type solid)) (layer "F.SilkS"))
    (fp_line (start -1.415 2.61) (end 1.415 2.61)
      (stroke (width 0.15) (type solid)) (layer "F.SilkS"))
    (fp_rect (start -3.7 -2.95) (end 3.7 2.95)
      (stroke (width 0.05) (type solid)) (fill none) (layer "F.CrtYd"))
    (fp_rect (start -2.85 -2.5) (end 2.85 2.5)
      (stroke (width 0.15) (type solid)) (fill none) (layer "F.Fab"))
    (pad "1" smd roundrect (at -2.55 0) (size 1.8 5.4) (layers "F.Cu" "F.Paste" "F.Mask") (roundrect_rratio 0.138889)
      (net 4 "GNDD") (pintype "passive"))
    (pad "2" smd roundrect (at 2.55 0) (size 1.8 5.4) (layers "F.Cu" "F.Paste" "F.Mask") (roundrect_rratio 0.138889)
      (net 6 "/PoE/VDD_POE_IN") (pintype "passive"))
  )

  (footprint "scalenode-cm4-baseboard-footprints:R_0805_2012Metric" (layer "F.Cu")
    (at 98.9 92.6)
    (property "Author" "Antmicro")
    (property "License" "Apache-2.0")
    (property "MPN" "CR0805-FX-3242ELF")
    (property "Manufacturer" "Bourns")
    (property "Sheetfile" "poe.kicad_sch")
    (property "Sheetname" "PoE")
    (property "Tolerance" "1%")
    (property "Val" "32k4")
    (property "ki_description" "32k4 resistor in 0805 package with 1% tolerance")
    (attr smd)
    (fp_text reference "R33" (at 1.75 0.425) (layer "F.SilkS")
        (effects (font (size 0.7 0.7) (thickness 0.15)) (justify left bottom))
    )
    (fp_text value "R_32k4_0805" (at 0 1.8) (layer "F.Fab")
        (effects (font (size 0.7 0.7) (thickness 0.15)) (justify left bottom))
    )
    (fp_text user "Author: Antmicro" (at -1.9 4.4) (layer "F.Fab") hide
        (effects (font (size 0.7 0.7) (thickness 0.15)) (justify left bottom))
    )
    (fp_text user "${REFERENCE}" (at -1.9 3.1) (layer "F.Fab") hide
        (effects (font (size 0.7 0.7) (thickness 0.15)) (justify left bottom))
    )
    (fp_text user "License: Apache-2.0" (at -1.9 5.75) (layer "F.Fab") hide
        (effects (font (size 0.7 0.7) (thickness 0.15)) (justify left bottom))
    )
    (fp_line (start -0.32 0.699) (end 0.28 0.699)
      (stroke (width 0.15) (type solid)) (layer "F.SilkS"))
    (fp_line (start -0.3 -0.701) (end 0.298 -0.701)
      (stroke (width 0.15) (type solid)) (layer "F.SilkS"))
    (fp_rect (start -1.75 -0.85) (end 1.75 0.85)
      (stroke (width 0.05) (type solid)) (fill none) (layer "F.CrtYd"))
    (fp_line (start -0.951 -0.682) (end 0.949 -0.682)
      (stroke (width 0.15) (type solid)) (layer "F.Fab"))
    (fp_line (start -0.951 -0.677) (end -0.951 0.675)
      (stroke (width 0.15) (type solid)) (layer "F.Fab"))
    (fp_line (start -0.951 0.68) (end 0.949 0.68)
      (stroke (width 0.15) (type solid)) (layer "F.Fab"))
    (fp_line (start 0.949 -0.677) (end 0.949 0.675)
      (stroke (width 0.15) (type solid)) (layer "F.Fab"))
    (pad "1" smd roundrect (at -1.1 -0.001) (size 1 1.4) (layers "F.Cu" "F.Paste" "F.Mask") (roundrect_rratio 0.15)
      (net 21 "Net-(D7-Pad1)") (pintype "passive"))
    (pad "2" smd roundrect (at 1.1 -0.001) (size 1 1.4) (layers "F.Cu" "F.Paste" "F.Mask") (roundrect_rratio 0.15)
      (net 6 "/PoE/VDD_POE_IN") (pintype "passive"))
  )

  (footprint "scalenode-cm4-baseboard-footprints:R_0402_1005Metric" (layer "F.Cu")
    (at 93.8 87.1 90)
    (descr "Resistor SMD 0402")
    (tags "resistor SMD 0402")
    (property "Author" "Antmicro")
    (property "DNP" "DNP")
    (property "License" "Apache-2.0")
    (property "MPN" "CR0402-FX-1002GLF")
    (property "Manufacturer" "Bourns")
    (property "Sheetfile" "poe.kicad_sch")
    (property "Sheetname" "PoE")
    (property "Tolerance" "1%")
    (property "Val" "10k")
    (property "dnp" "")
    (property "exclude_from_bom" "")
    (property "ki_description" "10k resistor in 0402 package with 1% tolerance")
    (attr exclude_from_pos_files exclude_from_bom)
    (fp_text reference "R40" (at 0.975 0.4 90) (layer "F.SilkS")
        (effects (font (size 0.7 0.7) (thickness 0.15)) (justify left bottom))
    )
    (fp_text value "R_10k_0402" (at 0 1.4 90) (layer "F.Fab")
        (effects (font (size 0.7 0.7) (thickness 0.15)) (justify left bottom))
    )
    (fp_text user "Author: Antmicro" (at -0.95 4.169 90) (layer "F.Fab") hide
        (effects (font (size 0.7 0.7) (thickness 0.15)) (justify left bottom))
    )
    (fp_text user "${REFERENCE}" (at -0.95 3.168 90) (layer "F.Fab") hide
        (effects (font (size 0.7 0.7) (thickness 0.15)) (justify left bottom))
    )
    (fp_text user "License: Apache-2.0" (at -0.95 5.169 90) (layer "F.Fab") hide
        (effects (font (size 0.7 0.7) (thickness 0.15)) (justify left bottom))
    )
    (fp_rect (start -0.95 -0.48) (end 0.95 0.48)
      (stroke (width 0.05) (type solid)) (fill none) (layer "F.CrtYd"))
    (fp_rect (start -0.5 -0.25) (end 0.5 0.25)
      (stroke (width 0.15) (type solid)) (fill none) (layer "F.Fab"))
    (pad "1" smd roundrect (at -0.485 0 90) (size 0.59 0.64) (layers "F.Cu" "F.Paste" "F.Mask") (roundrect_rratio 0.25)
      (net 262 "Net-(U3-TPL)") (pintype "passive"))
    (pad "2" smd roundrect (at 0.485 0 90) (size 0.59 0.64) (layers "F.Cu" "F.Paste" "F.Mask") (roundrect_rratio 0.25)
      (net 6 "/PoE/VDD_POE_IN") (pintype "passive"))
  )

  (footprint "scalenode-cm4-baseboard-footprints:VQFN-20_5x5x1mm_P0.65mm" (layer "F.Cu")
    (at 92.4 91.4)
    (property "Author" "Antmicro")
    (property "DNP" "DNP")
    (property "License" "Apache-2.0")
    (property "MPN" "TPS2373-3RGWR")
    (property "Manufacturer" "Texas Instruments")
    (property "Sheetfile" "poe.kicad_sch")
    (property "Sheetname" "PoE")
    (property "dnp" "")
    (property "exclude_from_bom" "")
    (property "ki_description" "High-Power PoE PD Interface with Advanced Startup")
    (attr exclude_from_pos_files exclude_from_bom)
    (fp_text reference "U3" (at -4.65 -1.15) (layer "F.SilkS")
        (effects (font (size 0.7 0.7) (thickness 0.15)) (justify left bottom))
    )
    (fp_text value "TPS2373-3RGW" (at 0 3.883) (layer "F.Fab")
        (effects (font (size 0.7 0.7) (thickness 0.15)) (justify left bottom))
    )
    (fp_text user "Author: Antmicro" (at -2.5 6.884) (layer "F.Fab") hide
        (effects (font (size 0.7 0.7) (thickness 0.15)) (justify left bottom))
    )
    (fp_text user "${REFERENCE}" (at -2.5 5.884) (layer "F.Fab") hide
        (effects (font (size 0.7 0.7) (thickness 0.15)) (justify left bottom))
    )
    (fp_text user "License: Apache-2.0" (at -2.5 7.884) (layer "F.Fab") hide
        (effects (font (size 0.7 0.7) (thickness 0.15)) (justify left bottom))
    )
    (fp_poly
      (pts
        (xy -1.081 -1.081)
        (xy -0.11 -1.081)
        (xy -0.11 -0.09)
        (xy -1.081 -0.09)
      )

      (stroke (width 0.01) (type solid)) (fill solid) (layer "F.Paste"))
    (fp_poly
      (pts
        (xy -1.081 0.088)
        (xy -0.11 0.088)
        (xy -0.11 1.08)
        (xy -1.081 1.08)
      )

      (stroke (width 0.01) (type solid)) (fill solid) (layer "F.Paste"))
    (fp_poly
      (pts
        (xy 0.108 -1.081)
        (xy 1.08 -1.081)
        (xy 1.08 -0.09)
        (xy 0.108 -0.09)
      )

      (stroke (width 0.01) (type solid)) (fill solid) (layer "F.Paste"))
    (fp_poly
      (pts
        (xy 0.108 0.088)
        (xy 1.08 0.088)
        (xy 1.08 1.08)
        (xy 0.108 1.08)
      )

      (stroke (width 0.01) (type solid)) (fill solid) (layer "F.Paste"))
    (fp_line (start -2.5 2.499) (end -2.5 1.789)
      (stroke (width 0.15) (type solid)) (layer "F.SilkS"))
    (fp_line (start -2.5 2.499) (end -1.79 2.499)
      (stroke (width 0.15) (type solid)) (layer "F.SilkS"))
    (fp_line (start -1.625 -2.5) (end -2.5 -2.5)
      (stroke (width 0.15) (type solid)) (layer "F.SilkS"))
    (fp_line (start 2.499 -2.5) (end 1.789 -2.5)
      (stroke (width 0.15) (type solid)) (layer "F.SilkS"))
    (fp_line (start 2.499 -2.5) (end 2.499 -1.79)
      (stroke (width 0.15) (type solid)) (layer "F.SilkS"))
    (fp_line (start 2.499 2.499) (end 1.789 2.499)
      (stroke (width 0.15) (type solid)) (layer "F.SilkS"))
    (fp_line (start 2.499 2.499) (end 2.499 1.789)
      (stroke (width 0.15) (type solid)) (layer "F.SilkS"))
    (fp_circle (center -2.775 -1.875) (end -2.725 -1.825)
      (stroke (width 0.15) (type solid)) (fill solid) (layer "F.SilkS"))
    (fp_rect (start -2.95 -2.95) (end 2.95 2.95)
      (stroke (width 0.05) (type solid)) (fill none) (layer "F.CrtYd"))
    (fp_line (start -2.5 -1.65) (end -1.65 -2.5)
      (stroke (width 0.15) (type solid)) (layer "F.Fab"))
    (fp_line (start -2.5 2.499) (end -2.5 -1.65)
      (stroke (width 0.15) (type solid)) (layer "F.Fab"))
    (fp_line (start 2.499 -2.5) (end -1.65 -2.5)
      (stroke (width 0.15) (type solid)) (layer "F.Fab"))
    (fp_line (start 2.499 2.499) (end -2.5 2.499)
      (stroke (width 0.15) (type solid)) (layer "F.Fab"))
    (fp_line (start 2.499 2.499) (end 2.499 -2.5)
      (stroke (width 0.15) (type solid)) (layer "F.Fab"))
    (pad "1" smd roundrect (at -2.327 -1.301) (size 0.75 0.31) (layers "F.Cu" "F.Paste" "F.Mask") (roundrect_rratio 0.25)
      (net 6 "/PoE/VDD_POE_IN") (pinfunction "VDD") (pintype "power_in"))
    (pad "2" smd roundrect (at -2.327 -0.652) (size 0.75 0.31) (layers "F.Cu" "F.Paste" "F.Mask") (roundrect_rratio 0.25)
      (net 258 "Net-(U3-DEN)") (pinfunction "DEN") (pintype "input"))
    (pad "3" smd roundrect (at -2.327 0) (size 0.75 0.31) (layers "F.Cu" "F.Paste" "F.Mask") (roundrect_rratio 0.25)
      (net 254 "Net-(U3-CLSA)") (pinfunction "CLSA") (pintype "input"))
    (pad "4" smd roundrect (at -2.327 0.65) (size 0.75 0.31) (layers "F.Cu" "F.Paste" "F.Mask") (roundrect_rratio 0.25)
      (net 5 "VSS") (pinfunction "VSS") (pintype "power_in"))
    (pad "5" smd roundrect (at -2.327 1.3) (size 0.75 0.31) (layers "F.Cu" "F.Paste" "F.Mask") (roundrect_rratio 0.25)
      (net 5 "VSS") (pinfunction "VSS") (pintype "passive"))
    (pad "6" smd roundrect (at -1.301 2.325) (size 0.31 0.75) (layers "F.Cu" "F.Paste" "F.Mask") (roundrect_rratio 0.25)
      (net 257 "Net-(U3-CLSB)") (pinfunction "CLSB") (pintype "input"))
    (pad "7" smd roundrect (at -0.652 2.325) (size 0.31 0.75) (layers "F.Cu" "F.Paste" "F.Mask") (roundrect_rratio 0.25)
      (net 260 "Net-(U3-REF)") (pinfunction "REF") (pintype "input"))
    (pad "8" smd roundrect (at 0 2.325) (size 0.31 0.75) (layers "F.Cu" "F.Paste" "F.Mask") (roundrect_rratio 0.25)
      (net 259 "Net-(U3-AMPS_CTL)") (pinfunction "AMPS_CTL") (pintype "input"))
    (pad "9" smd roundrect (at 0.65 2.325) (size 0.31 0.75) (layers "F.Cu" "F.Paste" "F.Mask") (roundrect_rratio 0.25)
      (net 5 "VSS") (pinfunction "MPS_DUTY") (pintype "input"))
    (pad "10" smd roundrect (at 1.3 2.325) (size 0.31 0.75) (layers "F.Cu" "F.Paste" "F.Mask") (roundrect_rratio 0.25)
      (net 4 "GNDD") (pinfunction "APD") (pintype "input"))
    (pad "11" smd roundrect (at 2.325 1.3) (size 0.75 0.31) (layers "F.Cu" "F.Paste" "F.Mask") (roundrect_rratio 0.25)
      (net 4 "GNDD") (pinfunction "RTN") (pintype "power_out"))
    (pad "12" smd roundrect (at 2.325 0.65) (size 0.75 0.31) (layers "F.Cu" "F.Paste" "F.Mask") (roundrect_rratio 0.25)
      (net 4 "GNDD") (pinfunction "RTN") (pintype "passive"))
    (pad "13" smd roundrect (at 2.325 0) (size 0.75 0.31) (layers "F.Cu" "F.Paste" "F.Mask") (roundrect_rratio 0.25)
      (net 34 "/PoE/POE_ACTIVE") (pinfunction "PG") (pintype "output"))
    (pad "14" smd roundrect (at 2.325 -0.652) (size 0.75 0.31) (layers "F.Cu" "F.Paste" "F.Mask") (roundrect_rratio 0.25)
      (net 271 "Net-(U3-VC_OUT)") (pinfunction "VC_OUT") (pintype "output"))
    (pad "15" smd roundrect (at 2.325 -1.301) (size 0.75 0.31) (layers "F.Cu" "F.Paste" "F.Mask") (roundrect_rratio 0.25)
      (net 269 "Net-(U3-VC_IN)") (pinfunction "VC_IN") (pintype "input"))
    (pad "16" smd roundrect (at 1.3 -2.327) (size 0.31 0.75) (layers "F.Cu" "F.Paste" "F.Mask") (roundrect_rratio 0.25)
      (net 272 "Net-(U3-UVLO_SEL)") (pinfunction "UVLO_SEL") (pintype "output"))
    (pad "17" smd roundrect (at 0.65 -2.327) (size 0.31 0.75) (layers "F.Cu" "F.Paste" "F.Mask") (roundrect_rratio 0.25)
      (net 262 "Net-(U3-TPL)") (pinfunction "TPL") (pintype "output"))
    (pad "18" smd roundrect (at 0 -2.327) (size 0.31 0.75) (layers "F.Cu" "F.Paste" "F.Mask") (roundrect_rratio 0.25)
      (net 261 "Net-(U3-TPH)") (pinfunction "TPH") (pintype "output"))
    (pad "19" smd roundrect (at -0.652 -2.327) (size 0.31 0.75) (layers "F.Cu" "F.Paste" "F.Mask") (roundrect_rratio 0.25)
      (net 263 "Net-(U3-~{BT})") (pinfunction "~{BT}") (pintype "output"))
    (pad "20" smd roundrect (at -1.301 -2.327) (size 0.31 0.75) (layers "F.Cu" "F.Paste" "F.Mask") (roundrect_rratio 0.25))
    (pad "21" smd rect (at 0 0) (size 2.2 2.2) (layers "F.Cu" "F.Mask")
      (net 5 "VSS") (pinfunction "VSS") (pintype "passive"))
  )

  (footprint "scalenode-cm4-baseboard-footprints:LED_0603_1608Metric_G" (layer "F.Cu")
    (at 76.1 78.681 -90)
    (descr "LED SMD 0603 Red")
    (tags "LED SMD 0603 Red")
    (property "Author" "Antmicro")
    (property "License" "Apache-2.0")
    (property "MPN" "598-8D80-107F")
    (property "Manufacturer" "Dialight")
    (property "Sheetfile" "nvme-ssd.kicad_sch")
    (property "Sheetname" "NVMe SSD")
    (attr smd)
    (fp_text reference "D1" (at -0.735969 -1.474009 90) (layer "F.SilkS")
        (effects (font (size 0.7 0.7) (thickness 0.15)) (justify right bottom))
    )
    (fp_text value "LED_G_0603_598-8D80-107F" (at 0 1.6 90) (layer "F.Fab")
        (effects (font (size 0.7 0.7) (thickness 0.15)) (justify right bottom))
    )
    (fp_text user "Author: Antmicro" (at -1.31 4.769 90) (layer "F.Fab") hide
        (effects (font (size 0.7 0.7) (thickness 0.15)) (justify right bottom))
    )
    (fp_text user "${REFERENCE}" (at -1.31 3.769 90) (layer "F.Fab") hide
        (effects (font (size 0.7 0.7) (thickness 0.15)) (justify right bottom))
    )
    (fp_text user "License: Apache-2.0" (at -1.31 5.769 90) (layer "F.Fab") hide
        (effects (font (size 0.7 0.7) (thickness 0.15)) (justify right bottom))
    )
    (fp_line (start -0.27 -0.35) (end 0.27 -0.35)
      (stroke (width 0.15) (type solid)) (layer "F.SilkS"))
    (fp_line (start -0.27 0.351) (end 0.27 0.351)
      (stroke (width 0.15) (type solid)) (layer "F.SilkS"))
    (fp_line (start -0.106328 -0.200008) (end -0.106328 0.199992)
      (stroke (width 0.1) (type solid)) (layer "F.SilkS"))
    (fp_line (start -0.106328 -0.200008) (end 0.093672 -0.000008)
      (stroke (width 0.1) (type solid)) (layer "F.SilkS"))
    (fp_line (start -0.106328 -0.000008) (end -0.29 0)
      (stroke (width 0.1) (type solid)) (layer "F.SilkS"))
    (fp_line (start 0.093672 -0.200008) (end 0.093672 0.199992)
      (stroke (width 0.1) (type solid)) (layer "F.SilkS"))
    (fp_line (start 0.093672 -0.000008) (end -0.106328 0.199992)
      (stroke (width 0.1) (type solid)) (layer "F.SilkS"))
    (fp_line (start 0.093672 -0.000008) (end 0.293672 -0.000008)
      (stroke (width 0.1) (type solid)) (layer "F.SilkS"))
    (fp_line (start 1.25 0.32) (end 1.25 -0.32)
      (stroke (width 0.15) (type solid)) (layer "F.SilkS"))
    (fp_rect (start 1.26 0.65) (end -1.26 -0.65)
      (stroke (width 0.05) (type solid)) (fill none) (layer "F.CrtYd"))
    (fp_line (start -0.599 0) (end -0.201 0)
      (stroke (width 0.15) (type solid)) (layer "F.Fab"))
    (fp_line (start -0.201 -0.2) (end -0.201 0)
      (stroke (width 0.15) (type solid)) (layer "F.Fab"))
    (fp_line (start -0.201 0) (end -0.201 0.202)
      (stroke (width 0.15) (type solid)) (layer "F.Fab"))
    (fp_line (start -0.201 0.202) (end 0.101 0)
      (stroke (width 0.15) (type solid)) (layer "F.Fab"))
    (fp_line (start 0.101 0) (end -0.201 -0.2)
      (stroke (width 0.15) (type solid)) (layer "F.Fab"))
    (fp_line (start 0.199 -0.2) (end 0.199 -0.1)
      (stroke (width 0.15) (type solid)) (layer "F.Fab"))
    (fp_line (start 0.199 0) (end 0.597 0)
      (stroke (width 0.15) (type solid)) (layer "F.Fab"))
    (fp_line (start 0.199 0.202) (end 0.199 -0.1)
      (stroke (width 0.15) (type solid)) (layer "F.Fab"))
    (fp_rect (start -0.848 -0.4) (end 0.85 0.402)
      (stroke (width 0.15) (type solid)) (fill none) (layer "F.Fab"))
    (pad "1" smd rect (at -0.75 0 90) (size 0.8 0.8) (layers "F.Cu" "F.Paste" "F.Mask")
      (net 188 "Net-(D1-Pad1)") (pinfunction "1") (pintype "passive"))
    (pad "2" smd rect (at 0.75 0 90) (size 0.8 0.8) (layers "F.Cu" "F.Paste" "F.Mask")
      (net 26 "Net-(J3-LED)") (pinfunction "2") (pintype "passive"))
  )

  (footprint "scalenode-cm4-baseboard-footprints:URB4805YMD-30WR3" (layer "F.Cu")
    (at 117.09 73.05)
    (property "Author" "Antmicro")
    (property "DNP" "DNP")
    (property "License" "Apache-2.0")
    (property "MPN" "URB4805YMD-30WR3")
    (property "Manufacturer" "Mornsun")
    (property "Sheetfile" "poe.kicad_sch")
    (property "Sheetname" "PoE")
    (property "dnp" "")
    (property "exclude_from_bom" "")
    (property "ki_description" "DC-DC CONVERTER, 48VDC input, 5VDC nom isolated output w/ trim option, 30W, 270kHz PWM mode")
    (property "ki_keywords" "dc converter step down 5v 48v isolated 30W poe")
    (attr exclude_from_pos_files exclude_from_bom)
    (fp_text reference "U4" (at -2.74 -2.83) (layer "F.SilkS")
        (effects (font (size 0.7 0.7) (thickness 0.15)) (justify left bottom))
    )
    (fp_text value "URB4805YMD-30WR3" (at 10.885 20.75) (layer "F.Fab")
        (effects (font (size 0.7 0.7) (thickness 0.15)) (justify left bottom))
    )
    (fp_text user "Author: Antmicro" (at -3.44 28.193) (layer "F.Fab") hide
        (effects (font (size 0.7 0.7) (thickness 0.15)) (justify left bottom))
    )
    (fp_text user "${REFERENCE}" (at -3.44 26.995 unlocked) (layer "F.Fab") hide
        (effects (font (size 0.7 0.7) (thickness 0.15)) (justify left bottom))
    )
    (fp_text user "Apache-2.0 License" (at 11.2 26) (layer "F.Fab") hide
        (effects (font (size 1 1) (thickness 0.15)))
    )
    (fp_text user "License: Apache-2.0" (at -3.44 25.795) (layer "F.Fab") hide
        (effects (font (size 0.7 0.7) (thickness 0.15)) (justify left bottom))
    )
    (fp_text user "Copyright (c) 2023 Antmicro" (at 11.07 25.27) (layer "F.Fab") hide
        (effects (font (size 1 1) (thickness 0.15)))
    )
    (fp_line (start -2.54 -2.54) (end 22.859 -2.54)
      (stroke (width 0.15) (type solid)) (layer "F.SilkS"))
    (fp_line (start -2.54 22.859) (end -2.54 -2.54)
      (stroke (width 0.15) (type solid)) (layer "F.SilkS"))
    (fp_line (start 22.859 -2.54) (end 22.859 22.859)
      (stroke (width 0.15) (type solid)) (layer "F.SilkS"))
    (fp_line (start 22.859 22.859) (end -2.54 22.859)
      (stroke (width 0.15) (type solid)) (layer "F.SilkS"))
    (fp_circle (center -3.048 0) (end -2.95 0)
      (stroke (width 0.15) (type solid)) (fill none) (layer "F.SilkS"))
    (fp_line (start -2.79 -2.79) (end 23.1 -2.79)
      (stroke (width 0.05) (type solid)) (layer "F.CrtYd"))
    (fp_line (start -2.79 23.1) (end -2.79 -2.79)
      (stroke (width 0.05) (type solid)) (layer "F.CrtYd"))
    (fp_line (start 23.1 -2.79) (end 23.1 23.1)
      (stroke (width 0.05) (type solid)) (layer "F.CrtYd"))
    (fp_line (start 23.1 23.1) (end -2.79 23.1)
      (stroke (width 0.05) (type solid)) (layer "F.CrtYd"))
    (fp_line (start -2.54 -2.54) (end -2.54 22.859)
      (stroke (width 0.15) (type solid)) (layer "F.Fab"))
    (fp_line (start -2.54 -2.54) (end 22.859 -2.54)
      (stroke (width 0.15) (type solid)) (layer "F.Fab"))
    (fp_line (start -2.54 22.859) (end 22.859 22.859)
      (stroke (width 0.15) (type solid)) (layer "F.Fab"))
    (fp_line (start 22.859 22.859) (end 22.859 -2.54)
      (stroke (width 0.15) (type solid)) (layer "F.Fab"))
    (fp_circle (center -3.048 0) (end -2.95 0)
      (stroke (width 0.15) (type solid)) (fill none) (layer "F.Fab"))
    (pad "1" thru_hole rect (at 0 0) (size 2.25 2.25) (drill 1.5) (layers "*.Cu" "*.Mask")
      (net 34 "/PoE/POE_ACTIVE") (pinfunction "CTRL") (pintype "input"))
    (pad "2" thru_hole circle (at 0 7.618) (size 2.25 2.25) (drill 1.5) (layers "*.Cu" "*.Mask")
      (net 4 "GNDD") (pinfunction "GND") (pintype "power_in"))
    (pad "3" thru_hole circle (at 0 12.698) (size 2.25 2.25) (drill 1.5) (layers "*.Cu" "*.Mask")
      (net 6 "/PoE/VDD_POE_IN") (pinfunction "V_{IN}") (pintype "power_in"))
    (pad "4" thru_hole circle (at 20.318 20.318) (size 2.25 2.25) (drill 1.5) (layers "*.Cu" "*.Mask")
      (net 13 "/PoE/VO5V") (pinfunction "V_{O}") (pintype "power_out"))
    (pad "5" thru_hole circle (at 20.318 10.159) (size 2.25 2.25) (drill 1.5) (layers "*.Cu" "*.Mask")
      (net 273 "unconnected-(U4-TRIM-Pad5)") (pinfunction "TRIM") (pintype "passive+no_connect"))
    (pad "6" thru_hole circle (at 20.318 0) (size 2.25 2.25) (drill 1.5) (layers "*.Cu" "*.Mask")
      (net 11 "GND") (pinfunction "0V") (pintype "power_out"))
  )

  (footprint "scalenode-cm4-baseboard-footprints:TP_SMD_1mm" (layer "F.Cu")
    (at 133.2 68.8842)
    (property "Author" "Antmicro")
    (property "License" "Apache-2.0")
    (property "MPN" "")
    (property "Manufacturer" "")
    (property "Sheetfile" "poe.kicad_sch")
    (property "Sheetname" "PoE")
    (property "ki_description" "Test Point 1mm")
    (attr exclude_from_pos_files)
    (fp_text reference "TP5" (at 0 -0.731898) (layer "F.SilkS") hide
        (effects (font (size 0.7 0.7) (thickness 0.15)) (justify left bottom))
    )
    (fp_text value "TP_1mm_SMD" (at 0 1.4) (layer "F.Fab")
        (effects (font (size 0.7 0.7) (thickness 0.15)) (justify left bottom))
    )
    (fp_text user "License: Apache-2.0" (at -0.5 5.2) (layer "F.Fab") hide
        (effects (font (size 0.7 0.7) (thickness 0.15)) (justify left bottom))
    )
    (fp_text user "Author: Antmicro" (at -0.5 4) (layer "F.Fab") hide
        (effects (font (size 0.7 0.7) (thickness 0.15)) (justify left bottom))
    )
    (fp_text user "${REFERENCE}" (at -0.5 2.8) (layer "F.Fab") hide
        (effects (font (size 0.7 0.7) (thickness 0.15)) (justify left bottom))
    )
    (pad "1" smd circle (at 0 0) (size 1 1) (layers "F.Cu" "F.Mask")
      (net 12 "VCC5V0") (pinfunction "1") (pintype "passive"))
  )

  (footprint "scalenode-cm4-baseboard-footprints:R_0402_1005Metric" (layer "F.Cu")
    (at 89.8 95.6 -90)
    (descr "Resistor SMD 0402")
    (tags "resistor SMD 0402")
    (property "Author" "Antmicro")
    (property "DNP" "DNP")
    (property "License" "Apache-2.0")
    (property "MPN" "CR0402-FX-63R4GLF")
    (property "Manufacturer" "Bourns")
    (property "Sheetfile" "poe.kicad_sch")
    (property "Sheetname" "PoE")
    (property "Tolerance" "1%")
    (property "Val" "63R4")
    (property "dnp" "")
    (property "exclude_from_bom" "")
    (property "ki_description" "63R4 resistor in 0402 package with 1% tolerance")
    (attr exclude_from_pos_files exclude_from_bom)
    (fp_text reference "R35" (at 1.1 0.65 -90) (layer "F.SilkS")
        (effects (font (size 0.7 0.7) (thickness 0.15)) (justify left bottom))
    )
    (fp_text value "R_63R4_0402" (at 0 1.4 -90) (layer "F.Fab")
        (effects (font (size 0.7 0.7) (thickness 0.15)) (justify left bottom))
    )
    (fp_text user "${REFERENCE}" (at -0.95 3.168 -90) (layer "F.Fab") hide
        (effects (font (size 0.7 0.7) (thickness 0.15)) (justify left bottom))
    )
    (fp_text user "License: Apache-2.0" (at -0.95 5.169 -90) (layer "F.Fab") hide
        (effects (font (size 0.7 0.7) (thickness 0.15)) (justify left bottom))
    )
    (fp_text user "Author: Antmicro" (at -0.95 4.169 -90) (layer "F.Fab") hide
        (effects (font (size 0.7 0.7) (thickness 0.15)) (justify left bottom))
    )
    (fp_rect (start -0.95 -0.48) (end 0.95 0.48)
      (stroke (width 0.05) (type solid)) (fill none) (layer "F.CrtYd"))
    (fp_rect (start -0.5 -0.25) (end 0.5 0.25)
      (stroke (width 0.15) (type solid)) (fill none) (layer "F.Fab"))
    (pad "1" smd roundrect (at -0.485 0 270) (size 0.59 0.64) (layers "F.Cu" "F.Paste" "F.Mask") (roundrect_rratio 0.25)
      (net 257 "Net-(U3-CLSB)") (pintype "passive"))
    (pad "2" smd roundrect (at 0.485 0 270) (size 0.59 0.64) (layers "F.Cu" "F.Paste" "F.Mask") (roundrect_rratio 0.25)
      (net 5 "VSS") (pintype "passive"))
  )

  (footprint "scalenode-cm4-baseboard-footprints:Ethernet_Jack_SS-74800-144" (layer "F.Cu")
    (at 88.923 71.45 90)
    (descr "https://www.belfuse.com/resources/drawings/stewartconnector/dr-STW-SS-74800-144.pdf")
    (property "Author" "Antmicro")
    (property "License" "Apache-2.0")
    (property "MPN" "SS-74800-144")
    (property "Manufacturer" "Bel")
    (property "Sheetfile" "poe.kicad_sch")
    (property "Sheetname" "PoE")
    (property "ki_description" "Jack Modular Connector 8p8c (RJ45, Ethernet) 90° Angle (Right) Shielded, EMI Finger Cat5e")
    (property "ki_keywords" "CONNECTOR")
    (attr through_hole)
    (fp_text reference "J6" (at -6.3 -2.423 180) (layer "F.SilkS")
        (effects (font (size 0.7 0.7) (thickness 0.15)) (justify right bottom))
    )
    (fp_text value "SS-74800-144" (at 0 -14.6 90) (layer "F.Fab")
        (effects (font (size 0.7 0.7) (thickness 0.15)) (justify right bottom))
    )
    (fp_text user "License: Apache-2.0" (at -12.471 18.341 90) (layer "F.Fab") hide
        (effects (font (size 0.7 0.7) (thickness 0.15)) (justify left bottom))
    )
    (fp_text user "${REFERENCE}" (at -12.471 15.941 90) (layer "F.Fab") hide
        (effects (font (size 0.7 0.7) (thickness 0.15)) (justify left bottom))
    )
    (fp_text user "Author: Antmicro" (at -12.471 17.141 90) (layer "F.Fab") hide
        (effects (font (size 0.7 0.7) (thickness 0.15)) (justify left bottom))
    )
    (fp_circle (center 0 6.85) (end -0.05 6.85)
      (stroke (width 0.15) (type solid)) (fill solid) (layer "F.SilkS"))
    (fp_line (start -5.4356 -13.9446) (end -5.4356 6.731)
      (stroke (width 0.05) (type solid)) (layer "F.CrtYd"))
    (fp_line (start -5.4356 -13.9446) (end 12.5476 -13.9446)
      (stroke (width 0.05) (type solid)) (layer "F.CrtYd"))
    (fp_line (start 12.5476 -13.9446) (end 12.5476 6.731)
      (stroke (width 0.05) (type solid)) (layer "F.CrtYd"))
    (fp_line (start 12.5476 6.731) (end -5.4356 6.731)
      (stroke (width 0.05) (type solid)) (layer "F.CrtYd"))
    (pad "1" thru_hole circle (at 0 0 270) (size 1.524 1.524) (drill 0.89) (layers "*.Cu" "*.Mask")
      (net 153 "/PoE/T_ETH_D0_P") (pintype "passive"))
    (pad "2" thru_hole circle (at 1.016 1.778 270) (size 1.524 1.524) (drill 0.89) (layers "*.Cu" "*.Mask")
      (net 154 "/PoE/T_ETH_D0_N") (pintype "passive"))
    (pad "3" thru_hole circle (at 2.032 0 270) (size 1.524 1.524) (drill 0.89) (layers "*.Cu" "*.Mask")
      (net 155 "/PoE/T_ETH_D1_P") (pintype "passive"))
    (pad "4" thru_hole circle (at 3.048 1.778 270) (size 1.524 1.524) (drill 0.89) (layers "*.Cu" "*.Mask")
      (net 156 "/PoE/T_ETH_D2_P") (pintype "passive"))
    (pad "5" thru_hole circle (at 4.064 0 270) (size 1.524 1.524) (drill 0.89) (layers "*.Cu" "*.Mask")
      (net 157 "/PoE/T_ETH_D2_N") (pintype "passive"))
    (pad "6" thru_hole circle (at 5.08 1.778 270) (size 1.524 1.524) (drill 0.89) (layers "*.Cu" "*.Mask")
      (net 158 "/PoE/T_ETH_D1_N") (pintype "passive"))
    (pad "7" thru_hole circle (at 6.096 0 270) (size 1.524 1.524) (drill 0.89) (layers "*.Cu" "*.Mask")
      (net 159 "/PoE/T_ETH_D3_P") (pintype "passive"))
    (pad "8" thru_hole circle (at 7.112 1.778 270) (size 1.524 1.524) (drill 0.89) (layers "*.Cu" "*.Mask")
      (net 160 "/PoE/T_ETH_D3_N") (pintype "passive"))
    (pad "9" thru_hole circle (at -2.9718 4.1402 270) (size 1.7 1.7) (drill 1) (layers "*.Cu" "*.Mask")
      (net 86 "ETH_LEDY") (pinfunction "9") (pintype "passive"))
    (pad "10" thru_hole circle (at -0.6858 4.1402 270) (size 1.7 1.7) (drill 1) (layers "*.Cu" "*.Mask")
      (net 225 "Net-(J6-Pad10)") (pinfunction "10") (pintype "passive"))
    (pad "11" thru_hole circle (at 7.7978 4.1402 270) (size 1.7 1.7) (drill 1) (layers "*.Cu" "*.Mask")
      (net 84 "ETH_LEDG") (pinfunction "11") (pintype "passive"))
    (pad "12" thru_hole circle (at 10.0838 4.1402 270) (size 1.7 1.7) (drill 1) (layers "*.Cu" "*.Mask")
      (net 226 "Net-(J6-Pad12)") (pinfunction "12") (pintype "passive"))
    (pad "SH" thru_hole oval (at -6.3627 -6.2738 270) (size 1.6 3) (drill oval 0.89 2.39) (layers "*.Cu" "*.Mask")
      (net 230 "Earth") (pinfunction "SHIELD") (pintype "passive"))
    (pad "SH" thru_hole oval (at 13.4747 -6.2738 270) (size 1.6 3) (drill oval 0.89 2.39) (layers "*.Cu" "*.Mask")
      (net 230 "Earth") (pinfunction "SHIELD") (pintype "passive"))
  )

  (footprint "scalenode-cm4-baseboard-footprints:TP_SMD_1mm" (layer "F.Cu")
    (at 123.2858 68.8842)
    (property "Author" "Antmicro")
    (property "License" "Apache-2.0")
    (property "MPN" "")
    (property "Manufacturer" "")
    (property "Sheetfile" "poe.kicad_sch")
    (property "Sheetname" "PoE")
    (property "ki_description" "Test Point 1mm")
    (attr exclude_from_pos_files)
    (fp_text reference "TP4" (at 0 -0.731898) (layer "F.SilkS") hide
        (effects (font (size 0.7 0.7) (thickness 0.15)) (justify left bottom))
    )
    (fp_text value "TP_1mm_SMD" (at 0 1.4) (layer "F.Fab")
        (effects (font (size 0.7 0.7) (thickness 0.15)) (justify left bottom))
    )
    (fp_text user "${REFERENCE}" (at -0.5 2.8) (layer "F.Fab") hide
        (effects (font (size 0.7 0.7) (thickness 0.15)) (justify left bottom))
    )
    (fp_text user "Author: Antmicro" (at -0.5 4) (layer "F.Fab") hide
        (effects (font (size 0.7 0.7) (thickness 0.15)) (justify left bottom))
    )
    (fp_text user "License: Apache-2.0" (at -0.5 5.2) (layer "F.Fab") hide
        (effects (font (size 0.7 0.7) (thickness 0.15)) (justify left bottom))
    )
    (pad "1" smd circle (at 0 0) (size 1 1) (layers "F.Cu" "F.Mask")
      (net 11 "GND") (pinfunction "1") (pintype "passive"))
  )

  (footprint "scalenode-cm4-baseboard-footprints:R_0402_1005Metric" (layer "F.Cu")
    (at 91.3 95.1)
    (descr "Resistor SMD 0402")
    (tags "resistor SMD 0402")
    (property "Author" "Antmicro")
    (property "DNP" "DNP")
    (property "License" "Apache-2.0")
    (property "MPN" "CR0402-FX-4992GLF")
    (property "Manufacturer" "Bourns")
    (property "Sheetfile" "poe.kicad_sch")
    (property "Sheetname" "PoE")
    (property "Tolerance" "1%")
    (property "Val" "49k9")
    (property "dnp" "")
    (property "exclude_from_bom" "")
    (property "ki_description" "49k9 resistor in 0402 package with 1% tolerance")
    (attr exclude_from_pos_files exclude_from_bom)
    (fp_text reference "R38" (at -1.05 1.375) (layer "F.SilkS")
        (effects (font (size 0.7 0.7) (thickness 0.15)) (justify left bottom))
    )
    (fp_text value "R_49k9_0402" (at 0 1.4) (layer "F.Fab")
        (effects (font (size 0.7 0.7) (thickness 0.15)) (justify left bottom))
    )
    (fp_text user "${REFERENCE}" (at -0.95 3.168) (layer "F.Fab") hide
        (effects (font (size 0.7 0.7) (thickness 0.15)) (justify left bottom))
    )
    (fp_text user "License: Apache-2.0" (at -0.95 5.169) (layer "F.Fab") hide
        (effects (font (size 0.7 0.7) (thickness 0.15)) (justify left bottom))
    )
    (fp_text user "Author: Antmicro" (at -0.95 4.169) (layer "F.Fab") hide
        (effects (font (size 0.7 0.7) (thickness 0.15)) (justify left bottom))
    )
    (fp_rect (start -0.95 -0.48) (end 0.95 0.48)
      (stroke (width 0.05) (type solid)) (fill none) (layer "F.CrtYd"))
    (fp_rect (start -0.5 -0.25) (end 0.5 0.25)
      (stroke (width 0.15) (type solid)) (fill none) (layer "F.Fab"))
    (pad "1" smd roundrect (at -0.485 0) (size 0.59 0.64) (layers "F.Cu" "F.Paste" "F.Mask") (roundrect_rratio 0.25)
      (net 5 "VSS") (pintype "passive"))
    (pad "2" smd roundrect (at 0.485 0) (size 0.59 0.64) (layers "F.Cu" "F.Paste" "F.Mask") (roundrect_rratio 0.25)
      (net 260 "Net-(U3-REF)") (pintype "passive"))
  )

  (footprint "scalenode-cm4-baseboard-footprints:TP_SMD_1mm" (layer "F.Cu")
    (at 128.2858 68.8842)
    (property "Author" "Antmicro")
    (property "License" "Apache-2.0")
    (property "MPN" "")
    (property "Manufacturer" "")
    (property "Sheetfile" "compute-module.kicad_sch")
    (property "Sheetname" "Compute module")
    (property "ki_description" "Test Point 1mm")
    (attr exclude_from_pos_files)
    (fp_text reference "TP6" (at 0 -0.731898) (layer "F.SilkS") hide
        (effects (font (size 0.7 0.7) (thickness 0.15)) (justify left bottom))
    )
    (fp_text value "TP_1mm_SMD" (at 0 1.4) (layer "F.Fab")
        (effects (font (size 0.7 0.7) (thickness 0.15)) (justify left bottom))
    )
    (fp_text user "License: Apache-2.0" (at -0.5 5.2) (layer "F.Fab") hide
        (effects (font (size 0.7 0.7) (thickness 0.15)) (justify left bottom))
    )
    (fp_text user "${REFERENCE}" (at -0.5 2.8) (layer "F.Fab") hide
        (effects (font (size 0.7 0.7) (thickness 0.15)) (justify left bottom))
    )
    (fp_text user "Author: Antmicro" (at -0.5 4) (layer "F.Fab") hide
        (effects (font (size 0.7 0.7) (thickness 0.15)) (justify left bottom))
    )
    (pad "1" smd circle (at 0 0) (size 1 1) (layers "F.Cu" "F.Mask")
      (net 232 "3V3_RPi") (pinfunction "1") (pintype "passive"))
  )

  (footprint "scalenode-cm4-baseboard-footprints:Compute-Module-4_H1.5mm" locked (layer "F.Cu")
    (at 164 56.125)
    (property "Author" "Antmicro")
    (property "License" "Apache-2.0")
    (property "MPN" "SC0294")
    (property "Manufacturer" "Raspberry Pi")
    (property "Sheetfile" "compute-module.kicad_sch")
    (property "Sheetname" "Compute module")
    (property "ki_keywords" "rpi raspberry pi cm4 compute module 4 ")
    (attr through_hole exclude_from_pos_files exclude_from_bom)
    (fp_text reference "M1" (at -23.125 39.925) (layer "F.SilkS")
        (effects (font (size 0.7 0.7) (thickness 0.15)) (justify left bottom))
    )
    (fp_text value "Compute-Module-4_H1.5mm" (at 0 -0.5) (layer "F.Fab")
        (effects (font (size 0.7 0.7) (thickness 0.15)) (justify left bottom))
    )
    (fp_text user "1" (at 14.599 35.6) (layer "F.SilkS")
        (effects (font (size 0.7 0.7) (thickness 0.15)) (justify left bottom))
    )
    (fp_text user "99" (at -8.5 1.699) (layer "F.SilkS")
        (effects (font (size 0.7 0.7) (thickness 0.15)) (justify left bottom))
    )
    (fp_text user "100" (at -8.5 5.7) (layer "F.SilkS")
        (effects (font (size 0.7 0.7) (thickness 0.15)) (justify left bottom))
    )
    (fp_text user "1" (at 14.499 1.6) (layer "F.SilkS")
        (effects (font (size 0.7 0.7) (thickness 0.15)) (justify left bottom))
    )
    (fp_text user "2" (at 14.599 39.6) (layer "F.SilkS")
        (effects (font (size 0.7 0.7) (thickness 0.15)) (justify left bottom))
    )
    (fp_text user "100" (at -8.401 39.7) (layer "F.SilkS")
        (effects (font (size 0.7 0.7) (thickness 0.15)) (justify left bottom))
    )
    (fp_text user "2" (at 14.499 5.599) (layer "F.SilkS")
        (effects (font (size 0.7 0.7) (thickness 0.15)) (justify left bottom))
    )
    (fp_text user "99" (at -8.401 35.7) (layer "F.SilkS")
        (effects (font (size 0.7 0.7) (thickness 0.15)) (justify left bottom))
    )
    (fp_text user "License: Apache-2.0" (at -22 44.97) (layer "F.Fab") hide
        (effects (font (size 0.7 0.7) (thickness 0.15)) (justify left bottom))
    )
    (fp_text user "${REFERENCE}" (at -22 42.569) (layer "F.Fab") hide
        (effects (font (size 0.7 0.7) (thickness 0.15)) (justify left bottom))
    )
    (fp_text user "Author: Antmicro" (at -22 43.77) (layer "F.Fab") hide
        (effects (font (size 0.7 0.7) (thickness 0.15)) (justify left bottom))
    )
    (fp_line (start -21.93 37.569) (end -21.93 3.569)
      (stroke (width 0.15) (type solid)) (layer "F.SilkS"))
    (fp_line (start -21.93 37.569) (end -21.93 3.569)
      (stroke (width 0.15) (type solid)) (layer "F.SilkS"))
    (fp_line (start -18.93 0.569) (end 30.07 0.569)
      (stroke (width 0.15) (type solid)) (layer "F.SilkS"))
    (fp_line (start -18.93 0.57) (end 30.07 0.569)
      (stroke (width 0.15) (type solid)) (layer "F.SilkS"))
    (fp_line (start 30.07 40.569) (end -18.93 40.569)
      (stroke (width 0.15) (type solid)) (layer "F.SilkS"))
    (fp_line (start 30.07 40.569) (end -18.93 40.569)
      (stroke (width 0.15) (type solid)) (layer "F.SilkS"))
    (fp_line (start 33.07 3.569) (end 33.07 37.569)
      (stroke (width 0.15) (type solid)) (layer "F.SilkS"))
    (fp_line (start 33.07 3.569) (end 33.07 37.569)
      (stroke (width 0.15) (type solid)) (layer "F.SilkS"))
    (fp_arc (start -21.93 3.57) (mid -21.051854 1.447853) (end -18.93 0.569)
      (stroke (width 0.15) (type solid)) (layer "F.SilkS"))
    (fp_arc (start -21.93 3.57) (mid -21.052 1.448) (end -18.93 0.57)
      (stroke (width 0.15) (type solid)) (layer "F.SilkS"))
    (fp_arc (start -18.93 40.569) (mid -21.052 39.691) (end -21.93 37.569)
      (stroke (width 0.15) (type solid)) (layer "F.SilkS"))
    (fp_arc (start -18.93 40.569) (mid -21.052 39.691) (end -21.93 37.569)
      (stroke (width 0.15) (type solid)) (layer "F.SilkS"))
    (fp_arc (start 30.07 0.569) (mid 32.190998 1.448002) (end 33.07 3.569)
      (stroke (width 0.15) (type solid)) (layer "F.SilkS"))
    (fp_arc (start 30.07 0.569) (mid 32.190998 1.448002) (end 33.07 3.569)
      (stroke (width 0.15) (type solid)) (layer "F.SilkS"))
    (fp_arc (start 33.069 37.569) (mid 32.191354 39.690647) (end 30.07 40.569)
      (stroke (width 0.15) (type solid)) (layer "F.SilkS"))
    (fp_arc (start 33.069 37.569) (mid 32.191354 39.690647) (end 30.07 40.569)
      (stroke (width 0.15) (type solid)) (layer "F.SilkS"))
  )

  (footprint "scalenode-cm4-baseboard-footprints:TP_SMD_0.75mm" (layer "F.Cu")
    (at 95.8 87.2 180)
    (property "Author" "Antmicro")
    (property "License" "Apache-2.0")
    (property "MPN" "")
    (property "Manufacturer" "")
    (property "Sheetfile" "poe.kicad_sch")
    (property "Sheetname" "PoE")
    (property "ki_description" "Test Point 0.75mm")
    (attr exclude_from_pos_files)
    (fp_text reference "TP9" (at 1 0.625 180) (layer "F.SilkS")
        (effects (font (size 0.7 0.7) (thickness 0.15)) (justify left bottom))
    )
    (fp_text value "TP_0.75mm_SMD" (at 0 1.2 180) (layer "F.Fab")
        (effects (font (size 0.7 0.7) (thickness 0.15)) (justify left bottom))
    )
    (fp_text user "License: Apache-2.0" (at -0.4 5.101 180) (layer "F.Fab") hide
        (effects (font (size 0.7 0.7) (thickness 0.15)) (justify left bottom))
    )
    (fp_text user "${REFERENCE}" (at -0.4 2.7 180) (layer "F.Fab") hide
        (effects (font (size 0.7 0.7) (thickness 0.15)) (justify left bottom))
    )
    (fp_text user "Author: Antmicro" (at -0.4 3.901 180) (layer "F.Fab") hide
        (effects (font (size 0.7 0.7) (thickness 0.15)) (justify left bottom))
    )
    (pad "1" smd circle (at 0 0 180) (size 0.75 0.75) (layers "F.Cu" "F.Mask")
      (net 272 "Net-(U3-UVLO_SEL)") (pinfunction "1") (pintype "passive"))
  )

  (footprint "scalenode-cm4-baseboard-footprints:R_0402_1005Metric" (layer "F.Cu")
    (at 92.4 87.1 90)
    (descr "Resistor SMD 0402")
    (tags "resistor SMD 0402")
    (property "Author" "Antmicro")
    (property "DNP" "DNP")
    (property "License" "Apache-2.0")
    (property "MPN" "CR0402-FX-1002GLF")
    (property "Manufacturer" "Bourns")
    (property "Sheetfile" "poe.kicad_sch")
    (property "Sheetname" "PoE")
    (property "Tolerance" "1%")
    (property "Val" "10k")
    (property "dnp" "")
    (property "exclude_from_bom" "")
    (property "ki_description" "10k resistor in 0402 package with 1% tolerance")
    (attr exclude_from_pos_files exclude_from_bom)
    (fp_text reference "R39" (at 0.95 0.4 90) (layer "F.SilkS")
        (effects (font (size 0.7 0.7) (thickness 0.15)) (justify left bottom))
    )
    (fp_text value "R_10k_0402" (at 0 1.4 90) (layer "F.Fab")
        (effects (font (size 0.7 0.7) (thickness 0.15)) (justify left bottom))
    )
    (fp_text user "License: Apache-2.0" (at -0.95 5.169 90) (layer "F.Fab") hide
        (effects (font (size 0.7 0.7) (thickness 0.15)) (justify left bottom))
    )
    (fp_text user "${REFERENCE}" (at -0.95 3.168 90) (layer "F.Fab") hide
        (effects (font (size 0.7 0.7) (thickness 0.15)) (justify left bottom))
    )
    (fp_text user "Author: Antmicro" (at -0.95 4.169 90) (layer "F.Fab") hide
        (effects (font (size 0.7 0.7) (thickness 0.15)) (justify left bottom))
    )
    (fp_rect (start -0.95 -0.48) (end 0.95 0.48)
      (stroke (width 0.05) (type solid)) (fill none) (layer "F.CrtYd"))
    (fp_rect (start -0.5 -0.25) (end 0.5 0.25)
      (stroke (width 0.15) (type solid)) (fill none) (layer "F.Fab"))
    (pad "1" smd roundrect (at -0.485 0 90) (size 0.59 0.64) (layers "F.Cu" "F.Paste" "F.Mask") (roundrect_rratio 0.25)
      (net 261 "Net-(U3-TPH)") (pintype "passive"))
    (pad "2" smd roundrect (at 0.485 0 90) (size 0.59 0.64) (layers "F.Cu" "F.Paste" "F.Mask") (roundrect_rratio 0.25)
      (net 6 "/PoE/VDD_POE_IN") (pintype "passive"))
  )

  (footprint "scalenode-cm4-baseboard-footprints:TP_SMD_0.75mm" (layer "F.Cu")
    (at 96.3 89.2)
    (property "Author" "Antmicro")
    (property "License" "Apache-2.0")
    (property "MPN" "")
    (property "Manufacturer" "")
    (property "Sheetfile" "poe.kicad_sch")
    (property "Sheetname" "PoE")
    (property "ki_description" "Test Point 0.75mm")
    (attr exclude_from_pos_files)
    (fp_text reference "TP1" (at -0.8 -0.6) (layer "F.SilkS")
        (effects (font (size 0.7 0.7) (thickness 0.15)) (justify left bottom))
    )
    (fp_text value "TP_0.75mm_SMD" (at 0 1.2) (layer "F.Fab")
        (effects (font (size 0.7 0.7) (thickness 0.15)) (justify left bottom))
    )
    (fp_text user "Author: Antmicro" (at -0.4 3.901) (layer "F.Fab") hide
        (effects (font (size 0.7 0.7) (thickness 0.15)) (justify left bottom))
    )
    (fp_text user "${REFERENCE}" (at -0.4 2.7) (layer "F.Fab") hide
        (effects (font (size 0.7 0.7) (thickness 0.15)) (justify left bottom))
    )
    (fp_text user "License: Apache-2.0" (at -0.4 5.101) (layer "F.Fab") hide
        (effects (font (size 0.7 0.7) (thickness 0.15)) (justify left bottom))
    )
    (pad "1" smd circle (at 0 0) (size 0.75 0.75) (layers "F.Cu" "F.Mask")
      (net 269 "Net-(U3-VC_IN)") (pinfunction "1") (pintype "passive"))
  )

  (footprint "scalenode-cm4-baseboard-footprints:CONV_PDQE30-Q48-S5-D" locked (layer "F.Cu")
    (at 117.09 73.05)
    (property "Author" "Antmicro")
    (property "License" "Apache-2.0")
    (property "MPN" "PDQE30-Q48-S5-D")
    (property "Manufacturer" "CUI Inc")
    (property "Sheetfile" "poe.kicad_sch")
    (property "Sheetname" "PoE")
    (property "ki_description" "DC-DC CONVERTER, 48VDC input, 5VDC nom isolated output w/ trim option, 30W, 270kHz PWM mode")
    (property "ki_keywords" "dc converter step down 5v 48v isolated 30W poe")
    (attr through_hole)
    (fp_text reference "U7" (at -2.74 -3.81) (layer "F.SilkS")
        (effects (font (size 0.7 0.7) (thickness 0.15)) (justify left bottom))
    )
    (fp_text value "PDQE30-Q48-S5-D" (at 10.32 24.312) (layer "F.Fab")
        (effects (font (size 0.7 0.7) (thickness 0.15)) (justify left bottom))
    )
    (fp_text user "${REFERENCE}" (at -3.912 28.711) (layer "F.Fab") hide
        (effects (font (size 0.7 0.7) (thickness 0.15)) (justify left bottom))
    )
    (fp_text user "License: Apache-2.0" (at -3.912 27.51) (layer "F.Fab") hide
        (effects (font (size 0.7 0.7) (thickness 0.15)) (justify left bottom))
    )
    (fp_text user "Author: Antmicro" (at -3.912 26.312) (layer "F.Fab") hide
        (effects (font (size 0.7 0.7) (thickness 0.15)) (justify left bottom))
    )
    (fp_line (start -2.54 -2.54) (end 22.859 -2.54)
      (stroke (width 0.15) (type solid)) (layer "F.SilkS"))
    (fp_line (start -2.54 22.859) (end -2.54 -2.54)
      (stroke (width 0.15) (type solid)) (layer "F.SilkS"))
    (fp_line (start 22.859 -2.54) (end 22.859 22.859)
      (stroke (width 0.15) (type solid)) (layer "F.SilkS"))
    (fp_line (start 22.859 22.859) (end -2.54 22.859)
      (stroke (width 0.15) (type solid)) (layer "F.SilkS"))
    (fp_circle (center -2.921 0) (end -2.82 0)
      (stroke (width 0.15) (type solid)) (fill none) (layer "F.SilkS"))
    (fp_circle (center 0 -3.84) (end 0.05 -3.84)
      (stroke (width 0.15) (type solid)) (fill solid) (layer "F.SilkS"))
    (fp_circle (center 0 -3.84) (end 0.05 -3.84)
      (stroke (width 0.15) (type solid)) (fill solid) (layer "F.SilkS"))
    (fp_rect (start -2.667 -2.667) (end 22.987 22.987)
      (stroke (width 0.05) (type solid)) (fill none) (layer "F.CrtYd"))
    (fp_line (start -2.54 -2.54) (end 22.859 -2.54)
      (stroke (width 0.15) (type solid)) (layer "F.Fab"))
    (fp_line (start -2.54 22.859) (end -2.54 -2.54)
      (stroke (width 0.15) (type solid)) (layer "F.Fab"))
    (fp_line (start 22.859 -2.54) (end 22.859 22.859)
      (stroke (width 0.15) (type solid)) (layer "F.Fab"))
    (fp_line (start 22.859 22.859) (end -2.54 22.859)
      (stroke (width 0.15) (type solid)) (layer "F.Fab"))
    (fp_circle (center -2.921 0) (end -2.82 0)
      (stroke (width 0.15) (type solid)) (fill none) (layer "F.Fab"))
    (pad "1" thru_hole rect locked (at 0 0) (size 2.25 2.25) (drill 1.5) (layers "*.Cu" "*.Mask")
      (net 34 "/PoE/POE_ACTIVE") (pinfunction "CTRL") (pintype "input"))
    (pad "2" thru_hole circle locked (at 0 7.618) (size 2.25 2.25) (drill 1.5) (layers "*.Cu" "*.Mask")
      (net 4 "GNDD") (pinfunction "GND") (pintype "power_in"))
    (pad "3" thru_hole circle locked (at 0 12.698) (size 2.25 2.25) (drill 1.5) (layers "*.Cu" "*.Mask")
      (net 6 "/PoE/VDD_POE_IN") (pinfunction "V_{IN}") (pintype "power_in"))
    (pad "4" thru_hole circle locked (at 20.318 20.318) (size 2.25 2.25) (drill 1.5) (layers "*.Cu" "*.Mask")
      (net 13 "/PoE/VO5V") (pinfunction "V_{O}") (pintype "power_out"))
    (pad "5" thru_hole circle locked (at 20.318 10.159) (size 2.25 2.25) (drill 1.5) (layers "*.Cu" "*.Mask")
      (net 277 "unconnected-(U7-TRIM-Pad5)") (pinfunction "TRIM") (pintype "passive+no_connect"))
    (pad "6" thru_hole circle locked (at 20.318 0) (size 2.25 2.25) (drill 1.5) (layers "*.Cu" "*.Mask")
      (net 11 "GND") (pinfunction "0V") (pintype "power_out"))
  )

  (footprint "scalenode-cm4-baseboard-footprints:R_0402_1005Metric" (layer "F.Cu")
    (at 86.885 92.2)
    (descr "Resistor SMD 0402")
    (tags "resistor SMD 0402")
    (property "Author" "Antmicro")
    (property "DNP" "DNP")
    (property "License" "Apache-2.0")
    (property "MPN" "CR0402-FX-63R4GLF")
    (property "Manufacturer" "Bourns")
    (property "Sheetfile" "poe.kicad_sch")
    (property "Sheetname" "PoE")
    (property "Tolerance" "1%")
    (property "Val" "63R4")
    (property "dnp" "")
    (property "exclude_from_bom" "")
    (property "ki_description" "63R4 resistor in 0402 package with 1% tolerance")
    (attr exclude_from_pos_files exclude_from_bom)
    (fp_text reference "R20" (at -1.085 1.375) (layer "F.SilkS")
        (effects (font (size 0.7 0.7) (thickness 0.15)) (justify left bottom))
    )
    (fp_text value "R_63R4_0402" (at 0 1.4) (layer "F.Fab")
        (effects (font (size 0.7 0.7) (thickness 0.15)) (justify left bottom))
    )
    (fp_text user "Author: Antmicro" (at -0.95 4.169) (layer "F.Fab") hide
        (effects (font (size 0.7 0.7) (thickness 0.15)) (justify left bottom))
    )
    (fp_text user "${REFERENCE}" (at -0.95 3.168) (layer "F.Fab") hide
        (effects (font (size 0.7 0.7) (thickness 0.15)) (justify left bottom))
    )
    (fp_text user "License: Apache-2.0" (at -0.95 5.169) (layer "F.Fab") hide
        (effects (font (size 0.7 0.7) (thickness 0.15)) (justify left bottom))
    )
    (fp_rect (start -0.95 -0.48) (end 0.95 0.48)
      (stroke (width 0.05) (type solid)) (fill none) (layer "F.CrtYd"))
    (fp_rect (start -0.5 -0.25) (end 0.5 0.25)
      (stroke (width 0.15) (type solid)) (fill none) (layer "F.Fab"))
    (pad "1" smd roundrect (at -0.485 0) (size 0.59 0.64) (layers "F.Cu" "F.Paste" "F.Mask") (roundrect_rratio 0.25)
      (net 254 "Net-(U3-CLSA)") (pintype "passive"))
    (pad "2" smd roundrect (at 0.485 0) (size 0.59 0.64) (layers "F.Cu" "F.Paste" "F.Mask") (roundrect_rratio 0.25)
      (net 5 "VSS") (pintype "passive"))
  )

  (footprint "scalenode-cm4-baseboard-footprints:R_0603_1608Metric" (layer "F.Cu")
    (at 79.15 77.94)
    (descr "Resistor SMD 0603")
    (tags "resistor SMD 0603")
    (property "Author" "Antmicro")
    (property "License" "Apache-2.0")
    (property "MPN" "CR0603-FX-2700ELF")
    (property "Manufacturer" "Bourns")
    (property "Sheetfile" "nvme-ssd.kicad_sch")
    (property "Sheetname" "NVMe SSD")
    (property "Tolerance" "1%")
    (property "Val" "270R")
    (property "ki_description" "270R resistor in 0603 package with 1% tolerance")
    (attr smd)
    (fp_text reference "R2" (at -1.39 1.55) (layer "F.SilkS")
        (effects (font (size 0.7 0.7) (thickness 0.15)) (justify left bottom))
    )
    (fp_text value "R_270R_0603" (at 0 1.6) (layer "F.Fab")
        (effects (font (size 0.7 0.7) (thickness 0.15)) (justify left bottom))
    )
    (fp_text user "${REFERENCE}" (at -1.25 3.898) (layer "F.Fab") hide
        (effects (font (size 0.7 0.7) (thickness 0.15)) (justify left bottom))
    )
    (fp_text user "Author: Antmicro" (at -1.25 4.9) (layer "F.Fab") hide
        (effects (font (size 0.7 0.7) (thickness 0.15)) (justify left bottom))
    )
    (fp_text user "License: Apache-2.0" (at -1.25 5.9) (layer "F.Fab") hide
        (effects (font (size 0.7 0.7) (thickness 0.15)) (justify left bottom))
    )
    (fp_line (start -0.3 -0.3) (end 0.3 -0.3)
      (stroke (width 0.15) (type solid)) (layer "F.SilkS"))
    (fp_line (start -0.3 0.3) (end 0.3 0.3)
      (stroke (width 0.15) (type solid)) (layer "F.SilkS"))
    (fp_rect (start -1.25 -0.7) (end 1.25 0.7)
      (stroke (width 0.05) (type solid)) (fill none) (layer "F.CrtYd"))
    (fp_rect (start -0.8 -0.4) (end 0.8 0.4)
      (stroke (width 0.15) (type solid)) (fill none) (layer "F.Fab"))
    (pad "1" smd roundrect (at -0.7 0) (size 0.6 0.8) (layers "F.Cu" "F.Paste" "F.Mask") (roundrect_rratio 0.2)
      (net 188 "Net-(D1-Pad1)") (pintype "passive"))
    (pad "2" smd roundrect (at 0.7 0) (size 0.6 0.8) (layers "F.Cu" "F.Paste" "F.Mask") (roundrect_rratio 0.2)
      (net 170 "3V3_SSD") (pintype "passive"))
  )

  (footprint "scalenode-cm4-baseboard-footprints:TP_SMD_1mm" (layer "F.Cu")
    (at 98.916 89.402)
    (property "Author" "Antmicro")
    (property "License" "Apache-2.0")
    (property "MPN" "")
    (property "Manufacturer" "")
    (property "Sheetfile" "poe.kicad_sch")
    (property "Sheetname" "PoE")
    (property "ki_description" "Test Point 1mm")
    (attr exclude_from_pos_files)
    (fp_text reference "TP3" (at -0.866 -0.802) (layer "F.SilkS")
        (effects (font (size 0.7 0.7) (thickness 0.15)) (justify left bottom))
    )
    (fp_text value "TP_1mm_SMD" (at 0 1.4) (layer "F.Fab")
        (effects (font (size 0.7 0.7) (thickness 0.15)) (justify left bottom))
    )
    (fp_text user "Author: Antmicro" (at -0.5 4) (layer "F.Fab") hide
        (effects (font (size 0.7 0.7) (thickness 0.15)) (justify left bottom))
    )
    (fp_text user "${REFERENCE}" (at -0.5 2.8) (layer "F.Fab") hide
        (effects (font (size 0.7 0.7) (thickness 0.15)) (justify left bottom))
    )
    (fp_text user "License: Apache-2.0" (at -0.5 5.2) (layer "F.Fab") hide
        (effects (font (size 0.7 0.7) (thickness 0.15)) (justify left bottom))
    )
    (pad "1" smd circle (at 0 0) (size 1 1) (layers "F.Cu" "F.Mask")
      (net 6 "/PoE/VDD_POE_IN") (pinfunction "1") (pintype "passive"))
  )

  (footprint "scalenode-cm4-baseboard-footprints:TP_SMD_0.75mm" (layer "F.Cu")
    (at 96.2 90.7)
    (property "Author" "Antmicro")
    (property "License" "Apache-2.0")
    (property "MPN" "")
    (property "Manufacturer" "")
    (property "Sheetfile" "poe.kicad_sch")
    (property "Sheetname" "PoE")
    (property "ki_description" "Test Point 0.75mm")
    (attr exclude_from_pos_files)
    (fp_text reference "TP8" (at -0.925 1.375) (layer "F.SilkS")
        (effects (font (size 0.7 0.7) (thickness 0.15)) (justify left bottom))
    )
    (fp_text value "TP_0.75mm_SMD" (at 0 1.2) (layer "F.Fab")
        (effects (font (size 0.7 0.7) (thickness 0.15)) (justify left bottom))
    )
    (fp_text user "${REFERENCE}" (at -0.4 2.7) (layer "F.Fab") hide
        (effects (font (size 0.7 0.7) (thickness 0.15)) (justify left bottom))
    )
    (fp_text user "License: Apache-2.0" (at -0.4 5.101) (layer "F.Fab") hide
        (effects (font (size 0.7 0.7) (thickness 0.15)) (justify left bottom))
    )
    (fp_text user "Author: Antmicro" (at -0.4 3.901) (layer "F.Fab") hide
        (effects (font (size 0.7 0.7) (thickness 0.15)) (justify left bottom))
    )
    (pad "1" smd circle (at 0 0) (size 0.75 0.75) (layers "F.Cu" "F.Mask")
      (net 271 "Net-(U3-VC_OUT)") (pinfunction "1") (pintype "passive"))
  )

  (footprint "scalenode-cm4-baseboard-footprints:R_0402_1005Metric" (layer "F.Cu")
    (at 91 87.1 90)
    (descr "Resistor SMD 0402")
    (tags "resistor SMD 0402")
    (property "Author" "Antmicro")
    (property "DNP" "DNP")
    (property "License" "Apache-2.0")
    (property "MPN" "CR0402-FX-1002GLF")
    (property "Manufacturer" "Bourns")
    (property "Sheetfile" "poe.kicad_sch")
    (property "Sheetname" "PoE")
    (property "Tolerance" "1%")
    (property "Val" "10k")
    (property "dnp" "")
    (property "exclude_from_bom" "")
    (property "ki_description" "10k resistor in 0402 package with 1% tolerance")
    (attr exclude_from_pos_files exclude_from_bom)
    (fp_text reference "R41" (at 1 0.325 90) (layer "F.SilkS")
        (effects (font (size 0.7 0.7) (thickness 0.15)) (justify left bottom))
    )
    (fp_text value "R_10k_0402" (at 0 1.4 90) (layer "F.Fab")
        (effects (font (size 0.7 0.7) (thickness 0.15)) (justify left bottom))
    )
    (fp_text user "Author: Antmicro" (at -0.95 4.169 90) (layer "F.Fab") hide
        (effects (font (size 0.7 0.7) (thickness 0.15)) (justify left bottom))
    )
    (fp_text user "${REFERENCE}" (at -0.95 3.168 90) (layer "F.Fab") hide
        (effects (font (size 0.7 0.7) (thickness 0.15)) (justify left bottom))
    )
    (fp_text user "License: Apache-2.0" (at -0.95 5.169 90) (layer "F.Fab") hide
        (effects (font (size 0.7 0.7) (thickness 0.15)) (justify left bottom))
    )
    (fp_rect (start -0.95 -0.48) (end 0.95 0.48)
      (stroke (width 0.05) (type solid)) (fill none) (layer "F.CrtYd"))
    (fp_rect (start -0.5 -0.25) (end 0.5 0.25)
      (stroke (width 0.15) (type solid)) (fill none) (layer "F.Fab"))
    (pad "1" smd roundrect (at -0.485 0 90) (size 0.59 0.64) (layers "F.Cu" "F.Paste" "F.Mask") (roundrect_rratio 0.25)
      (net 263 "Net-(U3-~{BT})") (pintype "passive"))
    (pad "2" smd roundrect (at 0.485 0 90) (size 0.59 0.64) (layers "F.Cu" "F.Paste" "F.Mask") (roundrect_rratio 0.25)
      (net 6 "/PoE/VDD_POE_IN") (pintype "passive"))
  )

  (footprint "scalenode-cm4-baseboard-footprints:R_0402_1005Metric" (layer "F.Cu")
    (at 85.9 90.85)
    (descr "Resistor SMD 0402")
    (tags "resistor SMD 0402")
    (property "Author" "Antmicro")
    (property "DNP" "DNP")
    (property "License" "Apache-2.0")
    (property "MPN" "CR0402-FX-2492GLF")
    (property "Manufacturer" "Bourns")
    (property "Sheetfile" "poe.kicad_sch")
    (property "Sheetname" "PoE")
    (property "Tolerance" "1%")
    (property "Val" "24k9")
    (property "dnp" "")
    (property "exclude_from_bom" "")
    (property "ki_description" "24k9 resistor in 0402 package with 1% tolerance")
    (attr exclude_from_pos_files exclude_from_bom)
    (fp_text reference "R36" (at -1.05 -0.65) (layer "F.SilkS")
        (effects (font (size 0.7 0.7) (thickness 0.15)) (justify left bottom))
    )
    (fp_text value "R_24k9_0402" (at 0 1.4) (layer "F.Fab")
        (effects (font (size 0.7 0.7) (thickness 0.15)) (justify left bottom))
    )
    (fp_text user "License: Apache-2.0" (at -0.95 5.169) (layer "F.Fab") hide
        (effects (font (size 0.7 0.7) (thickness 0.15)) (justify left bottom))
    )
    (fp_text user "Author: Antmicro" (at -0.95 4.169) (layer "F.Fab") hide
        (effects (font (size 0.7 0.7) (thickness 0.15)) (justify left bottom))
    )
    (fp_text user "${REFERENCE}" (at -0.95 3.168) (layer "F.Fab") hide
        (effects (font (size 0.7 0.7) (thickness 0.15)) (justify left bottom))
    )
    (fp_rect (start -0.95 -0.48) (end 0.95 0.48)
      (stroke (width 0.05) (type solid)) (fill none) (layer "F.CrtYd"))
    (fp_rect (start -0.5 -0.25) (end 0.5 0.25)
      (stroke (width 0.15) (type solid)) (fill none) (layer "F.Fab"))
    (pad "1" smd roundrect (at -0.485 0) (size 0.59 0.64) (layers "F.Cu" "F.Paste" "F.Mask") (roundrect_rratio 0.25)
      (net 6 "/PoE/VDD_POE_IN") (pintype "passive"))
    (pad "2" smd roundrect (at 0.485 0) (size 0.59 0.64) (layers "F.Cu" "F.Paste" "F.Mask") (roundrect_rratio 0.25)
      (net 258 "Net-(U3-DEN)") (pintype "passive"))
  )

  (footprint "scalenode-cm4-baseboard-footprints:Conn_JST_XH_1x2_B2B-XH-A-LF-SN" (layer "F.Cu")
    (at 130.7 60.2 180)
    (descr "http://www.jst-mfg.com/product/pdf/eng/eXH.pdf")
    (property "Author" "Antmicro")
    (property "License" "Apache-2.0")
    (property "MPN" "B2B-XH-A(LF)(SN)")
    (property "Manufacturer" "JST Automotive Connectors")
    (property "Sheetfile" "poe.kicad_sch")
    (property "Sheetname" "PoE")
    (property "ki_description" "Rectangular connector, header")
    (property "ki_keywords" "CONNECTOR, THT")
    (attr through_hole)
    (fp_text reference "J1" (at 1.8 -4 180) (layer "F.SilkS")
        (effects (font (size 0.7 0.7) (thickness 0.15)) (justify left bottom))
    )
    (fp_text value "JST_XH_1x2_B2B-XH-A-LF-SN" (at -0.225 -0.4 180) (layer "F.Fab")
        (effects (font (size 0.7 0.7) (thickness 0.15)) (justify left bottom))
    )
    (fp_text user "License: Apache-2.0" (at -2.702 8.81 180) (layer "F.Fab") hide
        (effects (font (size 0.7 0.7) (thickness 0.15)) (justify left bottom))
    )
    (fp_text user "${REFERENCE}" (at -2.702 6.41 180) (layer "F.Fab") hide
        (effects (font (size 0.7 0.7) (thickness 0.15)) (justify left bottom))
    )
    (fp_text user "Author: Antmicro" (at -2.702 7.61 180) (layer "F.Fab") hide
        (effects (font (size 0.7 0.7) (thickness 0.15)) (justify left bottom))
    )
    (fp_line (start -2.601 -3) (end -2.601 -2.5)
      (stroke (width 0.15) (type solid)) (layer "F.SilkS"))
    (fp_line (start -2.601 -3) (end -2.101 -3)
      (stroke (width 0.15) (type solid)) (layer "F.SilkS"))
    (fp_line (start -2.601 2.999) (end -2.601 2.499)
      (stroke (width 0.15) (type solid)) (layer "F.SilkS"))
    (fp_line (start -2.601 2.999) (end -2.101 2.999)
      (stroke (width 0.15) (type solid)) (layer "F.SilkS"))
    (fp_line (start 5.08 -3) (end 4.58 -3)
      (stroke (width 0.15) (type solid)) (layer "F.SilkS"))
    (fp_line (start 5.08 -3) (end 5.08 -2.5)
      (stroke (width 0.15) (type solid)) (layer "F.SilkS"))
    (fp_line (start 5.08 2.999) (end 4.58 2.999)
      (stroke (width 0.15) (type solid)) (layer "F.SilkS"))
    (fp_line (start 5.08 2.999) (end 5.08 2.499)
      (stroke (width 0.15) (type solid)) (layer "F.SilkS"))
    (fp_circle (center -3.252 0) (end -3.202 0)
      (stroke (width 0.15) (type solid)) (fill solid) (layer "F.SilkS"))
    (fp_line (start -2.71 -3.13) (end -2.71 3.12)
      (stroke (width 0.05) (type solid)) (layer "F.CrtYd"))
    (fp_line (start 5.1816 -3.13) (end -2.71 -3.13)
      (stroke (width 0.05) (type solid)) (layer "F.CrtYd"))
    (fp_line (start 5.1816 3.12) (end -2.71 3.12)
      (stroke (width 0.05) (type solid)) (layer "F.CrtYd"))
    (fp_line (start 5.1816 3.12) (end 5.1816 -3.13)
      (stroke (width 0.05) (type solid)) (layer "F.CrtYd"))
    (pad "1" thru_hole circle (at 0 0 180) (size 2.1 2.1) (drill 1.1) (layers "*.Cu" "*.Mask")
      (net 12 "VCC5V0") (pintype "passive"))
    (pad "2" thru_hole circle (at 2.499 0 180) (size 2.1 2.1) (drill 1.1) (layers "*.Cu" "*.Mask")
      (net 11 "GND") (pintype "passive"))
  )

  (footprint "scalenode-cm4-baseboard-footprints:LED_0603_1608Metric_G" (layer "F.Cu")
    (at 98.9 90.85)
    (descr "LED SMD 0603 Green")
    (tags "LED SMD 0603 Green")
    (property "Author" "Antmicro")
    (property "License" "Apache-2.0")
    (property "MPN" "KP-1608CGCK")
    (property "Manufacturer" "Kingbright")
    (property "Sheetfile" "poe.kicad_sch")
    (property "Sheetname" "PoE")
    (attr smd)
    (fp_text reference "D7" (at 1.35 0.425) (layer "F.SilkS")
        (effects (font (size 0.7 0.7) (thickness 0.15)) (justify left bottom))
    )
    (fp_text value "LED_G_0603_KP-1608CGCK" (at 0 1.6) (layer "F.Fab")
        (effects (font (size 0.7 0.7) (thickness 0.15)) (justify left bottom))
    )
    (fp_text user "Author: Antmicro" (at -1.31 4.769) (layer "F.Fab") hide
        (effects (font (size 0.7 0.7) (thickness 0.15)) (justify left bottom))
    )
    (fp_text user "${REFERENCE}" (at -1.31 3.769) (layer "F.Fab") hide
        (effects (font (size 0.7 0.7) (thickness 0.15)) (justify left bottom))
    )
    (fp_text user "License: Apache-2.0" (at -1.31 5.769) (layer "F.Fab") hide
        (effects (font (size 0.7 0.7) (thickness 0.15)) (justify left bottom))
    )
    (fp_line (start -0.27 -0.3) (end 0.27 -0.3)
      (stroke (width 0.15) (type solid)) (layer "F.SilkS"))
    (fp_line (start -0.27 0.3) (end 0.27 0.3)
      (stroke (width 0.15) (type solid)) (layer "F.SilkS"))
    (fp_line (start 1.25 0.5) (end 1.25 -0.498)
      (stroke (width 0.15) (type solid)) (layer "F.SilkS"))
    (fp_rect (start 1.31 0.7) (end -1.31 -0.7)
      (stroke (width 0.05) (type solid)) (fill none) (layer "F.CrtYd"))
    (fp_line (start -0.599 0) (end -0.201 0)
      (stroke (width 0.15) (type solid)) (layer "F.Fab"))
    (fp_line (start -0.201 -0.2) (end -0.201 0)
      (stroke (width 0.15) (type solid)) (layer "F.Fab"))
    (fp_line (start -0.201 0) (end -0.201 0.202)
      (stroke (width 0.15) (type solid)) (layer "F.Fab"))
    (fp_line (start -0.201 0.202) (end 0.101 0)
      (stroke (width 0.15) (type solid)) (layer "F.Fab"))
    (fp_line (start 0.101 0) (end -0.201 -0.2)
      (stroke (width 0.15) (type solid)) (layer "F.Fab"))
    (fp_line (start 0.199 -0.2) (end 0.199 -0.1)
      (stroke (width 0.15) (type solid)) (layer "F.Fab"))
    (fp_line (start 0.199 0) (end 0.597 0)
      (stroke (width 0.15) (type solid)) (layer "F.Fab"))
    (fp_line (start 0.199 0.202) (end 0.199 -0.1)
      (stroke (width 0.15) (type solid)) (layer "F.Fab"))
    (fp_rect (start -0.848 -0.4) (end 0.85 0.402)
      (stroke (width 0.15) (type solid)) (fill none) (layer "F.Fab"))
    (pad "1" smd rect (at -0.75 0 180) (size 0.8 0.8) (layers "F.Cu" "F.Paste" "F.Mask")
      (net 21 "Net-(D7-Pad1)") (pinfunction "1") (pintype "passive"))
    (pad "2" smd rect (at 0.75 0 180) (size 0.8 0.8) (layers "F.Cu" "F.Paste" "F.Mask")
      (net 4 "GNDD") (pinfunction "2") (pintype "passive"))
  )

  (footprint "scalenode-cm4-baseboard-footprints:R_0402_1005Metric" (layer "F.Cu")
    (at 93.3 95.1 180)
    (descr "Resistor SMD 0402")
    (tags "resistor SMD 0402")
    (property "Author" "Antmicro")
    (property "DNP" "DNP")
    (property "License" "Apache-2.0")
    (property "MPN" "CR0402-FX-1301GLF")
    (property "Manufacturer" "Bourns")
    (property "Sheetfile" "poe.kicad_sch")
    (property "Sheetname" "PoE")
    (property "Tolerance" "1%")
    (property "Val" "1k3")
    (property "dnp" "")
    (property "exclude_from_bom" "")
    (property "ki_description" "1k3 resistor in 0402 package with 1% tolerance")
    (attr exclude_from_pos_files exclude_from_bom)
    (fp_text reference "R37" (at 1.05 -1.35 180) (layer "F.SilkS")
        (effects (font (size 0.7 0.7) (thickness 0.15)) (justify left bottom))
    )
    (fp_text value "R_1k3_0402" (at 0 1.4 180) (layer "F.Fab")
        (effects (font (size 0.7 0.7) (thickness 0.15)) (justify left bottom))
    )
    (fp_text user "${REFERENCE}" (at -0.95 3.168 180) (layer "F.Fab") hide
        (effects (font (size 0.7 0.7) (thickness 0.15)) (justify left bottom))
    )
    (fp_text user "License: Apache-2.0" (at -0.95 5.169 180) (layer "F.Fab") hide
        (effects (font (size 0.7 0.7) (thickness 0.15)) (justify left bottom))
    )
    (fp_text user "Author: Antmicro" (at -0.95 4.169 180) (layer "F.Fab") hide
        (effects (font (size 0.7 0.7) (thickness 0.15)) (justify left bottom))
    )
    (fp_rect (start -0.95 -0.48) (end 0.95 0.48)
      (stroke (width 0.05) (type solid)) (fill none) (layer "F.CrtYd"))
    (fp_rect (start -0.5 -0.25) (end 0.5 0.25)
      (stroke (width 0.15) (type solid)) (fill none) (layer "F.Fab"))
    (pad "1" smd roundrect (at -0.485 0 180) (size 0.59 0.64) (layers "F.Cu" "F.Paste" "F.Mask") (roundrect_rratio 0.25)
      (net 5 "VSS") (pintype "passive"))
    (pad "2" smd roundrect (at 0.485 0 180) (size 0.59 0.64) (layers "F.Cu" "F.Paste" "F.Mask") (roundrect_rratio 0.25)
      (net 259 "Net-(U3-AMPS_CTL)") (pintype "passive"))
  )

  (footprint "scalenode-cm4-baseboard-footprints:C_2220_5650Metric" (layer "F.Cu")
    (at 110.4 85.96)
    (descr "Capacitor SMD 2220")
    (tags "capacitor SMD 2220")
    (property "Author" "Antmicro")
    (property "Dielectric" "X7S")
    (property "License" "Apache-2.0")
    (property "MPN" "C5750X7S2A226M280KB")
    (property "Manufacturer" "TDK")
    (property "Sheetfile" "poe.kicad_sch")
    (property "Sheetname" "PoE")
    (property "Val" "22u")
    (property "Voltage" "100V")
    (property "ki_description" " ")
    (attr smd)
    (fp_text reference "C32" (at -1.15 -3.2) (layer "F.SilkS")
        (effects (font (size 0.7 0.7) (thickness 0.15)) (justify left bottom))
    )
    (fp_text value "C_22u_100V_2220" (at 0 3.9) (layer "F.Fab")
        (effects (font (size 0.7 0.7) (thickness 0.15)) (justify left bottom))
    )
    (fp_text user "License: Apache-2.0" (at -3.7 6.9) (layer "F.Fab") hide
        (effects (font (size 0.7 0.7) (thickness 0.15)) (justify left bottom))
    )
    (fp_text user "Author: Antmicro" (at -3.7 7.9) (layer "F.Fab") hide
        (effects (font (size 0.7 0.7) (thickness 0.15)) (justify left bottom))
    )
    (fp_text user "${REFERENCE}" (at -3.7 5.9) (layer "F.Fab") hide
        (effects (font (size 0.7 0.7) (thickness 0.15)) (justify left bottom))
    )
    (fp_line (start -1.415 -2.61) (end 1.415 -2.61)
      (stroke (width 0.15) (type solid)) (layer "F.SilkS"))
    (fp_line (start -1.415 2.61) (end 1.415 2.61)
      (stroke (width 0.15) (type solid)) (layer "F.SilkS"))
    (fp_rect (start -3.7 -2.95) (end 3.7 2.95)
      (stroke (width 0.05) (type solid)) (fill none) (layer "F.CrtYd"))
    (fp_rect (start -2.85 -2.5) (end 2.85 2.5)
      (stroke (width 0.15) (type solid)) (fill none) (layer "F.Fab"))
    (pad "1" smd roundrect (at -2.55 0) (size 1.8 5.4) (layers "F.Cu" "F.Paste" "F.Mask") (roundrect_rratio 0.138889)
      (net 4 "GNDD") (pintype "passive"))
    (pad "2" smd roundrect (at 2.55 0) (size 1.8 5.4) (layers "F.Cu" "F.Paste" "F.Mask") (roundrect_rratio 0.138889)
      (net 6 "/PoE/VDD_POE_IN") (pintype "passive"))
  )

  (footprint "scalenode-cm4-baseboard-footprints:R_0603_1608Metric" (layer "F.Cu")
    (at 98.925 94.375 180)
    (descr "Resistor SMD 0603")
    (tags "resistor SMD 0603")
    (property "Author" "Antmicro")
    (property "License" "Apache-2.0")
    (property "MPN" "CR0603-FX-1502ELF")
    (property "Manufacturer" "Bourns")
    (property "Sheetfile" "poe.kicad_sch")
    (property "Sheetname" "PoE")
    (property "Tolerance" "1%")
    (property "Val" "15k")
    (property "ki_description" "15k resistor in 0603 package with 1% tolerance")
    (attr smd)
    (fp_text reference "R34" (at -1.15 -0.475 180) (layer "F.SilkS")
        (effects (font (size 0.7 0.7) (thickness 0.15)) (justify left bottom))
    )
    (fp_text value "R_15k_0603" (at 0 1.6 180) (layer "F.Fab")
        (effects (font (size 0.7 0.7) (thickness 0.15)) (justify left bottom))
    )
    (fp_text user "${REFERENCE}" (at -1.25 3.898 180) (layer "F.Fab") hide
        (effects (font (size 0.7 0.7) (thickness 0.15)) (justify left bottom))
    )
    (fp_text user "License: Apache-2.0" (at -1.25 5.9 180) (layer "F.Fab") hide
        (effects (font (size 0.7 0.7) (thickness 0.15)) (justify left bottom))
    )
    (fp_text user "Author: Antmicro" (at -1.25 4.9 180) (layer "F.Fab") hide
        (effects (font (size 0.7 0.7) (thickness 0.15)) (justify left bottom))
    )
    (fp_line (start -0.3 -0.3) (end 0.3 -0.3)
      (stroke (width 0.15) (type solid)) (layer "F.SilkS"))
    (fp_line (start -0.3 0.3) (end 0.3 0.3)
      (stroke (width 0.15) (type solid)) (layer "F.SilkS"))
    (fp_rect (start -1.25 -0.7) (end 1.25 0.7)
      (stroke (width 0.05) (type solid)) (fill none) (layer "F.CrtYd"))
    (fp_rect (start -0.8 -0.4) (end 0.8 0.4)
      (stroke (width 0.15) (type solid)) (fill none) (layer "F.Fab"))
    (pad "1" smd roundrect (at -0.7 0 180) (size 0.6 0.8) (layers "F.Cu" "F.Paste" "F.Mask") (roundrect_rratio 0.2)
      (net 4 "GNDD") (pintype "passive"))
    (pad "2" smd roundrect (at 0.7 0 180) (size 0.6 0.8) (layers "F.Cu" "F.Paste" "F.Mask") (roundrect_rratio 0.2)
      (net 6 "/PoE/VDD_POE_IN") (pintype "passive"))
  )

  (footprint "scalenode-cm4-baseboard-footprints:R_0402_1005Metric" (layer "B.Cu")
    (at 99.452 86.375 90)
    (descr "Resistor SMD 0402")
    (tags "resistor SMD 0402")
    (property "Author" "Antmicro")
    (property "License" "Apache-2.0")
    (property "MPN" "CR0402-FX-1002GLF")
    (property "Manufacturer" "Bourns")
    (property "Sheetfile" "interfaces.kicad_sch")
    (property "Sheetname" "Interfaces")
    (property "Tolerance" "1%")
    (property "Val" "10k")
    (property "ki_description" "10k resistor in 0402 package with 1% tolerance")
    (attr smd)
    (fp_text reference "R13" (at 3.2 0.403 270) (layer "B.SilkS")
        (effects (font (size 0.7 0.7) (thickness 0.15)) (justify left bottom mirror))
    )
    (fp_text value "R_10k_0402" (at 0 -1.4 270) (layer "B.Fab")
        (effects (font (size 0.7 0.7) (thickness 0.15)) (justify left bottom mirror))
    )
    (fp_text user "Author: Antmicro" (at -0.95 -4.169 270) (layer "B.Fab") hide
        (effects (font (size 0.7 0.7) (thickness 0.15)) (justify left bottom mirror))
    )
    (fp_text user "License: Apache-2.0" (at -0.95 -5.169 270) (layer "B.Fab") hide
        (effects (font (size 0.7 0.7) (thickness 0.15)) (justify left bottom mirror))
    )
    (fp_text user "${REFERENCE}" (at -0.95 -3.168 270) (layer "B.Fab") hide
        (effects (font (size 0.7 0.7) (thickness 0.15)) (justify left bottom mirror))
    )
    (fp_rect (start -0.95 0.48) (end 0.95 -0.48)
      (stroke (width 0.05) (type solid)) (fill none) (layer "B.CrtYd"))
    (fp_rect (start -0.5 0.25) (end 0.5 -0.25)
      (stroke (width 0.15) (type solid)) (fill none) (layer "B.Fab"))
    (pad "1" smd roundrect (at -0.485 0 90) (size 0.59 0.64) (layers "B.Cu" "B.Paste" "B.Mask") (roundrect_rratio 0.25)
      (net 232 "3V3_RPi") (pintype "passive"))
    (pad "2" smd roundrect (at 0.485 0 90) (size 0.59 0.64) (layers "B.Cu" "B.Paste" "B.Mask") (roundrect_rratio 0.25)
      (net 33 "SD_DAT2") (pintype "passive"))
  )

  (footprint "scalenode-cm4-baseboard-footprints:R_0402_1005Metric" (layer "B.Cu")
    (at 98.436 86.375 90)
    (descr "Resistor SMD 0402")
    (tags "resistor SMD 0402")
    (property "Author" "Antmicro")
    (property "License" "Apache-2.0")
    (property "MPN" "CR0402-FX-1002GLF")
    (property "Manufacturer" "Bourns")
    (property "Sheetfile" "interfaces.kicad_sch")
    (property "Sheetname" "Interfaces")
    (property "Tolerance" "1%")
    (property "Val" "10k")
    (property "ki_description" "10k resistor in 0402 package with 1% tolerance")
    (attr smd)
    (fp_text reference "R12" (at 3.2 0.403 270) (layer "B.SilkS")
        (effects (font (size 0.7 0.7) (thickness 0.15)) (justify left bottom mirror))
    )
    (fp_text value "R_10k_0402" (at 0 -1.4 270) (layer "B.Fab")
        (effects (font (size 0.7 0.7) (thickness 0.15)) (justify left bottom mirror))
    )
    (fp_text user "License: Apache-2.0" (at -0.95 -5.169 270) (layer "B.Fab") hide
        (effects (font (size 0.7 0.7) (thickness 0.15)) (justify left bottom mirror))
    )
    (fp_text user "Author: Antmicro" (at -0.95 -4.169 270) (layer "B.Fab") hide
        (effects (font (size 0.7 0.7) (thickness 0.15)) (justify left bottom mirror))
    )
    (fp_text user "${REFERENCE}" (at -0.95 -3.168 270) (layer "B.Fab") hide
        (effects (font (size 0.7 0.7) (thickness 0.15)) (justify left bottom mirror))
    )
    (fp_rect (start -0.95 0.48) (end 0.95 -0.48)
      (stroke (width 0.05) (type solid)) (fill none) (layer "B.CrtYd"))
    (fp_rect (start -0.5 0.25) (end 0.5 -0.25)
      (stroke (width 0.15) (type solid)) (fill none) (layer "B.Fab"))
    (pad "1" smd roundrect (at -0.485 0 90) (size 0.59 0.64) (layers "B.Cu" "B.Paste" "B.Mask") (roundrect_rratio 0.25)
      (net 232 "3V3_RPi") (pintype "passive"))
    (pad "2" smd roundrect (at 0.485 0 90) (size 0.59 0.64) (layers "B.Cu" "B.Paste" "B.Mask") (roundrect_rratio 0.25)
      (net 32 "SD_DAT3") (pintype "passive"))
  )

  (footprint "scalenode-cm4-baseboard-footprints:R_0402_1005Metric" (layer "B.Cu")
    (at 97.42 86.375 90)
    (descr "Resistor SMD 0402")
    (tags "resistor SMD 0402")
    (property "Author" "Antmicro")
    (property "License" "Apache-2.0")
    (property "MPN" "CR0402-FX-1002GLF")
    (property "Manufacturer" "Bourns")
    (property "Sheetfile" "interfaces.kicad_sch")
    (property "Sheetname" "Interfaces")
    (property "Tolerance" "1%")
    (property "Val" "10k")
    (property "ki_description" "10k resistor in 0402 package with 1% tolerance")
    (attr smd)
    (fp_text reference "R11" (at 3.2 0.403 270) (layer "B.SilkS")
        (effects (font (size 0.7 0.7) (thickness 0.15)) (justify left bottom mirror))
    )
    (fp_text value "R_10k_0402" (at 0 -1.4 270) (layer "B.Fab")
        (effects (font (size 0.7 0.7) (thickness 0.15)) (justify left bottom mirror))
    )
    (fp_text user "License: Apache-2.0" (at -0.95 -5.169 270) (layer "B.Fab") hide
        (effects (font (size 0.7 0.7) (thickness 0.15)) (justify left bottom mirror))
    )
    (fp_text user "Author: Antmicro" (at -0.95 -4.169 270) (layer "B.Fab") hide
        (effects (font (size 0.7 0.7) (thickness 0.15)) (justify left bottom mirror))
    )
    (fp_text user "${REFERENCE}" (at -0.95 -3.168 270) (layer "B.Fab") hide
        (effects (font (size 0.7 0.7) (thickness 0.15)) (justify left bottom mirror))
    )
    (fp_rect (start -0.95 0.48) (end 0.95 -0.48)
      (stroke (width 0.05) (type solid)) (fill none) (layer "B.CrtYd"))
    (fp_rect (start -0.5 0.25) (end 0.5 -0.25)
      (stroke (width 0.15) (type solid)) (fill none) (layer "B.Fab"))
    (pad "1" smd roundrect (at -0.485 0 90) (size 0.59 0.64) (layers "B.Cu" "B.Paste" "B.Mask") (roundrect_rratio 0.25)
      (net 232 "3V3_RPi") (pintype "passive"))
    (pad "2" smd roundrect (at 0.485 0 90) (size 0.59 0.64) (layers "B.Cu" "B.Paste" "B.Mask") (roundrect_rratio 0.25)
      (net 31 "SD_CMD") (pintype "passive"))
  )

  (footprint "scalenode-cm4-baseboard-footprints:R_0402_1005Metric" (layer "B.Cu")
    (at 96.404 86.375 90)
    (descr "Resistor SMD 0402")
    (tags "resistor SMD 0402")
    (property "Author" "Antmicro")
    (property "License" "Apache-2.0")
    (property "MPN" "CR0402-FX-1002GLF")
    (property "Manufacturer" "Bourns")
    (property "Sheetfile" "interfaces.kicad_sch")
    (property "Sheetname" "Interfaces")
    (property "Tolerance" "1%")
    (property "Val" "10k")
    (property "ki_description" "10k resistor in 0402 package with 1% tolerance")
    (attr smd)
    (fp_text reference "R10" (at 3.2 0.403 270) (layer "B.SilkS")
        (effects (font (size 0.7 0.7) (thickness 0.15)) (justify left bottom mirror))
    )
    (fp_text value "R_10k_0402" (at 0 -1.4 270) (layer "B.Fab")
        (effects (font (size 0.7 0.7) (thickness 0.15)) (justify left bottom mirror))
    )
    (fp_text user "License: Apache-2.0" (at -0.95 -5.169 270) (layer "B.Fab") hide
        (effects (font (size 0.7 0.7) (thickness 0.15)) (justify left bottom mirror))
    )
    (fp_text user "Author: Antmicro" (at -0.95 -4.169 270) (layer "B.Fab") hide
        (effects (font (size 0.7 0.7) (thickness 0.15)) (justify left bottom mirror))
    )
    (fp_text user "${REFERENCE}" (at -0.95 -3.168 270) (layer "B.Fab") hide
        (effects (font (size 0.7 0.7) (thickness 0.15)) (justify left bottom mirror))
    )
    (fp_rect (start -0.95 0.48) (end 0.95 -0.48)
      (stroke (width 0.05) (type solid)) (fill none) (layer "B.CrtYd"))
    (fp_rect (start -0.5 0.25) (end 0.5 -0.25)
      (stroke (width 0.15) (type solid)) (fill none) (layer "B.Fab"))
    (pad "1" smd roundrect (at -0.485 0 90) (size 0.59 0.64) (layers "B.Cu" "B.Paste" "B.Mask") (roundrect_rratio 0.25)
      (net 232 "3V3_RPi") (pintype "passive"))
    (pad "2" smd roundrect (at 0.485 0 90) (size 0.59 0.64) (layers "B.Cu" "B.Paste" "B.Mask") (roundrect_rratio 0.25)
      (net 30 "SD_CLK") (pintype "passive"))
  )

  (footprint "scalenode-cm4-baseboard-footprints:R_0402_1005Metric" (layer "B.Cu")
    (at 95.388 86.375 90)
    (descr "Resistor SMD 0402")
    (tags "resistor SMD 0402")
    (property "Author" "Antmicro")
    (property "License" "Apache-2.0")
    (property "MPN" "CR0402-FX-1002GLF")
    (property "Manufacturer" "Bourns")
    (property "Sheetfile" "interfaces.kicad_sch")
    (property "Sheetname" "Interfaces")
    (property "Tolerance" "1%")
    (property "Val" "10k")
    (property "ki_description" "10k resistor in 0402 package with 1% tolerance")
    (attr smd)
    (fp_text reference "R9" (at 3.2 0.403 270) (layer "B.SilkS")
        (effects (font (size 0.7 0.7) (thickness 0.15)) (justify left bottom mirror))
    )
    (fp_text value "R_10k_0402" (at 0 -1.4 270) (layer "B.Fab")
        (effects (font (size 0.7 0.7) (thickness 0.15)) (justify left bottom mirror))
    )
    (fp_text user "Author: Antmicro" (at -0.95 -4.169 270) (layer "B.Fab") hide
        (effects (font (size 0.7 0.7) (thickness 0.15)) (justify left bottom mirror))
    )
    (fp_text user "License: Apache-2.0" (at -0.95 -5.169 270) (layer "B.Fab") hide
        (effects (font (size 0.7 0.7) (thickness 0.15)) (justify left bottom mirror))
    )
    (fp_text user "${REFERENCE}" (at -0.95 -3.168 270) (layer "B.Fab") hide
        (effects (font (size 0.7 0.7) (thickness 0.15)) (justify left bottom mirror))
    )
    (fp_rect (start -0.95 0.48) (end 0.95 -0.48)
      (stroke (width 0.05) (type solid)) (fill none) (layer "B.CrtYd"))
    (fp_rect (start -0.5 0.25) (end 0.5 -0.25)
      (stroke (width 0.15) (type solid)) (fill none) (layer "B.Fab"))
    (pad "1" smd roundrect (at -0.485 0 90) (size 0.59 0.64) (layers "B.Cu" "B.Paste" "B.Mask") (roundrect_rratio 0.25)
      (net 232 "3V3_RPi") (pintype "passive"))
    (pad "2" smd roundrect (at 0.485 0 90) (size 0.59 0.64) (layers "B.Cu" "B.Paste" "B.Mask") (roundrect_rratio 0.25)
      (net 29 "SD_DAT0") (pintype "passive"))
  )

  (footprint "scalenode-cm4-baseboard-footprints:R_0402_1005Metric" (layer "B.Cu")
    (at 94.372 86.375 90)
    (descr "Resistor SMD 0402")
    (tags "resistor SMD 0402")
    (property "Author" "Antmicro")
    (property "License" "Apache-2.0")
    (property "MPN" "CR0402-FX-1002GLF")
    (property "Manufacturer" "Bourns")
    (property "Sheetfile" "interfaces.kicad_sch")
    (property "Sheetname" "Interfaces")
    (property "Tolerance" "1%")
    (property "Val" "10k")
    (property "ki_description" "10k resistor in 0402 package with 1% tolerance")
    (attr smd)
    (fp_text reference "R5" (at 3.2 0.403 270) (layer "B.SilkS")
        (effects (font (size 0.7 0.7) (thickness 0.15)) (justify left bottom mirror))
    )
    (fp_text value "R_10k_0402" (at 0 -1.4 270) (layer "B.Fab")
        (effects (font (size 0.7 0.7) (thickness 0.15)) (justify left bottom mirror))
    )
    (fp_text user "${REFERENCE}" (at -0.95 -3.168 270) (layer "B.Fab") hide
        (effects (font (size 0.7 0.7) (thickness 0.15)) (justify left bottom mirror))
    )
    (fp_text user "License: Apache-2.0" (at -0.95 -5.169 270) (layer "B.Fab") hide
        (effects (font (size 0.7 0.7) (thickness 0.15)) (justify left bottom mirror))
    )
    (fp_text user "Author: Antmicro" (at -0.95 -4.169 270) (layer "B.Fab") hide
        (effects (font (size 0.7 0.7) (thickness 0.15)) (justify left bottom mirror))
    )
    (fp_rect (start -0.95 0.48) (end 0.95 -0.48)
      (stroke (width 0.05) (type solid)) (fill none) (layer "B.CrtYd"))
    (fp_rect (start -0.5 0.25) (end 0.5 -0.25)
      (stroke (width 0.15) (type solid)) (fill none) (layer "B.Fab"))
    (pad "1" smd roundrect (at -0.485 0 90) (size 0.59 0.64) (layers "B.Cu" "B.Paste" "B.Mask") (roundrect_rratio 0.25)
      (net 232 "3V3_RPi") (pintype "passive"))
    (pad "2" smd roundrect (at 0.485 0 90) (size 0.59 0.64) (layers "B.Cu" "B.Paste" "B.Mask") (roundrect_rratio 0.25)
      (net 28 "SD_DAT1") (pintype "passive"))
  )

  (footprint "scalenode-cm4-baseboard-footprints:C_0603_1608Metric" (layer "B.Cu")
    (at 176.07 67.352 -90)
    (descr "Capacitor SMD 0603")
    (tags "capacitor 0603")
    (property "Author" "Antmicro")
    (property "Dielectric" "")
    (property "License" "Apache-2.0")
    (property "MPN" "0603YC104KAZ2A")
    (property "Manufacturer" "AVX")
    (property "Sheetfile" "nvme-ssd.kicad_sch")
    (property "Sheetname" "NVMe SSD")
    (property "Val" "100n")
    (property "Voltage" "")
    (property "ki_description" " ")
    (attr smd)
    (fp_text reference "C7" (at -3.143667 -0.405 90) (layer "B.SilkS")
        (effects (font (size 0.7 0.7) (thickness 0.15)) (justify left bottom mirror))
    )
    (fp_text value "C_100n_0603" (at 0 -1.6 90) (layer "B.Fab")
        (effects (font (size 0.7 0.7) (thickness 0.15)) (justify left bottom mirror))
    )
    (fp_text user "Author: Antmicro" (at -1.682 -4.894 90) (layer "B.Fab") hide
        (effects (font (size 0.7 0.7) (thickness 0.15)) (justify left bottom mirror))
    )
    (fp_text user "License: Apache-2.0" (at -1.682 -5.895 90) (layer "B.Fab") hide
        (effects (font (size 0.7 0.7) (thickness 0.15)) (justify left bottom mirror))
    )
    (fp_text user "${REFERENCE}" (at -1.682 -3.895 90) (layer "B.Fab") hide
        (effects (font (size 0.7 0.7) (thickness 0.15)) (justify left bottom mirror))
    )
    (fp_line (start -0.3 -0.3) (end 0.3 -0.3)
      (stroke (width 0.15) (type solid)) (layer "B.SilkS"))
    (fp_line (start -0.3 0.3) (end 0.3 0.3)
      (stroke (width 0.15) (type solid)) (layer "B.SilkS"))
    (fp_rect (start -1.24 0.7) (end 1.24 -0.7)
      (stroke (width 0.05) (type solid)) (fill none) (layer "B.CrtYd"))
    (fp_rect (start -0.8 0.4) (end 0.8 -0.4)
      (stroke (width 0.15) (type solid)) (fill none) (layer "B.Fab"))
    (pad "1" smd roundrect (at -0.7 0 270) (size 0.6 0.8) (layers "B.Cu" "B.Paste" "B.Mask") (roundrect_rratio 0.2)
      (net 11 "GND") (pintype "passive"))
    (pad "2" smd roundrect (at 0.7 0 270) (size 0.6 0.8) (layers "B.Cu" "B.Paste" "B.Mask") (roundrect_rratio 0.2)
      (net 170 "3V3_SSD") (pintype "passive"))
  )

  (footprint "scalenode-cm4-baseboard-footprints:C_0603_1608Metric" (layer "B.Cu")
    (at 173.022 81.068 -90)
    (descr "Capacitor SMD 0603")
    (tags "capacitor 0603")
    (property "Author" "Antmicro")
    (property "License" "Apache-2.0")
    (property "MPN" "GRM188R61A106KE69D")
    (property "Manufacturer" "Murata")
    (property "Sheetfile" "nvme-ssd.kicad_sch")
    (property "Sheetname" "NVMe SSD")
    (property "Val" "10u")
    (property "Voltage" "")
    (property "ki_description" " ")
    (attr smd)
    (fp_text reference "C2" (at -2.968 -0.503 90) (layer "B.SilkS")
        (effects (font (size 0.7 0.7) (thickness 0.15)) (justify left bottom mirror))
    )
    (fp_text value "C_10u_0603" (at 0 -1.6 90) (layer "B.Fab")
        (effects (font (size 0.7 0.7) (thickness 0.15)) (justify left bottom mirror))
    )
    (fp_text user "Author: Antmicro" (at -1.682 -4.894 90) (layer "B.Fab") hide
        (effects (font (size 0.7 0.7) (thickness 0.15)) (justify left bottom mirror))
    )
    (fp_text user "${REFERENCE}" (at -1.682 -3.895 90) (layer "B.Fab") hide
        (effects (font (size 0.7 0.7) (thickness 0.15)) (justify left bottom mirror))
    )
    (fp_text user "License: Apache-2.0" (at -1.682 -5.895 90) (layer "B.Fab") hide
        (effects (font (size 0.7 0.7) (thickness 0.15)) (justify left bottom mirror))
    )
    (fp_line (start -0.3 -0.3) (end 0.3 -0.3)
      (stroke (width 0.15) (type solid)) (layer "B.SilkS"))
    (fp_line (start -0.3 0.3) (end 0.3 0.3)
      (stroke (width 0.15) (type solid)) (layer "B.SilkS"))
    (fp_rect (start -1.24 0.7) (end 1.24 -0.7)
      (stroke (width 0.05) (type solid)) (fill none) (layer "B.CrtYd"))
    (fp_rect (start -0.8 0.4) (end 0.8 -0.4)
      (stroke (width 0.15) (type solid)) (fill none) (layer "B.Fab"))
    (pad "1" smd roundrect (at -0.7 0 270) (size 0.6 0.8) (layers "B.Cu" "B.Paste" "B.Mask") (roundrect_rratio 0.2)
      (net 11 "GND") (pintype "passive"))
    (pad "2" smd roundrect (at 0.7 0 270) (size 0.6 0.8) (layers "B.Cu" "B.Paste" "B.Mask") (roundrect_rratio 0.2)
      (net 170 "3V3_SSD") (pintype "passive"))
  )

  (footprint "scalenode-cm4-baseboard-footprints:C_0603_1608Metric" (layer "B.Cu")
    (at 177.594 86.148 90)
    (descr "Capacitor SMD 0603")
    (tags "capacitor 0603")
    (property "Author" "Antmicro")
    (property "Dielectric" "")
    (property "License" "Apache-2.0")
    (property "MPN" "06031C102JAT2A")
    (property "Manufacturer" "AVX")
    (property "Sheetfile" "nvme-ssd.kicad_sch")
    (property "Sheetname" "NVMe SSD")
    (property "Val" "1n")
    (property "Voltage" "")
    (property "ki_description" " ")
    (attr smd)
    (fp_text reference "C12" (at -3.502 0.456 90) (layer "B.SilkS")
        (effects (font (size 0.7 0.7) (thickness 0.15)) (justify right bottom mirror))
    )
    (fp_text value "C_1n_0603" (at 0 -1.6 90) (layer "B.Fab")
        (effects (font (size 0.7 0.7) (thickness 0.15)) (justify right bottom mirror))
    )
    (fp_text user "${REFERENCE}" (at -1.682 -3.895 90) (layer "B.Fab") hide
        (effects (font (size 0.7 0.7) (thickness 0.15)) (justify right bottom mirror))
    )
    (fp_text user "Author: Antmicro" (at -1.682 -4.894 90) (layer "B.Fab") hide
        (effects (font (size 0.7 0.7) (thickness 0.15)) (justify right bottom mirror))
    )
    (fp_text user "License: Apache-2.0" (at -1.682 -5.895 90) (layer "B.Fab") hide
        (effects (font (size 0.7 0.7) (thickness 0.15)) (justify right bottom mirror))
    )
    (fp_line (start -0.3 -0.3) (end 0.3 -0.3)
      (stroke (width 0.15) (type solid)) (layer "B.SilkS"))
    (fp_line (start -0.3 0.3) (end 0.3 0.3)
      (stroke (width 0.15) (type solid)) (layer "B.SilkS"))
    (fp_rect (start -1.24 0.7) (end 1.24 -0.7)
      (stroke (width 0.05) (type solid)) (fill none) (layer "B.CrtYd"))
    (fp_rect (start -0.8 0.4) (end 0.8 -0.4)
      (stroke (width 0.15) (type solid)) (fill none) (layer "B.Fab"))
    (pad "1" smd roundrect (at -0.7 0 90) (size 0.6 0.8) (layers "B.Cu" "B.Paste" "B.Mask") (roundrect_rratio 0.2)
      (net 11 "GND") (pintype "passive"))
    (pad "2" smd roundrect (at 0.7 0 90) (size 0.6 0.8) (layers "B.Cu" "B.Paste" "B.Mask") (roundrect_rratio 0.2)
      (net 170 "3V3_SSD") (pintype "passive"))
  )

  (footprint "scalenode-cm4-baseboard-footprints:C_0603_1608Metric" (layer "B.Cu")
    (at 176.07 81.068 -90)
    (descr "Capacitor SMD 0603")
    (tags "capacitor 0603")
    (property "Author" "Antmicro")
    (property "Dielectric" "")
    (property "License" "Apache-2.0")
    (property "MPN" "0603YC104KAZ2A")
    (property "Manufacturer" "AVX")
    (property "Sheetfile" "nvme-ssd.kicad_sch")
    (property "Sheetname" "NVMe SSD")
    (property "Val" "100n")
    (property "Voltage" "")
    (property "ki_description" " ")
    (attr smd)
    (fp_text reference "C8" (at -2.968 -0.355 90) (layer "B.SilkS")
        (effects (font (size 0.7 0.7) (thickness 0.15)) (justify left bottom mirror))
    )
    (fp_text value "C_100n_0603" (at 0 -1.6 90) (layer "B.Fab")
        (effects (font (size 0.7 0.7) (thickness 0.15)) (justify left bottom mirror))
    )
    (fp_text user "License: Apache-2.0" (at -1.682 -5.895 90) (layer "B.Fab") hide
        (effects (font (size 0.7 0.7) (thickness 0.15)) (justify left bottom mirror))
    )
    (fp_text user "Author: Antmicro" (at -1.682 -4.894 90) (layer "B.Fab") hide
        (effects (font (size 0.7 0.7) (thickness 0.15)) (justify left bottom mirror))
    )
    (fp_text user "${REFERENCE}" (at -1.682 -3.895 90) (layer "B.Fab") hide
        (effects (font (size 0.7 0.7) (thickness 0.15)) (justify left bottom mirror))
    )
    (fp_line (start -0.3 -0.3) (end 0.3 -0.3)
      (stroke (width 0.15) (type solid)) (layer "B.SilkS"))
    (fp_line (start -0.3 0.3) (end 0.3 0.3)
      (stroke (width 0.15) (type solid)) (layer "B.SilkS"))
    (fp_rect (start -1.24 0.7) (end 1.24 -0.7)
      (stroke (width 0.05) (type solid)) (fill none) (layer "B.CrtYd"))
    (fp_rect (start -0.8 0.4) (end 0.8 -0.4)
      (stroke (width 0.15) (type solid)) (fill none) (layer "B.Fab"))
    (pad "1" smd roundrect (at -0.7 0 270) (size 0.6 0.8) (layers "B.Cu" "B.Paste" "B.Mask") (roundrect_rratio 0.2)
      (net 11 "GND") (pintype "passive"))
    (pad "2" smd roundrect (at 0.7 0 270) (size 0.6 0.8) (layers "B.Cu" "B.Paste" "B.Mask") (roundrect_rratio 0.2)
      (net 170 "3V3_SSD") (pintype "passive"))
  )

  (footprint "scalenode-cm4-baseboard-footprints:C_0603_1608Metric" (layer "B.Cu")
    (at 174.546 81.068 -90)
    (descr "Capacitor SMD 0603")
    (tags "capacitor 0603")
    (property "Author" "Antmicro")
    (property "Dielectric" "")
    (property "License" "Apache-2.0")
    (property "MPN" "0603YD105KAT2A")
    (property "Manufacturer" "Walsin")
    (property "Sheetfile" "nvme-ssd.kicad_sch")
    (property "Sheetname" "NVMe SSD")
    (property "Val" "1u")
    (property "Voltage" "")
    (property "ki_description" " ")
    (attr smd)
    (fp_text reference "C5" (at -2.968 -0.379 90) (layer "B.SilkS")
        (effects (font (size 0.7 0.7) (thickness 0.15)) (justify left bottom mirror))
    )
    (fp_text value "C_1u_0603" (at 0 -1.6 90) (layer "B.Fab")
        (effects (font (size 0.7 0.7) (thickness 0.15)) (justify left bottom mirror))
    )
    (fp_text user "License: Apache-2.0" (at -1.682 -5.895 90) (layer "B.Fab") hide
        (effects (font (size 0.7 0.7) (thickness 0.15)) (justify left bottom mirror))
    )
    (fp_text user "${REFERENCE}" (at -1.682 -3.895 90) (layer "B.Fab") hide
        (effects (font (size 0.7 0.7) (thickness 0.15)) (justify left bottom mirror))
    )
    (fp_text user "Author: Antmicro" (at -1.682 -4.894 90) (layer "B.Fab") hide
        (effects (font (size 0.7 0.7) (thickness 0.15)) (justify left bottom mirror))
    )
    (fp_line (start -0.3 -0.3) (end 0.3 -0.3)
      (stroke (width 0.15) (type solid)) (layer "B.SilkS"))
    (fp_line (start -0.3 0.3) (end 0.3 0.3)
      (stroke (width 0.15) (type solid)) (layer "B.SilkS"))
    (fp_rect (start -1.24 0.7) (end 1.24 -0.7)
      (stroke (width 0.05) (type solid)) (fill none) (layer "B.CrtYd"))
    (fp_rect (start -0.8 0.4) (end 0.8 -0.4)
      (stroke (width 0.15) (type solid)) (fill none) (layer "B.Fab"))
    (pad "1" smd roundrect (at -0.7 0 270) (size 0.6 0.8) (layers "B.Cu" "B.Paste" "B.Mask") (roundrect_rratio 0.2)
      (net 11 "GND") (pintype "passive"))
    (pad "2" smd roundrect (at 0.7 0 270) (size 0.6 0.8) (layers "B.Cu" "B.Paste" "B.Mask") (roundrect_rratio 0.2)
      (net 170 "3V3_SSD") (pintype "passive"))
  )

  (footprint "scalenode-cm4-baseboard-footprints:C_0603_1608Metric" (layer "B.Cu")
    (at 177.594 81.068 -90)
    (descr "Capacitor SMD 0603")
    (tags "capacitor 0603")
    (property "Author" "Antmicro")
    (property "Dielectric" "")
    (property "License" "Apache-2.0")
    (property "MPN" "06031C102JAT2A")
    (property "Manufacturer" "AVX")
    (property "Sheetfile" "nvme-ssd.kicad_sch")
    (property "Sheetname" "NVMe SSD")
    (property "Val" "1n")
    (property "Voltage" "")
    (property "ki_description" " ")
    (attr smd)
    (fp_text reference "C11" (at -3.301333 -0.356 90) (layer "B.SilkS")
        (effects (font (size 0.7 0.7) (thickness 0.15)) (justify left bottom mirror))
    )
    (fp_text value "C_1n_0603" (at 0 -1.6 90) (layer "B.Fab")
        (effects (font (size 0.7 0.7) (thickness 0.15)) (justify left bottom mirror))
    )
    (fp_text user "${REFERENCE}" (at -1.682 -3.895 90) (layer "B.Fab") hide
        (effects (font (size 0.7 0.7) (thickness 0.15)) (justify left bottom mirror))
    )
    (fp_text user "Author: Antmicro" (at -1.682 -4.894 90) (layer "B.Fab") hide
        (effects (font (size 0.7 0.7) (thickness 0.15)) (justify left bottom mirror))
    )
    (fp_text user "License: Apache-2.0" (at -1.682 -5.895 90) (layer "B.Fab") hide
        (effects (font (size 0.7 0.7) (thickness 0.15)) (justify left bottom mirror))
    )
    (fp_line (start -0.3 -0.3) (end 0.3 -0.3)
      (stroke (width 0.15) (type solid)) (layer "B.SilkS"))
    (fp_line (start -0.3 0.3) (end 0.3 0.3)
      (stroke (width 0.15) (type solid)) (layer "B.SilkS"))
    (fp_rect (start -1.24 0.7) (end 1.24 -0.7)
      (stroke (width 0.05) (type solid)) (fill none) (layer "B.CrtYd"))
    (fp_rect (start -0.8 0.4) (end 0.8 -0.4)
      (stroke (width 0.15) (type solid)) (fill none) (layer "B.Fab"))
    (pad "1" smd roundrect (at -0.7 0 270) (size 0.6 0.8) (layers "B.Cu" "B.Paste" "B.Mask") (roundrect_rratio 0.2)
      (net 11 "GND") (pintype "passive"))
    (pad "2" smd roundrect (at 0.7 0 270) (size 0.6 0.8) (layers "B.Cu" "B.Paste" "B.Mask") (roundrect_rratio 0.2)
      (net 170 "3V3_SSD") (pintype "passive"))
  )

  (footprint "scalenode-cm4-baseboard-footprints:C_0603_1608Metric" (layer "B.Cu")
    (at 173.022 86.148 90)
    (descr "Capacitor SMD 0603")
    (tags "capacitor 0603")
    (property "Author" "Antmicro")
    (property "License" "Apache-2.0")
    (property "MPN" "GRM188R61A106KE69D")
    (property "Manufacturer" "Murata")
    (property "Sheetfile" "nvme-ssd.kicad_sch")
    (property "Sheetname" "NVMe SSD")
    (property "Val" "10u")
    (property "Voltage" "")
    (property "ki_description" " ")
    (attr smd)
    (fp_text reference "C3" (at -3.168667 0.353 90) (layer "B.SilkS")
        (effects (font (size 0.7 0.7) (thickness 0.15)) (justify right bottom mirror))
    )
    (fp_text value "C_10u_0603" (at 0 -1.6 90) (layer "B.Fab")
        (effects (font (size 0.7 0.7) (thickness 0.15)) (justify right bottom mirror))
    )
    (fp_text user "Author: Antmicro" (at -1.682 -4.894 90) (layer "B.Fab") hide
        (effects (font (size 0.7 0.7) (thickness 0.15)) (justify right bottom mirror))
    )
    (fp_text user "License: Apache-2.0" (at -1.682 -5.895 90) (layer "B.Fab") hide
        (effects (font (size 0.7 0.7) (thickness 0.15)) (justify right bottom mirror))
    )
    (fp_text user "${REFERENCE}" (at -1.682 -3.895 90) (layer "B.Fab") hide
        (effects (font (size 0.7 0.7) (thickness 0.15)) (justify right bottom mirror))
    )
    (fp_line (start -0.3 -0.3) (end 0.3 -0.3)
      (stroke (width 0.15) (type solid)) (layer "B.SilkS"))
    (fp_line (start -0.3 0.3) (end 0.3 0.3)
      (stroke (width 0.15) (type solid)) (layer "B.SilkS"))
    (fp_rect (start -1.24 0.7) (end 1.24 -0.7)
      (stroke (width 0.05) (type solid)) (fill none) (layer "B.CrtYd"))
    (fp_rect (start -0.8 0.4) (end 0.8 -0.4)
      (stroke (width 0.15) (type solid)) (fill none) (layer "B.Fab"))
    (pad "1" smd roundrect (at -0.7 0 90) (size 0.6 0.8) (layers "B.Cu" "B.Paste" "B.Mask") (roundrect_rratio 0.2)
      (net 11 "GND") (pintype "passive"))
    (pad "2" smd roundrect (at 0.7 0 90) (size 0.6 0.8) (layers "B.Cu" "B.Paste" "B.Mask") (roundrect_rratio 0.2)
      (net 170 "3V3_SSD") (pintype "passive"))
  )

  (footprint "scalenode-cm4-baseboard-footprints:C_0603_1608Metric" (layer "B.Cu")
    (at 177.594 67.352 -90)
    (descr "Capacitor SMD 0603")
    (tags "capacitor 0603")
    (property "Author" "Antmicro")
    (property "Dielectric" "")
    (property "License" "Apache-2.0")
    (property "MPN" "06031C102JAT2A")
    (property "Manufacturer" "AVX")
    (property "Sheetfile" "nvme-ssd.kicad_sch")
    (property "Sheetname" "NVMe SSD")
    (property "Val" "1n")
    (property "Voltage" "")
    (property "ki_description" " ")
    (attr smd)
    (fp_text reference "C10" (at -3.477 -0.356 90) (layer "B.SilkS")
        (effects (font (size 0.7 0.7) (thickness 0.15)) (justify left bottom mirror))
    )
    (fp_text value "C_1n_0603" (at 0 -1.6 90) (layer "B.Fab")
        (effects (font (size 0.7 0.7) (thickness 0.15)) (justify left bottom mirror))
    )
    (fp_text user "${REFERENCE}" (at -1.682 -3.895 90) (layer "B.Fab") hide
        (effects (font (size 0.7 0.7) (thickness 0.15)) (justify left bottom mirror))
    )
    (fp_text user "License: Apache-2.0" (at -1.682 -5.895 90) (layer "B.Fab") hide
        (effects (font (size 0.7 0.7) (thickness 0.15)) (justify left bottom mirror))
    )
    (fp_text user "Author: Antmicro" (at -1.682 -4.894 90) (layer "B.Fab") hide
        (effects (font (size 0.7 0.7) (thickness 0.15)) (justify left bottom mirror))
    )
    (fp_line (start -0.3 -0.3) (end 0.3 -0.3)
      (stroke (width 0.15) (type solid)) (layer "B.SilkS"))
    (fp_line (start -0.3 0.3) (end 0.3 0.3)
      (stroke (width 0.15) (type solid)) (layer "B.SilkS"))
    (fp_rect (start -1.24 0.7) (end 1.24 -0.7)
      (stroke (width 0.05) (type solid)) (fill none) (layer "B.CrtYd"))
    (fp_rect (start -0.8 0.4) (end 0.8 -0.4)
      (stroke (width 0.15) (type solid)) (fill none) (layer "B.Fab"))
    (pad "1" smd roundrect (at -0.7 0 270) (size 0.6 0.8) (layers "B.Cu" "B.Paste" "B.Mask") (roundrect_rratio 0.2)
      (net 11 "GND") (pintype "passive"))
    (pad "2" smd roundrect (at 0.7 0 270) (size 0.6 0.8) (layers "B.Cu" "B.Paste" "B.Mask") (roundrect_rratio 0.2)
      (net 170 "3V3_SSD") (pintype "passive"))
  )

  (footprint "scalenode-cm4-baseboard-footprints:C_0805_2012Metric" (layer "B.Cu")
    (at 121.6 85.6)
    (descr "Capacitor SMD 0805")
    (tags "capacitor SMD 0805")
    (property "Author" "Antmicro")
    (property "Dielectric" "")
    (property "License" "Apache-2.0")
    (property "MPN" "0805ZD226MAT2A")
    (property "Manufacturer" "AVX")
    (property "Sheetfile" "supply.kicad_sch")
    (property "Sheetname" "Supply")
    (property "Val" "22u")
    (property "Voltage" "")
    (property "ki_description" " ")
    (attr smd)
    (fp_text reference "C18" (at -1.05 -1.15) (layer "B.SilkS")
        (effects (font (size 0.7 0.7) (thickness 0.15)) (justify right bottom mirror))
    )
    (fp_text value "C_22u_0805_10V" (at 0 -1.947) (layer "B.Fab")
        (effects (font (size 0.7 0.7) (thickness 0.15)) (justify right bottom mirror))
    )
    (fp_text user "Author: Antmicro" (at -1.9 -5.947) (layer "B.Fab") hide
        (effects (font (size 0.7 0.7) (thickness 0.15)) (justify right bottom mirror))
    )
    (fp_text user "License: Apache-2.0" (at -1.9 -4.947) (layer "B.Fab") hide
        (effects (font (size 0.7 0.7) (thickness 0.15)) (justify right bottom mirror))
    )
    (fp_text user "${REFERENCE}" (at -1.9 -3.947) (layer "B.Fab") hide
        (effects (font (size 0.7 0.7) (thickness 0.15)) (justify right bottom mirror))
    )
    (fp_line (start -0.3 -0.8) (end 0.3 -0.8)
      (stroke (width 0.15) (type solid)) (layer "B.SilkS"))
    (fp_line (start -0.3 0.8) (end 0.3 0.8)
      (stroke (width 0.15) (type solid)) (layer "B.SilkS"))
    (fp_rect (start -1.9 0.93) (end 1.9 -0.93)
      (stroke (width 0.05) (type solid)) (fill none) (layer "B.CrtYd"))
    (fp_rect (start -0.95 0.675) (end 0.95 -0.675)
      (stroke (width 0.15) (type solid)) (fill none) (layer "B.Fab"))
    (pad "1" smd rect (at -1.05 0) (size 1.2 1.2) (layers "B.Cu" "B.Paste" "B.Mask")
      (net 11 "GND") (pintype "passive"))
    (pad "2" smd rect (at 1.05 0) (size 1.2 1.2) (layers "B.Cu" "B.Paste" "B.Mask")
      (net 170 "3V3_SSD") (pintype "passive"))
  )

  (footprint "scalenode-cm4-baseboard-footprints:R_0402_1005Metric" (layer "B.Cu")
    (at 129.2 83.8 180)
    (descr "Resistor SMD 0402")
    (tags "resistor SMD 0402")
    (property "Author" "Antmicro")
    (property "License" "Apache-2.0")
    (property "MPN" "CR0402-FX-3322GLF")
    (property "Manufacturer" "Bourns")
    (property "Sheetfile" "supply.kicad_sch")
    (property "Sheetname" "Supply")
    (property "Tolerance" "1%")
    (property "Val" "33k2")
    (property "ki_description" "33k2 resistor in 0402 package with 1% tolerance")
    (attr smd)
    (fp_text reference "R18" (at -1.05 0.7) (layer "B.SilkS")
        (effects (font (size 0.7 0.7) (thickness 0.15)) (justify left bottom mirror))
    )
    (fp_text value "R_33k2_0402" (at 0 -1.4) (layer "B.Fab")
        (effects (font (size 0.7 0.7) (thickness 0.15)) (justify left bottom mirror))
    )
    (fp_text user "License: Apache-2.0" (at -0.95 -5.169) (layer "B.Fab") hide
        (effects (font (size 0.7 0.7) (thickness 0.15)) (justify left bottom mirror))
    )
    (fp_text user "${REFERENCE}" (at -0.95 -3.168) (layer "B.Fab") hide
        (effects (font (size 0.7 0.7) (thickness 0.15)) (justify left bottom mirror))
    )
    (fp_text user "Author: Antmicro" (at -0.95 -4.169) (layer "B.Fab") hide
        (effects (font (size 0.7 0.7) (thickness 0.15)) (justify left bottom mirror))
    )
    (fp_rect (start -0.95 0.48) (end 0.95 -0.48)
      (stroke (width 0.05) (type solid)) (fill none) (layer "B.CrtYd"))
    (fp_rect (start -0.5 0.25) (end 0.5 -0.25)
      (stroke (width 0.15) (type solid)) (fill none) (layer "B.Fab"))
    (pad "1" smd roundrect (at -0.485 0 180) (size 0.59 0.64) (layers "B.Cu" "B.Paste" "B.Mask") (roundrect_rratio 0.25)
      (net 252 "Net-(U2-FB)") (pintype "passive"))
    (pad "2" smd roundrect (at 0.485 0 180) (size 0.59 0.64) (layers "B.Cu" "B.Paste" "B.Mask") (roundrect_rratio 0.25)
      (net 170 "3V3_SSD") (pintype "passive"))
  )

  (footprint "scalenode-cm4-baseboard-footprints:USON-14_3.5x1.35_P0.5mm" (layer "B.Cu")
    (at 92.33 83.44)
    (descr "JEDEC MO-229")
    (property "Author" "Antmicro")
    (property "License" "Apache-2.0")
    (property "MPN" "SP3011-06UTG")
    (property "Manufacturer" "Littelfuse")
    (property "Sheetfile" "interfaces.kicad_sch")
    (property "Sheetname" "Interfaces")
    (attr smd)
    (fp_text reference "D2" (at 0.67 -2.19 180) (layer "B.SilkS")
        (effects (font (size 0.7 0.7) (thickness 0.15)) (justify left bottom mirror))
    )
    (fp_text value "SP3011-06UTG" (at -1.3 -3 180) (layer "B.Fab")
        (effects (font (size 0.7 0.7) (thickness 0.15)) (justify left bottom mirror))
    )
    (fp_text user "." (at -0.83 1.81 180) (layer "B.SilkS")
        (effects (font (size 1 1) (thickness 0.15)) (justify mirror))
    )
    (fp_text user "Author: Antmicro" (at -1.3 -5.4 180) (layer "B.Fab") hide
        (effects (font (size 0.7 0.7) (thickness 0.15)) (justify left bottom mirror))
    )
    (fp_text user "${REFERENCE}" (at -1.3 -4.2 180) (layer "B.Fab") hide
        (effects (font (size 0.7 0.7) (thickness 0.15)) (justify left bottom mirror))
    )
    (fp_text user "License: Apache-2.0" (at -1.3 -6.6 180) (layer "B.Fab") hide
        (effects (font (size 0.7 0.7) (thickness 0.15)) (justify left bottom mirror))
    )
    (fp_line (start -0.8 -1.75) (end 0.8 -1.75)
      (stroke (width 0.12) (type solid)) (layer "B.SilkS"))
    (fp_line (start -0.4 1.75) (end 0.8 1.75)
      (stroke (width 0.12) (type solid)) (layer "B.SilkS"))
    (fp_rect (start 1 1.9) (end -0.95 -1.9)
      (stroke (width 0.05) (type solid)) (fill none) (layer "B.CrtYd"))
    (fp_line (start -0.7 -1.75) (end -0.7 1.55)
      (stroke (width 0.1) (type solid)) (layer "B.Fab"))
    (fp_line (start -0.7 1.55) (end -0.5 1.75)
      (stroke (width 0.1) (type solid)) (layer "B.Fab"))
    (fp_line (start -0.5 1.75) (end 0.65 1.75)
      (stroke (width 0.1) (type solid)) (layer "B.Fab"))
    (fp_line (start 0.65 -1.75) (end -0.7 -1.75)
      (stroke (width 0.1) (type solid)) (layer "B.Fab"))
    (fp_line (start 0.65 1.75) (end 0.65 -1.75)
      (stroke (width 0.1) (type solid)) (layer "B.Fab"))
    (pad "1" smd roundrect (at -0.623 1.5 90) (size 0.2 0.5) (layers "B.Cu" "B.Paste" "B.Mask") (roundrect_rratio 0.25)
      (chamfer_ratio 0.2) (chamfer top_left)
      (net 28 "SD_DAT1") (pintype "passive"))
    (pad "2" smd roundrect (at -0.623 1 90) (size 0.2 0.5) (layers "B.Cu" "B.Paste" "B.Mask") (roundrect_rratio 0.25)
      (net 29 "SD_DAT0") (pintype "passive"))
    (pad "3" smd roundrect (at -0.623 0.5 90) (size 0.2 0.5) (layers "B.Cu" "B.Paste" "B.Mask") (roundrect_rratio 0.25)
      (net 30 "SD_CLK") (pintype "passive"))
    (pad "4" smd roundrect (at -0.623 0 90) (size 0.2 0.5) (layers "B.Cu" "B.Paste" "B.Mask") (roundrect_rratio 0.25)
      (net 31 "SD_CMD") (pintype "passive"))
    (pad "5" smd roundrect (at -0.623 -0.498 90) (size 0.2 0.5) (layers "B.Cu" "B.Paste" "B.Mask") (roundrect_rratio 0.25)
      (net 11 "GND") (pintype "passive"))
    (pad "6" smd roundrect (at -0.623 -0.998 90) (size 0.2 0.5) (layers "B.Cu" "B.Paste" "B.Mask") (roundrect_rratio 0.25)
      (net 32 "SD_DAT3") (pintype "passive"))
    (pad "7" smd roundrect (at -0.623 -1.499 90) (size 0.2 0.5) (layers "B.Cu" "B.Paste" "B.Mask") (roundrect_rratio 0.25)
      (net 33 "SD_DAT2") (pintype "passive"))
    (pad "8" smd roundrect (at 0.625 -1.499 90) (size 0.2 0.5) (layers "B.Cu" "B.Paste" "B.Mask") (roundrect_rratio 0.25)
      (net 33 "SD_DAT2") (pintype "passive"))
    (pad "9" smd roundrect (at 0.625 -0.998 90) (size 0.2 0.5) (layers "B.Cu" "B.Paste" "B.Mask") (roundrect_rratio 0.25)
      (net 32 "SD_DAT3") (pintype "passive"))
    (pad "10" smd roundrect (at 0.625 -0.498 90) (size 0.2 0.5) (layers "B.Cu" "B.Paste" "B.Mask") (roundrect_rratio 0.25)
      (net 11 "GND") (pintype "passive"))
    (pad "11" smd roundrect (at 0.625 0 90) (size 0.2 0.5) (layers "B.Cu" "B.Paste" "B.Mask") (roundrect_rratio 0.25)
      (net 31 "SD_CMD") (pintype "passive"))
    (pad "12" smd roundrect (at 0.625 0.5 90) (size 0.2 0.5) (layers "B.Cu" "B.Paste" "B.Mask") (roundrect_rratio 0.25)
      (net 30 "SD_CLK") (pintype "passive"))
    (pad "13" smd roundrect (at 0.625 1 90) (size 0.2 0.5) (layers "B.Cu" "B.Paste" "B.Mask") (roundrect_rratio 0.25)
      (net 29 "SD_DAT0") (pintype "passive"))
    (pad "14" smd roundrect (at 0.625 1.5 90) (size 0.2 0.5) (layers "B.Cu" "B.Paste" "B.Mask") (roundrect_rratio 0.25)
      (net 28 "SD_DAT1") (pintype "passive"))
  )

  (footprint "scalenode-cm4-baseboard-footprints:C_0805_2012Metric" (layer "B.Cu")
    (at 132.2 90.2 180)
    (descr "Capacitor SMD 0805")
    (tags "capacitor SMD 0805")
    (property "Author" "Antmicro")
    (property "Dielectric" "")
    (property "License" "Apache-2.0")
    (property "MPN" "0805ZD226MAT2A")
    (property "Manufacturer" "AVX")
    (property "Sheetfile" "supply.kicad_sch")
    (property "Sheetname" "Supply")
    (property "Val" "22u")
    (property "Voltage" "")
    (property "ki_description" " ")
    (attr smd)
    (fp_text reference "C16" (at -1.02 -1.84 180) (layer "B.SilkS")
        (effects (font (size 0.7 0.7) (thickness 0.15)) (justify left bottom mirror))
    )
    (fp_text value "C_22u_0805_10V" (at 0 -1.947) (layer "B.Fab")
        (effects (font (size 0.7 0.7) (thickness 0.15)) (justify left bottom mirror))
    )
    (fp_text user "License: Apache-2.0" (at -1.9 -4.947) (layer "B.Fab") hide
        (effects (font (size 0.7 0.7) (thickness 0.15)) (justify left bottom mirror))
    )
    (fp_text user "Author: Antmicro" (at -1.9 -5.947) (layer "B.Fab") hide
        (effects (font (size 0.7 0.7) (thickness 0.15)) (justify left bottom mirror))
    )
    (fp_text user "${REFERENCE}" (at -1.9 -3.947) (layer "B.Fab") hide
        (effects (font (size 0.7 0.7) (thickness 0.15)) (justify left bottom mirror))
    )
    (fp_line (start -0.3 -0.8) (end 0.3 -0.8)
      (stroke (width 0.15) (type solid)) (layer "B.SilkS"))
    (fp_line (start -0.3 0.8) (end 0.3 0.8)
      (stroke (width 0.15) (type solid)) (layer "B.SilkS"))
    (fp_rect (start -1.9 0.93) (end 1.9 -0.93)
      (stroke (width 0.05) (type solid)) (fill none) (layer "B.CrtYd"))
    (fp_rect (start -0.95 0.675) (end 0.95 -0.675)
      (stroke (width 0.15) (type solid)) (fill none) (layer "B.Fab"))
    (pad "1" smd rect (at -1.05 0 180) (size 1.2 1.2) (layers "B.Cu" "B.Paste" "B.Mask")
      (net 11 "GND") (pintype "passive"))
    (pad "2" smd rect (at 1.05 0 180) (size 1.2 1.2) (layers "B.Cu" "B.Paste" "B.Mask")
      (net 12 "VCC5V0") (pintype "passive"))
  )

  (footprint "scalenode-cm4-baseboard-footprints:L_Bourns-SRP3212A" (layer "B.Cu")
    (at 127.5 86.75 180)
    (property "Author" "Antmicro")
    (property "License" "Apache-2.0")
    (property "MPN" "SRP3212A-1R0M")
    (property "Manufacturer" "Bourns")
    (property "MaxCur" "5.5A")
    (property "Sheetfile" "supply.kicad_sch")
    (property "Sheetname" "Supply")
    (property "Size" "3.2x2.5")
    (property "Val" "1u/5.5A")
    (property "ki_description" "4.4x4.1mm")
    (property "ki_keywords" "Fixed Inductors Ind,3.2x2.5x1mm,1uH+/-20%,5.5A,shd AEC-Q200")
    (attr smd)
    (fp_text reference "L1" (at -0.625 1.75) (layer "B.SilkS")
        (effects (font (size 0.7 0.7) (thickness 0.15)) (justify left bottom mirror))
    )
    (fp_text value "L_1u_5.5A_Bourns-SRP3212A" (at 0.05 -3.301) (layer "B.Fab")
        (effects (font (size 0.7 0.7) (thickness 0.15)) (justify left bottom mirror))
    )
    (fp_text user "License: Apache-2.0" (at -2 -7.701) (layer "B.Fab") hide
        (effects (font (size 0.7 0.7) (thickness 0.15)) (justify left bottom mirror))
    )
    (fp_text user "${REFERENCE}" (at -2 -5.301) (layer "B.Fab") hide
        (effects (font (size 0.7 0.7) (thickness 0.15)) (justify left bottom mirror))
    )
    (fp_text user "Author: Antmicro" (at -2 -6.501) (layer "B.Fab") hide
        (effects (font (size 0.7 0.7) (thickness 0.15)) (justify left bottom mirror))
    )
    (fp_line (start -0.401 -1.249) (end 0.4 -1.249)
      (stroke (width 0.15) (type solid)) (layer "B.SilkS"))
    (fp_line (start -0.401 1.25) (end 0.4 1.25)
      (stroke (width 0.15) (type solid)) (layer "B.SilkS"))
    (fp_circle (center -2.3 0) (end -2.25 0)
      (stroke (width 0.15) (type solid)) (fill solid) (layer "B.SilkS"))
    (fp_rect (start -2 1.5) (end 1.99 -1.49)
      (stroke (width 0.05) (type solid)) (fill none) (layer "B.CrtYd"))
    (fp_line (start -1.601 -1.249) (end -1.601 1.25)
      (stroke (width 0.15) (type solid)) (layer "B.Fab"))
    (fp_line (start -1.601 -1.249) (end 1.6 -1.249)
      (stroke (width 0.15) (type solid)) (layer "B.Fab"))
    (fp_line (start 1.6 1.25) (end -1.601 1.25)
      (stroke (width 0.15) (type solid)) (layer "B.Fab"))
    (fp_line (start 1.6 1.25) (end 1.6 -1.249)
      (stroke (width 0.15) (type solid)) (layer "B.Fab"))
    (pad "1" smd roundrect (at -1.176 0 180) (size 1.35 2.8) (layers "B.Cu" "B.Paste" "B.Mask") (roundrect_rratio 0.25)
      (net 19 "Net-(U2-SW)") (pinfunction "1") (pintype "passive"))
    (pad "2" smd roundrect (at 1.175 0 180) (size 1.35 2.8) (layers "B.Cu" "B.Paste" "B.Mask") (roundrect_rratio 0.25)
      (net 170 "3V3_SSD") (pinfunction "2") (pintype "passive"))
  )

  (footprint "scalenode-cm4-baseboard-footprints:C_1210_3225Metric" (layer "B.Cu")
    (at 106.306 63.712 -90)
    (descr "Capacitor SMD 1210")
    (tags "capacitor SMD 1210")
    (property "Author" "Antmicro")
    (property "Dielectric" "")
    (property "License" "Apache-2.0")
    (property "MPN" "C1210C102KGRACTU")
    (property "Manufacturer" "KEMET")
    (property "Sheetfile" "poe.kicad_sch")
    (property "Sheetname" "PoE")
    (property "Val" "1n")
    (property "Voltage" "2kV")
    (property "ki_description" " ")
    (attr smd)
    (fp_text reference "C50" (at -2.237 -0.919 180) (layer "B.SilkS")
        (effects (font (size 0.7 0.7) (thickness 0.15)) (justify left bottom mirror))
    )
    (fp_text value "C_1n_1210_2kV" (at 0 -2.749 90) (layer "B.Fab")
        (effects (font (size 0.7 0.7) (thickness 0.15)) (justify left bottom mirror))
    )
    (fp_text user "License: Apache-2.0" (at -2.1 -6.749 90) (layer "B.Fab") hide
        (effects (font (size 0.7 0.7) (thickness 0.15)) (justify left bottom mirror))
    )
    (fp_text user "${REFERENCE}" (at -2.1 -4.749 90) (layer "B.Fab") hide
        (effects (font (size 0.7 0.7) (thickness 0.15)) (justify left bottom mirror))
    )
    (fp_text user "Author: Antmicro" (at -2.1 -5.749 90) (layer "B.Fab") hide
        (effects (font (size 0.7 0.7) (thickness 0.15)) (justify left bottom mirror))
    )
    (fp_line (start -0.3 -1.39) (end 0.3 -1.39)
      (stroke (width 0.15) (type solid)) (layer "B.SilkS"))
    (fp_line (start -0.3 1.39) (end 0.3 1.39)
      (stroke (width 0.15) (type solid)) (layer "B.SilkS"))
    (fp_rect (start -2.1 1.75) (end 2.1 -1.75)
      (stroke (width 0.05) (type solid)) (fill none) (layer "B.CrtYd"))
    (fp_rect (start -1.6 1.25) (end 1.6 -1.25)
      (stroke (width 0.15) (type solid)) (fill none) (layer "B.Fab"))
    (pad "1" smd rect (at -1.145 0 270) (size 1.52 3.05) (layers "B.Cu" "B.Paste" "B.Mask")
      (net 11 "GND") (pintype "passive"))
    (pad "2" smd rect (at 1.145 0 270) (size 1.52 3.05) (layers "B.Cu" "B.Paste" "B.Mask")
      (net 230 "Earth") (pintype "passive"))
  )

  (footprint "scalenode-cm4-baseboard-footprints:Spacer_Drill1mm_H4mm_97730406332R" (layer "B.Cu")
    (at 142.039 76.877)
    (property "Author" "Antmicro")
    (property "DNP" "DNP")
    (property "License" "Apache-2.0")
    (property "MPN" "97730406332R ")
    (property "Manufacturer" "Würth Elektronik")
    (property "Sheetfile" "nvme-ssd.kicad_sch")
    (property "Sheetname" "NVMe SSD")
    (property "dnp" "")
    (property "exclude_from_bom" "")
    (attr exclude_from_pos_files exclude_from_bom)
    (fp_text reference "SP1" (at 1.071 -2.127 unlocked) (layer "B.SilkS")
        (effects (font (size 0.7 0.7) (thickness 0.15)) (justify left bottom mirror))
    )
    (fp_text value "Spacer_Drill1mm_H4mm_97730406332R" (at 5.183069 1.377434 180 unlocked) (layer "B.Fab")
        (effects (font (size 0.7 0.7) (thickness 0.15)) (justify left bottom mirror))
    )
    (fp_text user "${REFERENCE}" (at 5.259356 -0.014823 180) (layer "B.Fab") hide
        (effects (font (size 0.7 0.7) (thickness 0.15)) (justify left bottom mirror))
    )
    (fp_text user "License: Apache-2.0" (at 5.259356 -2.414823 180) (layer "B.Fab") hide
        (effects (font (size 0.7 0.7) (thickness 0.15)) (justify left bottom mirror))
    )
    (fp_text user "Author: Antmicro" (at 5.259356 -1.214823 180) (layer "B.Fab") hide
        (effects (font (size 0.7 0.7) (thickness 0.15)) (justify left bottom mirror))
    )
    (fp_line (start -1.849 -0.569) (end -1.849 0.579)
      (stroke (width 0.12) (type solid)) (layer "B.Paste"))
    (fp_line (start -1.748 -0.819) (end -1.748 0.83)
      (stroke (width 0.12) (type solid)) (layer "B.Paste"))
    (fp_line (start -1.65 -0.998) (end -1.65 1.024)
      (stroke (width 0.12) (type solid)) (layer "B.Paste"))
    (fp_line (start -1.549 -1.149) (end -1.549 1.159)
      (stroke (width 0.12) (type solid)) (layer "B.Paste"))
    (fp_line (start -1.448 -1.274) (end -1.448 1.275)
      (stroke (width 0.12) (type solid)) (layer "B.Paste"))
    (fp_line (start -1.349 -1.375) (end -1.349 1.374)
      (stroke (width 0.12) (type solid)) (layer "B.Paste"))
    (fp_line (start -1.248 -1.476) (end -1.248 1.468)
      (stroke (width 0.12) (type solid)) (layer "B.Paste"))
    (fp_line (start -1.15 -1.551) (end -1.15 1.55)
      (stroke (width 0.12) (type solid)) (layer "B.Paste"))
    (fp_line (start -1.049 -1.625) (end -1.049 1.624)
      (stroke (width 0.12) (type solid)) (layer "B.Paste"))
    (fp_line (start -0.95 -1.676) (end -0.95 1.679)
      (stroke (width 0.12) (type solid)) (layer "B.Paste"))
    (fp_line (start -0.849 -1.726) (end -0.849 1.739)
      (stroke (width 0.12) (type solid)) (layer "B.Paste"))
    (fp_line (start -0.748 -1.774) (end -0.748 1.778)
      (stroke (width 0.12) (type solid)) (layer "B.Paste"))
    (fp_line (start -0.65 -1.825) (end -0.65 1.823)
      (stroke (width 0.12) (type solid)) (layer "B.Paste"))
    (fp_line (start -0.551 1.87) (end -0.551 -1.86)
      (stroke (width 0.12) (type solid)) (layer "B.Paste"))
    (fp_line (start 0.551 -1.87) (end 0.551 1.859)
      (stroke (width 0.12) (type solid)) (layer "B.Paste"))
    (fp_line (start 0.65 1.823) (end 0.65 -1.825)
      (stroke (width 0.12) (type solid)) (layer "B.Paste"))
    (fp_line (start 0.749 1.775) (end 0.749 -1.779)
      (stroke (width 0.12) (type solid)) (layer "B.Paste"))
    (fp_line (start 0.849 1.724) (end 0.849 -1.74)
      (stroke (width 0.12) (type solid)) (layer "B.Paste"))
    (fp_line (start 0.95 1.675) (end 0.95 -1.679)
      (stroke (width 0.12) (type solid)) (layer "B.Paste"))
    (fp_line (start 1.051 1.624) (end 1.051 -1.625)
      (stroke (width 0.12) (type solid)) (layer "B.Paste"))
    (fp_line (start 1.149 1.55) (end 1.149 -1.551)
      (stroke (width 0.12) (type solid)) (layer "B.Paste"))
    (fp_line (start 1.25 1.474) (end 1.25 -1.469)
      (stroke (width 0.12) (type solid)) (layer "B.Paste"))
    (fp_line (start 1.351 1.374) (end 1.351 -1.375)
      (stroke (width 0.12) (type solid)) (layer "B.Paste"))
    (fp_line (start 1.45 1.275) (end 1.45 -1.274)
      (stroke (width 0.12) (type solid)) (layer "B.Paste"))
    (fp_line (start 1.551 1.15) (end 1.551 -1.16)
      (stroke (width 0.12) (type solid)) (layer "B.Paste"))
    (fp_line (start 1.649 0.999) (end 1.649 -1.024)
      (stroke (width 0.12) (type solid)) (layer "B.Paste"))
    (fp_line (start 1.75 0.82) (end 1.75 -0.83)
      (stroke (width 0.12) (type solid)) (layer "B.Paste"))
    (fp_line (start 1.851 0.57) (end 1.851 -0.578)
      (stroke (width 0.12) (type solid)) (layer "B.Paste"))
    (fp_arc (start -0.551 1.874) (mid -1.952999 0.00274) (end -0.557 -1.873)
      (stroke (width 0.1) (type solid)) (layer "B.Paste"))
    (fp_arc (start 0.551 -1.875) (mid 1.953999 -0.002741) (end 0.557 1.874)
      (stroke (width 0.1) (type solid)) (layer "B.Paste"))
    (fp_circle (center 0.001 2.2) (end 0.051 2.2)
      (stroke (width 0.15) (type solid)) (fill solid) (layer "B.SilkS"))
    (fp_rect (start -1.9 1.9) (end 1.89 -1.89)
      (stroke (width 0.05) (type solid)) (fill none) (layer "B.CrtYd"))
    (pad "1" thru_hole custom (at 0.001 0) (size 4 4) (drill 1) (layers "B.Cu" "B.Mask")
      (net 216 "unconnected-(SP1-Pad1)") (pinfunction "1") (pintype "passive+no_connect") (solder_paste_margin -1.2) (zone_connect 0)
      (options (clearance outline) (anchor circle))
      (primitives
      ))
  )

  (footprint "scalenode-cm4-baseboard-footprints:R_0402_1005Metric" (layer "B.Cu")
    (at 131.5 83.8 180)
    (descr "Resistor SMD 0402")
    (tags "resistor SMD 0402")
    (property "Author" "Antmicro")
    (property "License" "Apache-2.0")
    (property "MPN" "CR0402-FX-1002GLF")
    (property "Manufacturer" "Bourns")
    (property "Sheetfile" "supply.kicad_sch")
    (property "Sheetname" "Supply")
    (property "Tolerance" "1%")
    (property "Val" "10k")
    (property "ki_description" "10k resistor in 0402 package with 1% tolerance")
    (attr smd)
    (fp_text reference "R19" (at -1.025 0.7) (layer "B.SilkS")
        (effects (font (size 0.7 0.7) (thickness 0.15)) (justify left bottom mirror))
    )
    (fp_text value "R_10k_0402" (at 0 -1.4) (layer "B.Fab")
        (effects (font (size 0.7 0.7) (thickness 0.15)) (justify left bottom mirror))
    )
    (fp_text user "Author: Antmicro" (at -0.95 -4.169) (layer "B.Fab") hide
        (effects (font (size 0.7 0.7) (thickness 0.15)) (justify left bottom mirror))
    )
    (fp_text user "${REFERENCE}" (at -0.95 -3.168) (layer "B.Fab") hide
        (effects (font (size 0.7 0.7) (thickness 0.15)) (justify left bottom mirror))
    )
    (fp_text user "License: Apache-2.0" (at -0.95 -5.169) (layer "B.Fab") hide
        (effects (font (size 0.7 0.7) (thickness 0.15)) (justify left bottom mirror))
    )
    (fp_rect (start -0.95 0.48) (end 0.95 -0.48)
      (stroke (width 0.05) (type solid)) (fill none) (layer "B.CrtYd"))
    (fp_rect (start -0.5 0.25) (end 0.5 -0.25)
      (stroke (width 0.15) (type solid)) (fill none) (layer "B.Fab"))
    (pad "1" smd roundrect (at -0.485 0 180) (size 0.59 0.64) (layers "B.Cu" "B.Paste" "B.Mask") (roundrect_rratio 0.25)
      (net 11 "GND") (pintype "passive"))
    (pad "2" smd roundrect (at 0.485 0 180) (size 0.59 0.64) (layers "B.Cu" "B.Paste" "B.Mask") (roundrect_rratio 0.25)
      (net 252 "Net-(U2-FB)") (pintype "passive"))
  )

  (footprint "scalenode-cm4-baseboard-footprints:R_0402_1005Metric" (layer "B.Cu")
    (at 88.425 89.156 -90)
    (descr "Resistor SMD 0402")
    (tags "resistor SMD 0402")
    (property "Author" "Antmicro")
    (property "License" "Apache-2.0")
    (property "MPN" "CR0402-FX-3300GLF")
    (property "Manufacturer" "Bourns")
    (property "Sheetfile" "interfaces.kicad_sch")
    (property "Sheetname" "Interfaces")
    (property "Tolerance" "1%")
    (property "Val" "330R")
    (property "ki_description" "330R resistor in 0402 package with 1% tolerance")
    (attr smd)
    (fp_text reference "R6" (at -2.506 -0.4 90) (layer "B.SilkS")
        (effects (font (size 0.7 0.7) (thickness 0.15)) (justify left bottom mirror))
    )
    (fp_text value "R_330R_0402" (at 0 -1.4 90) (layer "B.Fab")
        (effects (font (size 0.7 0.7) (thickness 0.15)) (justify left bottom mirror))
    )
    (fp_text user "License: Apache-2.0" (at -0.95 -5.169 90) (layer "B.Fab") hide
        (effects (font (size 0.7 0.7) (thickness 0.15)) (justify left bottom mirror))
    )
    (fp_text user "Author: Antmicro" (at -0.95 -4.169 90) (layer "B.Fab") hide
        (effects (font (size 0.7 0.7) (thickness 0.15)) (justify left bottom mirror))
    )
    (fp_text user "${REFERENCE}" (at -0.95 -3.168 90) (layer "B.Fab") hide
        (effects (font (size 0.7 0.7) (thickness 0.15)) (justify left bottom mirror))
    )
    (fp_rect (start -0.95 0.48) (end 0.95 -0.48)
      (stroke (width 0.05) (type solid)) (fill none) (layer "B.CrtYd"))
    (fp_rect (start -0.5 0.25) (end 0.5 -0.25)
      (stroke (width 0.15) (type solid)) (fill none) (layer "B.Fab"))
    (pad "1" smd roundrect (at -0.485 0 270) (size 0.59 0.64) (layers "B.Cu" "B.Paste" "B.Mask") (roundrect_rratio 0.25)
      (net 57 "GPIO3") (pintype "passive"))
    (pad "2" smd roundrect (at 0.485 0 270) (size 0.59 0.64) (layers "B.Cu" "B.Paste" "B.Mask") (roundrect_rratio 0.25)
      (net 201 "Net-(J4-CD1)") (pintype "passive"))
  )

  (footprint "scalenode-cm4-baseboard-footprints:C_0603_1608Metric" (layer "B.Cu")
    (at 173.022 67.352 -90)
    (descr "Capacitor SMD 0603")
    (tags "capacitor 0603")
    (property "Author" "Antmicro")
    (property "License" "Apache-2.0")
    (property "MPN" "GRM188R61A106KE69D")
    (property "Manufacturer" "Murata")
    (property "Sheetfile" "nvme-ssd.kicad_sch")
    (property "Sheetname" "NVMe SSD")
    (property "Val" "10u")
    (property "Voltage" "")
    (property "ki_description" " ")
    (attr smd)
    (fp_text reference "C1" (at -3.143667 -0.678 90) (layer "B.SilkS")
        (effects (font (size 0.7 0.7) (thickness 0.15)) (justify left bottom mirror))
    )
    (fp_text value "C_10u_0603" (at 0 -1.6 90) (layer "B.Fab")
        (effects (font (size 0.7 0.7) (thickness 0.15)) (justify left bottom mirror))
    )
    (fp_text user "Author: Antmicro" (at -1.682 -4.894 90) (layer "B.Fab") hide
        (effects (font (size 0.7 0.7) (thickness 0.15)) (justify left bottom mirror))
    )
    (fp_text user "License: Apache-2.0" (at -1.682 -5.895 90) (layer "B.Fab") hide
        (effects (font (size 0.7 0.7) (thickness 0.15)) (justify left bottom mirror))
    )
    (fp_text user "${REFERENCE}" (at -1.682 -3.895 90) (layer "B.Fab") hide
        (effects (font (size 0.7 0.7) (thickness 0.15)) (justify left bottom mirror))
    )
    (fp_line (start -0.3 -0.3) (end 0.3 -0.3)
      (stroke (width 0.15) (type solid)) (layer "B.SilkS"))
    (fp_line (start -0.3 0.3) (end 0.3 0.3)
      (stroke (width 0.15) (type solid)) (layer "B.SilkS"))
    (fp_rect (start -1.24 0.7) (end 1.24 -0.7)
      (stroke (width 0.05) (type solid)) (fill none) (layer "B.CrtYd"))
    (fp_rect (start -0.8 0.4) (end 0.8 -0.4)
      (stroke (width 0.15) (type solid)) (fill none) (layer "B.Fab"))
    (pad "1" smd roundrect (at -0.7 0 270) (size 0.6 0.8) (layers "B.Cu" "B.Paste" "B.Mask") (roundrect_rratio 0.2)
      (net 11 "GND") (pintype "passive"))
    (pad "2" smd roundrect (at 0.7 0 270) (size 0.6 0.8) (layers "B.Cu" "B.Paste" "B.Mask") (roundrect_rratio 0.2)
      (net 170 "3V3_SSD") (pintype "passive"))
  )

  (footprint "scalenode-cm4-baseboard-footprints:C_0603_1608Metric" (layer "B.Cu")
    (at 174.546 67.352 -90)
    (descr "Capacitor SMD 0603")
    (tags "capacitor 0603")
    (property "Author" "Antmicro")
    (property "Dielectric" "")
    (property "License" "Apache-2.0")
    (property "MPN" "0603YD105KAT2A")
    (property "Manufacturer" "Walsin")
    (property "Sheetfile" "nvme-ssd.kicad_sch")
    (property "Sheetname" "NVMe SSD")
    (property "Val" "1u")
    (property "Voltage" "")
    (property "ki_description" " ")
    (attr smd)
    (fp_text reference "C4" (at -3.143667 -0.504 90) (layer "B.SilkS")
        (effects (font (size 0.7 0.7) (thickness 0.15)) (justify left bottom mirror))
    )
    (fp_text value "C_1u_0603" (at 0 -1.6 90) (layer "B.Fab")
        (effects (font (size 0.7 0.7) (thickness 0.15)) (justify left bottom mirror))
    )
    (fp_text user "License: Apache-2.0" (at -1.682 -5.895 90) (layer "B.Fab") hide
        (effects (font (size 0.7 0.7) (thickness 0.15)) (justify left bottom mirror))
    )
    (fp_text user "Author: Antmicro" (at -1.682 -4.894 90) (layer "B.Fab") hide
        (effects (font (size 0.7 0.7) (thickness 0.15)) (justify left bottom mirror))
    )
    (fp_text user "${REFERENCE}" (at -1.682 -3.895 90) (layer "B.Fab") hide
        (effects (font (size 0.7 0.7) (thickness 0.15)) (justify left bottom mirror))
    )
    (fp_line (start -0.3 -0.3) (end 0.3 -0.3)
      (stroke (width 0.15) (type solid)) (layer "B.SilkS"))
    (fp_line (start -0.3 0.3) (end 0.3 0.3)
      (stroke (width 0.15) (type solid)) (layer "B.SilkS"))
    (fp_rect (start -1.24 0.7) (end 1.24 -0.7)
      (stroke (width 0.05) (type solid)) (fill none) (layer "B.CrtYd"))
    (fp_rect (start -0.8 0.4) (end 0.8 -0.4)
      (stroke (width 0.15) (type solid)) (fill none) (layer "B.Fab"))
    (pad "1" smd roundrect (at -0.7 0 270) (size 0.6 0.8) (layers "B.Cu" "B.Paste" "B.Mask") (roundrect_rratio 0.2)
      (net 11 "GND") (pintype "passive"))
    (pad "2" smd roundrect (at 0.7 0 270) (size 0.6 0.8) (layers "B.Cu" "B.Paste" "B.Mask") (roundrect_rratio 0.2)
      (net 170 "3V3_SSD") (pintype "passive"))
  )

  (footprint "scalenode-cm4-baseboard-footprints:C_0603_1608Metric" (layer "B.Cu")
    (at 176.07 86.148 90)
    (descr "Capacitor SMD 0603")
    (tags "capacitor 0603")
    (property "Author" "Antmicro")
    (property "Dielectric" "")
    (property "License" "Apache-2.0")
    (property "MPN" "0603YC104KAZ2A")
    (property "Manufacturer" "AVX")
    (property "Sheetfile" "nvme-ssd.kicad_sch")
    (property "Sheetname" "NVMe SSD")
    (property "Val" "100n")
    (property "Voltage" "")
    (property "ki_description" " ")
    (attr smd)
    (fp_text reference "C9" (at -3.168667 0.405 90) (layer "B.SilkS")
        (effects (font (size 0.7 0.7) (thickness 0.15)) (justify right bottom mirror))
    )
    (fp_text value "C_100n_0603" (at 0 -1.6 90) (layer "B.Fab")
        (effects (font (size 0.7 0.7) (thickness 0.15)) (justify right bottom mirror))
    )
    (fp_text user "${REFERENCE}" (at -1.682 -3.895 90) (layer "B.Fab") hide
        (effects (font (size 0.7 0.7) (thickness 0.15)) (justify right bottom mirror))
    )
    (fp_text user "Author: Antmicro" (at -1.682 -4.894 90) (layer "B.Fab") hide
        (effects (font (size 0.7 0.7) (thickness 0.15)) (justify right bottom mirror))
    )
    (fp_text user "License: Apache-2.0" (at -1.682 -5.895 90) (layer "B.Fab") hide
        (effects (font (size 0.7 0.7) (thickness 0.15)) (justify right bottom mirror))
    )
    (fp_line (start -0.3 -0.3) (end 0.3 -0.3)
      (stroke (width 0.15) (type solid)) (layer "B.SilkS"))
    (fp_line (start -0.3 0.3) (end 0.3 0.3)
      (stroke (width 0.15) (type solid)) (layer "B.SilkS"))
    (fp_rect (start -1.24 0.7) (end 1.24 -0.7)
      (stroke (width 0.05) (type solid)) (fill none) (layer "B.CrtYd"))
    (fp_rect (start -0.8 0.4) (end 0.8 -0.4)
      (stroke (width 0.15) (type solid)) (fill none) (layer "B.Fab"))
    (pad "1" smd roundrect (at -0.7 0 90) (size 0.6 0.8) (layers "B.Cu" "B.Paste" "B.Mask") (roundrect_rratio 0.2)
      (net 11 "GND") (pintype "passive"))
    (pad "2" smd roundrect (at 0.7 0 90) (size 0.6 0.8) (layers "B.Cu" "B.Paste" "B.Mask") (roundrect_rratio 0.2)
      (net 170 "3V3_SSD") (pintype "passive"))
  )

  (footprint "scalenode-cm4-baseboard-footprints:C_0603_1608Metric" (layer "B.Cu")
    (at 174.546 86.148 90)
    (descr "Capacitor SMD 0603")
    (tags "capacitor 0603")
    (property "Author" "Antmicro")
    (property "Dielectric" "")
    (property "License" "Apache-2.0")
    (property "MPN" "0603YD105KAT2A")
    (property "Manufacturer" "Walsin")
    (property "Sheetfile" "nvme-ssd.kicad_sch")
    (property "Sheetname" "NVMe SSD")
    (property "Val" "1u")
    (property "Voltage" "")
    (property "ki_description" " ")
    (attr smd)
    (fp_text reference "C6" (at -3.168667 0.429 90) (layer "B.SilkS")
        (effects (font (size 0.7 0.7) (thickness 0.15)) (justify right bottom mirror))
    )
    (fp_text value "C_1u_0603" (at 0 -1.6 90) (layer "B.Fab")
        (effects (font (size 0.7 0.7) (thickness 0.15)) (justify right bottom mirror))
    )
    (fp_text user "License: Apache-2.0" (at -1.682 -5.895 90) (layer "B.Fab") hide
        (effects (font (size 0.7 0.7) (thickness 0.15)) (justify right bottom mirror))
    )
    (fp_text user "Author: Antmicro" (at -1.682 -4.894 90) (layer "B.Fab") hide
        (effects (font (size 0.7 0.7) (thickness 0.15)) (justify right bottom mirror))
    )
    (fp_text user "${REFERENCE}" (at -1.682 -3.895 90) (layer "B.Fab") hide
        (effects (font (size 0.7 0.7) (thickness 0.15)) (justify right bottom mirror))
    )
    (fp_line (start -0.3 -0.3) (end 0.3 -0.3)
      (stroke (width 0.15) (type solid)) (layer "B.SilkS"))
    (fp_line (start -0.3 0.3) (end 0.3 0.3)
      (stroke (width 0.15) (type solid)) (layer "B.SilkS"))
    (fp_rect (start -1.24 0.7) (end 1.24 -0.7)
      (stroke (width 0.05) (type solid)) (fill none) (layer "B.CrtYd"))
    (fp_rect (start -0.8 0.4) (end 0.8 -0.4)
      (stroke (width 0.15) (type solid)) (fill none) (layer "B.Fab"))
    (pad "1" smd roundrect (at -0.7 0 90) (size 0.6 0.8) (layers "B.Cu" "B.Paste" "B.Mask") (roundrect_rratio 0.2)
      (net 11 "GND") (pintype "passive"))
    (pad "2" smd roundrect (at 0.7 0 90) (size 0.6 0.8) (layers "B.Cu" "B.Paste" "B.Mask") (roundrect_rratio 0.2)
      (net 170 "3V3_SSD") (pintype "passive"))
  )

  (footprint "scalenode-cm4-baseboard-footprints:C_0805_2012Metric" (layer "B.Cu")
    (at 121.6 87.8)
    (descr "Capacitor SMD 0805")
    (tags "capacitor SMD 0805")
    (property "Author" "Antmicro")
    (property "Dielectric" "")
    (property "License" "Apache-2.0")
    (property "MPN" "0805ZD226MAT2A")
    (property "Manufacturer" "AVX")
    (property "Sheetfile" "supply.kicad_sch")
    (property "Sheetname" "Supply")
    (property "Val" "22u")
    (property "Voltage" "")
    (property "ki_description" " ")
    (attr smd)
    (fp_text reference "C19" (at -1.125 1.825) (layer "B.SilkS")
        (effects (font (size 0.7 0.7) (thickness 0.15)) (justify right bottom mirror))
    )
    (fp_text value "C_22u_0805_10V" (at 0 -1.947) (layer "B.Fab")
        (effects (font (size 0.7 0.7) (thickness 0.15)) (justify right bottom mirror))
    )
    (fp_text user "${REFERENCE}" (at -1.9 -3.947) (layer "B.Fab") hide
        (effects (font (size 0.7 0.7) (thickness 0.15)) (justify right bottom mirror))
    )
    (fp_text user "Author: Antmicro" (at -1.9 -5.947) (layer "B.Fab") hide
        (effects (font (size 0.7 0.7) (thickness 0.15)) (justify right bottom mirror))
    )
    (fp_text user "License: Apache-2.0" (at -1.9 -4.947) (layer "B.Fab") hide
        (effects (font (size 0.7 0.7) (thickness 0.15)) (justify right bottom mirror))
    )
    (fp_line (start -0.3 -0.8) (end 0.3 -0.8)
      (stroke (width 0.15) (type solid)) (layer "B.SilkS"))
    (fp_line (start -0.3 0.8) (end 0.3 0.8)
      (stroke (width 0.15) (type solid)) (layer "B.SilkS"))
    (fp_rect (start -1.9 0.93) (end 1.9 -0.93)
      (stroke (width 0.05) (type solid)) (fill none) (layer "B.CrtYd"))
    (fp_rect (start -0.95 0.675) (end 0.95 -0.675)
      (stroke (width 0.15) (type solid)) (fill none) (layer "B.Fab"))
    (pad "1" smd rect (at -1.05 0) (size 1.2 1.2) (layers "B.Cu" "B.Paste" "B.Mask")
      (net 11 "GND") (pintype "passive"))
    (pad "2" smd rect (at 1.05 0) (size 1.2 1.2) (layers "B.Cu" "B.Paste" "B.Mask")
      (net 170 "3V3_SSD") (pintype "passive"))
  )

  (footprint "scalenode-cm4-baseboard-footprints:C_0402_1005Metric" (layer "B.Cu")
    (at 152.9258 73.7014 -90)
    (descr "Capacitor SMD 0402")
    (tags "capacitor SMD 0402")
    (property "Author" "Antmicro")
    (property "Dielectric" "X5R")
    (property "License" "Apache-2.0")
    (property "MPN" "GRM155R61H104KE14D")
    (property "Manufacturer" "Murata")
    (property "Sheetfile" "interfaces.kicad_sch")
    (property "Sheetname" "Interfaces")
    (property "Val" "100n")
    (property "Voltage" "50V")
    (property "ki_description" " ")
    (attr smd)
    (fp_text reference "C51" (at -3.1514 -0.3492 90) (layer "B.SilkS")
        (effects (font (size 0.7 0.7) (thickness 0.15)) (justify left bottom mirror))
    )
    (fp_text value "C_100n_0402" (at 0 -1.4 90) (layer "B.Fab")
        (effects (font (size 0.7 0.7) (thickness 0.15)) (justify left bottom mirror))
    )
    (fp_text user "License: Apache-2.0" (at -0.932 -5.17 90) (layer "B.Fab") hide
        (effects (font (size 0.7 0.7) (thickness 0.15)) (justify left bottom mirror))
    )
    (fp_text user "${REFERENCE}" (at -0.932 -3.168 90) (layer "B.Fab") hide
        (effects (font (size 0.7 0.7) (thickness 0.15)) (justify left bottom mirror))
    )
    (fp_text user "Author: Antmicro" (at -0.932 -4.17 90) (layer "B.Fab") hide
        (effects (font (size 0.7 0.7) (thickness 0.15)) (justify left bottom mirror))
    )
    (fp_rect (start -0.94 0.47) (end 0.94 -0.47)
      (stroke (width 0.05) (type solid)) (fill none) (layer "B.CrtYd"))
    (fp_rect (start -0.499 0.249) (end 0.499 -0.249)
      (stroke (width 0.15) (type solid)) (fill none) (layer "B.Fab"))
    (pad "1" smd roundrect (at -0.484 0 270) (size 0.59 0.64) (layers "B.Cu" "B.Paste" "B.Mask") (roundrect_rratio 0.25)
      (net 11 "GND") (pintype "passive"))
    (pad "2" smd roundrect (at 0.484 0 270) (size 0.59 0.64) (layers "B.Cu" "B.Paste" "B.Mask") (roundrect_rratio 0.25)
      (net 232 "3V3_RPi") (pintype "passive"))
  )

  (footprint "scalenode-cm4-baseboard-footprints:C_0402_1005Metric" (layer "B.Cu")
    (at 151.9352 73.7014 -90)
    (descr "Capacitor SMD 0402")
    (tags "capacitor SMD 0402")
    (property "Author" "Antmicro")
    (property "Dielectric" "")
    (property "License" "Apache-2.0")
    (property "MPN" "C1005X6S1A105K050BC")
    (property "Manufacturer" "TDK")
    (property "Sheetfile" "interfaces.kicad_sch")
    (property "Sheetname" "Interfaces")
    (property "Val" "1u")
    (property "Voltage" "")
    (property "ki_description" " ")
    (attr smd)
    (fp_text reference "C52" (at -3.2014 -0.3398 90) (layer "B.SilkS")
        (effects (font (size 0.7 0.7) (thickness 0.15)) (justify left bottom mirror))
    )
    (fp_text value "C_1u_0402" (at 0 -1.4 90) (layer "B.Fab")
        (effects (font (size 0.7 0.7) (thickness 0.15)) (justify left bottom mirror))
    )
    (fp_text user "License: Apache-2.0" (at -0.932 -5.17 90) (layer "B.Fab") hide
        (effects (font (size 0.7 0.7) (thickness 0.15)) (justify left bottom mirror))
    )
    (fp_text user "${REFERENCE}" (at -0.932 -3.168 90) (layer "B.Fab") hide
        (effects (font (size 0.7 0.7) (thickness 0.15)) (justify left bottom mirror))
    )
    (fp_text user "Author: Antmicro" (at -0.932 -4.17 90) (layer "B.Fab") hide
        (effects (font (size 0.7 0.7) (thickness 0.15)) (justify left bottom mirror))
    )
    (fp_rect (start -0.94 0.47) (end 0.94 -0.47)
      (stroke (width 0.05) (type solid)) (fill none) (layer "B.CrtYd"))
    (fp_rect (start -0.499 0.249) (end 0.499 -0.249)
      (stroke (width 0.15) (type solid)) (fill none) (layer "B.Fab"))
    (pad "1" smd roundrect (at -0.484 0 270) (size 0.59 0.64) (layers "B.Cu" "B.Paste" "B.Mask") (roundrect_rratio 0.25)
      (net 11 "GND") (pintype "passive"))
    (pad "2" smd roundrect (at 0.484 0 270) (size 0.59 0.64) (layers "B.Cu" "B.Paste" "B.Mask") (roundrect_rratio 0.25)
      (net 232 "3V3_RPi") (pintype "passive"))
  )

  (footprint "scalenode-cm4-baseboard-footprints:MicroSD_Amphenol_1140084168" (layer "B.Cu")
    (at 81.604 85.024 90)
    (property "Author" "Antmicro")
    (property "License" "Apache-2.0")
    (property "MPN" "1140084168")
    (property "Manufacturer" "Amphenol")
    (property "Sheetfile" "interfaces.kicad_sch")
    (property "Sheetname" "Interfaces")
    (property "ki_description" "Micro SD Right Angle, PCB Mount")
    (attr smd)
    (fp_text reference "J4" (at 5.524 7.396 270) (layer "B.SilkS")
        (effects (font (size 0.7 0.7) (thickness 0.15)) (justify left bottom mirror))
    )
    (fp_text value "MicroSD_1140084168" (at 0.894 11.006 270) (layer "B.Fab")
        (effects (font (size 0.7 0.7) (thickness 0.15)) (justify left bottom mirror))
    )
    (fp_text user "${REFERENCE}" (at -6.925 -12.774 270) (layer "B.Fab") hide
        (effects (font (size 0.7 0.7) (thickness 0.15)) (justify left bottom mirror))
    )
    (fp_text user "Author: Antmicro" (at -6.925 -14.1 270) (layer "B.Fab") hide
        (effects (font (size 0.7 0.7) (thickness 0.15)) (justify left bottom mirror))
    )
    (fp_text user "License: Apache-2.0" (at -6.925 -15.4 270) (layer "B.Fab") hide
        (effects (font (size 0.7 0.7) (thickness 0.15)) (justify left bottom mirror))
    )
    (fp_line (start -6.3 1.6) (end -6.3 -4.2)
      (stroke (width 0.15) (type solid)) (layer "B.SilkS"))
    (fp_line (start -6.3 6.1) (end -6.3 4.7)
      (stroke (width 0.15) (type solid)) (layer "B.SilkS"))
    (fp_line (start 4.8 6.1) (end -6.3 6.1)
      (stroke (width 0.15) (type solid)) (layer "B.SilkS"))
    (fp_line (start 6.2 -4.2) (end 6.2 2.2)
      (stroke (width 0.15) (type solid)) (layer "B.SilkS"))
    (fp_line (start 6.2 4) (end 6.2 6.1)
      (stroke (width 0.15) (type solid)) (layer "B.SilkS"))
    (fp_line (start 6.2 6.1) (end 6.1 6.1)
      (stroke (width 0.15) (type solid)) (layer "B.SilkS"))
    (fp_rect (start -6.5 6.3) (end 6.4 -6.2)
      (stroke (width 0.05) (type solid)) (fill none) (layer "B.CrtYd"))
    (fp_line (start -5.6 -5.8) (end -5.6 -9.5)
      (stroke (width 0.12) (type solid)) (layer "B.Fab"))
    (fp_line (start -5.1 -9.1) (end -5.6 -9.2)
      (stroke (width 0.12) (type solid)) (layer "B.Fab"))
    (fp_line (start -5.1 -8.8) (end -5.6 -8.9)
      (stroke (width 0.12) (type solid)) (layer "B.Fab"))
    (fp_line (start -3.8 -8.8) (end -5.1 -9.1)
      (stroke (width 0.12) (type solid)) (layer "B.Fab"))
    (fp_line (start -3.8 -8.5) (end -5.1 -8.8)
      (stroke (width 0.12) (type solid)) (layer "B.Fab"))
    (fp_line (start -2.3 -8.6) (end -3.8 -8.8)
      (stroke (width 0.12) (type solid)) (layer "B.Fab"))
    (fp_line (start -2.3 -8.3) (end -3.8 -8.5)
      (stroke (width 0.12) (type solid)) (layer "B.Fab"))
    (fp_line (start -1 -8.5) (end -2.3 -8.6)
      (stroke (width 0.12) (type solid)) (layer "B.Fab"))
    (fp_line (start -1 -8.2) (end -2.3 -8.3)
      (stroke (width 0.12) (type solid)) (layer "B.Fab"))
    (fp_line (start 0.8 -8.5) (end -1 -8.5)
      (stroke (width 0.12) (type solid)) (layer "B.Fab"))
    (fp_line (start 0.8 -8.2) (end -1 -8.2)
      (stroke (width 0.12) (type solid)) (layer "B.Fab"))
    (fp_line (start 2.1 -8.6) (end 0.8 -8.5)
      (stroke (width 0.12) (type solid)) (layer "B.Fab"))
    (fp_line (start 2.1 -8.3) (end 0.8 -8.2)
      (stroke (width 0.12) (type solid)) (layer "B.Fab"))
    (fp_line (start 2.9 -8.7) (end 2.1 -8.6)
      (stroke (width 0.12) (type solid)) (layer "B.Fab"))
    (fp_line (start 2.9 -8.4) (end 2.1 -8.3)
      (stroke (width 0.12) (type solid)) (layer "B.Fab"))
    (fp_line (start 4.6 -9) (end 2.9 -8.7)
      (stroke (width 0.12) (type solid)) (layer "B.Fab"))
    (fp_line (start 4.6 -8.7) (end 2.9 -8.4)
      (stroke (width 0.12) (type solid)) (layer "B.Fab"))
    (fp_line (start 4.9 -10) (end -5.1 -10)
      (stroke (width 0.12) (type solid)) (layer "B.Fab"))
    (fp_line (start 5.4 -9.5) (end 5.4 -5.8)
      (stroke (width 0.12) (type solid)) (layer "B.Fab"))
    (fp_line (start 5.4 -9.2) (end 4.6 -9)
      (stroke (width 0.12) (type solid)) (layer "B.Fab"))
    (fp_line (start 5.4 -8.9) (end 4.6 -8.7)
      (stroke (width 0.12) (type solid)) (layer "B.Fab"))
    (fp_rect (start -6 5.8) (end 5.999 -5.799)
      (stroke (width 0.1) (type solid)) (fill none) (layer "B.Fab"))
    (fp_arc (start -5.6 -9.5) (mid -5.453553 -9.853553) (end -5.1 -10)
      (stroke (width 0.12) (type solid)) (layer "B.Fab"))
    (fp_arc (start 4.9 -10) (mid 5.253553 -9.853553) (end 5.4 -9.5)
      (stroke (width 0.12) (type solid)) (layer "B.Fab"))
    (pad "1" smd rect (at 3.124 -5.254 270) (size 0.7 1.75) (layers "B.Cu" "B.Paste" "B.Mask")
      (net 33 "SD_DAT2") (pinfunction "DAT2") (pintype "bidirectional"))
    (pad "2" smd rect (at 2.024 -5.254 270) (size 0.7 1.75) (layers "B.Cu" "B.Paste" "B.Mask")
      (net 32 "SD_DAT3") (pinfunction "CD/DAT3") (pintype "bidirectional"))
    (pad "3" smd rect (at 0.925 -5.254 270) (size 0.7 1.75) (layers "B.Cu" "B.Paste" "B.Mask")
      (net 31 "SD_CMD") (pinfunction "CMD") (pintype "bidirectional"))
    (pad "4" smd rect (at -0.176 -5.254 270) (size 0.7 1.75) (layers "B.Cu" "B.Paste" "B.Mask")
      (net 232 "3V3_RPi") (pinfunction "VDD") (pintype "power_in"))
    (pad "5" smd rect (at -1.276 -5.254 270) (size 0.7 1.75) (layers "B.Cu" "B.Paste" "B.Mask")
      (net 30 "SD_CLK") (pinfunction "CLK") (pintype "output"))
    (pad "6" smd rect (at -2.375 -5.254 270) (size 0.7 1.75) (layers "B.Cu" "B.Paste" "B.Mask")
      (net 11 "GND") (pinfunction "VSS") (pintype "power_in"))
    (pad "7" smd rect (at -3.476 -5.254 270) (size 0.7 1.75) (layers "B.Cu" "B.Paste" "B.Mask")
      (net 29 "SD_DAT0") (pinfunction "DAT0") (pintype "bidirectional"))
    (pad "8" smd rect (at -4.576 -5.254 270) (size 0.7 1.75) (layers "B.Cu" "B.Paste" "B.Mask")
      (net 28 "SD_DAT1") (pinfunction "DAT1") (pintype "bidirectional"))
    (pad "9" smd rect (at -5.675 4.05 90) (size 1.4 1) (layers "B.Cu" "B.Paste" "B.Mask")
      (net 201 "Net-(J4-CD1)") (pinfunction "CD1") (pintype "passive"))
    (pad "10" smd rect (at 5.424 5.531) (size 1.4 1) (layers "B.Cu" "B.Paste" "B.Mask")
      (net 11 "GND") (pinfunction "CD2") (pintype "passive"))
    (pad "SH" smd rect (at -5.976 2.48) (size 1.5 0.8) (layers "B.Cu" "B.Paste" "B.Mask")
      (net 11 "GND") (pinfunction "Shell") (pintype "passive"))
    (pad "SH" smd rect (at -5.776 -5.129 90) (size 1.3 1.5) (layers "B.Cu" "B.Paste" "B.Mask")
      (net 11 "GND") (pinfunction "Shell") (pintype "passive"))
    (pad "SH" smd rect (at 5.575 -5.129 90) (size 1.5 1.5) (layers "B.Cu" "B.Paste" "B.Mask")
      (net 11 "GND") (pinfunction "Shell") (pintype "passive"))
    (pad "SH" smd rect (at 5.874 3.13) (size 1.5 0.8) (layers "B.Cu" "B.Paste" "B.Mask")
      (net 11 "GND") (pinfunction "Shell") (pintype "passive"))
  )

  (footprint "scalenode-cm4-baseboard-footprints:R_1206_3216Metric" (layer "B.Cu")
    (at 103.818 59.13)
    (property "Author" "Antmicro")
    (property "Current" "2A")
    (property "DNP" "DNP")
    (property "License" "Apache-2.0")
    (property "MPN" "MCMR12X000_PTL")
    (property "Manufacturer" "Multicomp Pro")
    (property "Sheetfile" "poe.kicad_sch")
    (property "Sheetname" "PoE")
    (property "Tolerance" "~")
    (property "Val" "0R")
    (property "dnp" "")
    (property "exclude_from_bom" "")
    (property "ki_description" "0R resistor in 1206 package with unspecified tolerance")
    (attr exclude_from_pos_files exclude_from_bom)
    (fp_text reference "R17" (at 0.982 -1.38 180) (layer "B.SilkS")
        (effects (font (size 0.7 0.7) (thickness 0.15)) (justify left bottom mirror))
    )
    (fp_text value "R_0R_1206" (at 1.257 1.87 180) (layer "B.Fab")
        (effects (font (size 0.7 0.7) (thickness 0.15)) (justify left bottom mirror))
    )
    (fp_text user "License: Apache-2.0" (at -2.401 -6.3 180) (layer "B.Fab") hide
        (effects (font (size 0.7 0.7) (thickness 0.15)) (justify left bottom mirror))
    )
    (fp_text user "Author: Antmicro" (at -2.401 -4.899 180) (layer "B.Fab") hide
        (effects (font (size 0.7 0.7) (thickness 0.15)) (justify left bottom mirror))
    )
    (fp_text user "${REFERENCE}" (at -2.401 -3.5 180) (layer "B.Fab") hide
        (effects (font (size 0.7 0.7) (thickness 0.15)) (justify left bottom mirror))
    )
    (fp_line (start 0 -0.9) (end -0.5 -0.9)
      (stroke (width 0.15) (type solid)) (layer "B.SilkS"))
    (fp_line (start 0 -0.9) (end 0.498 -0.9)
      (stroke (width 0.15) (type solid)) (layer "B.SilkS"))
    (fp_line (start 0 0.902) (end -0.5 0.902)
      (stroke (width 0.15) (type solid)) (layer "B.SilkS"))
    (fp_line (start 0 0.902) (end 0.498 0.902)
      (stroke (width 0.15) (type solid)) (layer "B.SilkS"))
    (fp_rect (start -2.25 1.05) (end 2.25 -1.05)
      (stroke (width 0.05) (type solid)) (fill none) (layer "B.CrtYd"))
    (fp_line (start -1.601 -0.8) (end 1.6 -0.8)
      (stroke (width 0.15) (type solid)) (layer "B.Fab"))
    (fp_line (start -1.601 0.802) (end -1.601 -0.8)
      (stroke (width 0.15) (type solid)) (layer "B.Fab"))
    (fp_line (start -1.601 0.802) (end 1.6 0.802)
      (stroke (width 0.15) (type solid)) (layer "B.Fab"))
    (fp_line (start 1.6 0.802) (end 1.6 -0.8)
      (stroke (width 0.15) (type solid)) (layer "B.Fab"))
    (pad "1" smd roundrect (at -1.5 0) (size 1.2 1.8) (layers "B.Cu" "B.Paste" "B.Mask") (roundrect_rratio 0.15)
      (net 230 "Earth") (pintype "passive"))
    (pad "2" smd roundrect (at 1.499 0) (size 1.2 1.8) (layers "B.Cu" "B.Paste" "B.Mask") (roundrect_rratio 0.15)
      (net 11 "GND") (pintype "passive"))
  )

  (footprint "scalenode-cm4-baseboard-footprints:R_0402_1005Metric" (layer "B.Cu")
    (at 109.387 62.638 -90)
    (descr "Resistor SMD 0402")
    (tags "resistor SMD 0402")
    (property "Author" "Antmicro")
    (property "License" "Apache-2.0")
    (property "MPN" "CR0402-FX-75R0GLF")
    (property "Manufacturer" "Bourns")
    (property "Sheetfile" "poe.kicad_sch")
    (property "Sheetname" "PoE")
    (property "Tolerance" "1%")
    (property "Val" "75R")
    (property "ki_description" "75R resistor in 0402 package with 1% tolerance")
    (attr smd)
    (fp_text reference "R30" (at -1.088 -1.488 90) (layer "B.SilkS")
        (effects (font (size 0.7 0.7) (thickness 0.15)) (justify left bottom mirror))
    )
    (fp_text value "R_75R_0402" (at 0 -1.4 90) (layer "B.Fab")
        (effects (font (size 0.7 0.7) (thickness 0.15)) (justify left bottom mirror))
    )
    (fp_text user "Author: Antmicro" (at -0.95 -4.169 90) (layer "B.Fab") hide
        (effects (font (size 0.7 0.7) (thickness 0.15)) (justify left bottom mirror))
    )
    (fp_text user "${REFERENCE}" (at -0.95 -3.168 90) (layer "B.Fab") hide
        (effects (font (size 0.7 0.7) (thickness 0.15)) (justify left bottom mirror))
    )
    (fp_text user "License: Apache-2.0" (at -0.95 -5.169 90) (layer "B.Fab") hide
        (effects (font (size 0.7 0.7) (thickness 0.15)) (justify left bottom mirror))
    )
    (fp_rect (start -0.95 0.48) (end 0.95 -0.48)
      (stroke (width 0.05) (type solid)) (fill none) (layer "B.CrtYd"))
    (fp_rect (start -0.5 0.25) (end 0.5 -0.25)
      (stroke (width 0.15) (type solid)) (fill none) (layer "B.Fab"))
    (pad "1" smd roundrect (at -0.485 0 270) (size 0.59 0.64) (layers "B.Cu" "B.Paste" "B.Mask") (roundrect_rratio 0.25)
      (net 175 "Net-(C25-Pad2)") (pintype "passive"))
    (pad "2" smd roundrect (at 0.485 0 270) (size 0.59 0.64) (layers "B.Cu" "B.Paste" "B.Mask") (roundrect_rratio 0.25)
      (net 228 "Net-(L3-TCT4)") (pintype "passive"))
  )

  (footprint "scalenode-cm4-baseboard-footprints:C_1210_3225Metric" (layer "B.Cu")
    (at 109.406 59.511 180)
    (descr "Capacitor SMD 1210")
    (tags "capacitor SMD 1210")
    (property "Author" "Antmicro")
    (property "Dielectric" "")
    (property "License" "Apache-2.0")
    (property "MPN" "C1210C102KGRACTU")
    (property "Manufacturer" "KEMET")
    (property "Sheetfile" "poe.kicad_sch")
    (property "Sheetname" "PoE")
    (property "Val" "1n")
    (property "Voltage" "2kV")
    (property "ki_description" " ")
    (attr smd)
    (fp_text reference "C25" (at -0.969 1.761) (layer "B.SilkS")
        (effects (font (size 0.7 0.7) (thickness 0.15)) (justify left bottom mirror))
    )
    (fp_text value "C_1n_1210_2kV" (at 0 -2.749) (layer "B.Fab")
        (effects (font (size 0.7 0.7) (thickness 0.15)) (justify left bottom mirror))
    )
    (fp_text user "License: Apache-2.0" (at -2.1 -6.749) (layer "B.Fab") hide
        (effects (font (size 0.7 0.7) (thickness 0.15)) (justify left bottom mirror))
    )
    (fp_text user "Author: Antmicro" (at -2.1 -5.749) (layer "B.Fab") hide
        (effects (font (size 0.7 0.7) (thickness 0.15)) (justify left bottom mirror))
    )
    (fp_text user "${REFERENCE}" (at -2.1 -4.749) (layer "B.Fab") hide
        (effects (font (size 0.7 0.7) (thickness 0.15)) (justify left bottom mirror))
    )
    (fp_line (start -0.3 -1.39) (end 0.3 -1.39)
      (stroke (width 0.15) (type solid)) (layer "B.SilkS"))
    (fp_line (start -0.3 1.39) (end 0.3 1.39)
      (stroke (width 0.15) (type solid)) (layer "B.SilkS"))
    (fp_rect (start -2.1 1.75) (end 2.1 -1.75)
      (stroke (width 0.05) (type solid)) (fill none) (layer "B.CrtYd"))
    (fp_rect (start -1.6 1.25) (end 1.6 -1.25)
      (stroke (width 0.15) (type solid)) (fill none) (layer "B.Fab"))
    (pad "1" smd rect (at -1.145 0 180) (size 1.52 3.05) (layers "B.Cu" "B.Paste" "B.Mask")
      (net 11 "GND") (pintype "passive"))
    (pad "2" smd rect (at 1.145 0 180) (size 1.52 3.05) (layers "B.Cu" "B.Paste" "B.Mask")
      (net 175 "Net-(C25-Pad2)") (pintype "passive"))
  )

  (footprint "scalenode-cm4-baseboard-footprints:R_0402_1005Metric" (layer "B.Cu")
    (at 154.4828 73.6346 -90)
    (descr "Resistor SMD 0402")
    (tags "resistor SMD 0402")
    (property "Author" "Antmicro")
    (property "License" "Apache-2.0")
    (property "MPN" "CR0402-FX-1002GLF")
    (property "Manufacturer" "Bourns")
    (property "Sheetfile" "interfaces.kicad_sch")
    (property "Sheetname" "Interfaces")
    (property "Tolerance" "1%")
    (property "Val" "10k")
    (property "ki_description" "10k resistor in 0402 package with 1% tolerance")
    (attr smd)
    (fp_text reference "R55" (at 0.9654 -0.4422 90) (layer "B.SilkS")
        (effects (font (size 0.7 0.7) (thickness 0.15)) (justify left bottom mirror))
    )
    (fp_text value "R_10k_0402" (at 0 -1.4 90) (layer "B.Fab")
        (effects (font (size 0.7 0.7) (thickness 0.15)) (justify left bottom mirror))
    )
    (fp_text user "Author: Antmicro" (at -0.95 -4.169 90) (layer "B.Fab") hide
        (effects (font (size 0.7 0.7) (thickness 0.15)) (justify left bottom mirror))
    )
    (fp_text user "License: Apache-2.0" (at -0.95 -5.169 90) (layer "B.Fab") hide
        (effects (font (size 0.7 0.7) (thickness 0.15)) (justify left bottom mirror))
    )
    (fp_text user "${REFERENCE}" (at -0.95 -3.168 90) (layer "B.Fab") hide
        (effects (font (size 0.7 0.7) (thickness 0.15)) (justify left bottom mirror))
    )
    (fp_rect (start -0.95 0.48) (end 0.95 -0.48)
      (stroke (width 0.05) (type solid)) (fill none) (layer "B.CrtYd"))
    (fp_rect (start -0.5 0.25) (end 0.5 -0.25)
      (stroke (width 0.15) (type solid)) (fill none) (layer "B.Fab"))
    (pad "1" smd roundrect (at -0.485 0 270) (size 0.59 0.64) (layers "B.Cu" "B.Paste" "B.Mask") (roundrect_rratio 0.25)
      (net 264 "Net-(U5-~{OE})") (pintype "passive"))
    (pad "2" smd roundrect (at 0.485 0 270) (size 0.59 0.64) (layers "B.Cu" "B.Paste" "B.Mask") (roundrect_rratio 0.25)
      (net 11 "GND") (pintype "passive"))
  )

  (footprint "scalenode-cm4-baseboard-footprints:R_0402_1005Metric" (layer "B.Cu")
    (at 108.3 69.659 -90)
    (descr "Resistor SMD 0402")
    (tags "resistor SMD 0402")
    (property "Author" "Antmicro")
    (property "License" "Apache-2.0")
    (property "MPN" "CR0402-FX-75R0GLF")
    (property "Manufacturer" "Bourns")
    (property "Sheetfile" "poe.kicad_sch")
    (property "Sheetname" "PoE")
    (property "Tolerance" "1%")
    (property "Val" "75R")
    (property "ki_description" "75R resistor in 0402 package with 1% tolerance")
    (attr smd)
    (fp_text reference "R27" (at -1.059 0.625 90) (layer "B.SilkS")
        (effects (font (size 0.7 0.7) (thickness 0.15)) (justify left bottom mirror))
    )
    (fp_text value "R_75R_0402" (at 0 -1.4 90) (layer "B.Fab")
        (effects (font (size 0.7 0.7) (thickness 0.15)) (justify left bottom mirror))
    )
    (fp_text user "Author: Antmicro" (at -0.95 -4.169 90) (layer "B.Fab") hide
        (effects (font (size 0.7 0.7) (thickness 0.15)) (justify left bottom mirror))
    )
    (fp_text user "License: Apache-2.0" (at -0.95 -5.169 90) (layer "B.Fab") hide
        (effects (font (size 0.7 0.7) (thickness 0.15)) (justify left bottom mirror))
    )
    (fp_text user "${REFERENCE}" (at -0.95 -3.168 90) (layer "B.Fab") hide
        (effects (font (size 0.7 0.7) (thickness 0.15)) (justify left bottom mirror))
    )
    (fp_rect (start -0.95 0.48) (end 0.95 -0.48)
      (stroke (width 0.05) (type solid)) (fill none) (layer "B.CrtYd"))
    (fp_rect (start -0.5 0.25) (end 0.5 -0.25)
      (stroke (width 0.15) (type solid)) (fill none) (layer "B.Fab"))
    (pad "1" smd roundrect (at -0.485 0 270) (size 0.59 0.64) (layers "B.Cu" "B.Paste" "B.Mask") (roundrect_rratio 0.25)
      (net 175 "Net-(C25-Pad2)") (pintype "passive"))
    (pad "2" smd roundrect (at 0.485 0 270) (size 0.59 0.64) (layers "B.Cu" "B.Paste" "B.Mask") (roundrect_rratio 0.25)
      (net 222 "Net-(L3-TCT1)") (pintype "passive"))
  )

  (footprint "scalenode-cm4-baseboard-footprints:TSOT23-6" (layer "B.Cu")
    (at 132 87 180)
    (property "Author" "Antmicro")
    (property "License" "Apache-2.0")
    (property "MPN" "AP62301WU-7")
    (property "Manufacturer" "Diodes Incorporated")
    (property "Sheetfile" "supply.kicad_sch")
    (property "Sheetname" "Supply")
    (attr smd)
    (fp_text reference "U2" (at -1.98 -1.85 180) (layer "B.SilkS")
        (effects (font (size 0.7 0.7) (thickness 0.15)) (justify right bottom mirror))
    )
    (fp_text value "AP62301_TSOT" (at -0.002 -2.91) (layer "B.Fab")
        (effects (font (size 0.7 0.7) (thickness 0.15)) (justify left bottom mirror))
    )
    (fp_text user "Author: Antmicro" (at -1.893 -7.368) (layer "B.Fab") hide
        (effects (font (size 0.7 0.7) (thickness 0.15)) (justify left bottom mirror))
    )
    (fp_text user "License: Apache-2.0" (at -2.231 -4.91) (layer "B.Fab") hide
        (effects (font (size 0.7 0.7) (thickness 0.15)) (justify left bottom mirror))
    )
    (fp_text user "${REFERENCE}" (at -2.231 -6.11) (layer "B.Fab") hide
        (effects (font (size 0.7 0.7) (thickness 0.15)) (justify left bottom mirror))
    )
    (fp_line (start -1.4805 -0.725) (end -1.4795 0.725)
      (stroke (width 0.15) (type solid)) (layer "B.SilkS"))
    (fp_line (start -1.4805 -0.725) (end -1.3905 -0.725)
      (stroke (width 0.15) (type solid)) (layer "B.SilkS"))
    (fp_line (start -1.4795 0.725) (end -1.3905 0.725)
      (stroke (width 0.15) (type solid)) (layer "B.SilkS"))
    (fp_line (start 1.479 -0.73) (end 1.38 -0.73)
      (stroke (width 0.15) (type solid)) (layer "B.SilkS"))
    (fp_line (start 1.48 0.72) (end 1.38 0.72)
      (stroke (width 0.15) (type solid)) (layer "B.SilkS"))
    (fp_line (start 1.48 0.72) (end 1.479 -0.73)
      (stroke (width 0.15) (type solid)) (layer "B.SilkS"))
    (fp_circle (center -1.499 -1.236) (end -1.45 -1.236)
      (stroke (width 0.15) (type solid)) (fill solid) (layer "B.SilkS"))
    (fp_rect (start -1.65 1.61) (end 1.65 -1.61)
      (stroke (width 0.05) (type solid)) (fill none) (layer "B.CrtYd"))
    (fp_line (start -1.527 -0.491) (end -1.527 0.833)
      (stroke (width 0.15) (type solid)) (layer "B.Fab"))
    (fp_line (start -1.527 -0.491) (end -1.102 -0.916)
      (stroke (width 0.15) (type solid)) (layer "B.Fab"))
    (fp_line (start -1.527 0.833) (end 1.523 0.833)
      (stroke (width 0.15) (type solid)) (layer "B.Fab"))
    (fp_line (start -1.102 -0.916) (end 1.523 -0.916)
      (stroke (width 0.15) (type solid)) (layer "B.Fab"))
    (fp_line (start 1.523 0.833) (end 1.523 -0.916)
      (stroke (width 0.15) (type solid)) (layer "B.Fab"))
    (pad "1" smd rect (at -0.952 -1.18 180) (size 0.7 0.8) (layers "B.Cu" "B.Paste" "B.Mask")
      (net 11 "GND") (pinfunction "GND") (pintype "power_in"))
    (pad "2" smd rect (at -0.001 -1.18 180) (size 0.7 0.8) (layers "B.Cu" "B.Paste" "B.Mask")
      (net 19 "Net-(U2-SW)") (pinfunction "SW") (pintype "power_out"))
    (pad "3" smd rect (at 0.947 -1.18 180) (size 0.7 0.8) (layers "B.Cu" "B.Paste" "B.Mask")
      (net 12 "VCC5V0") (pinfunction "VIN") (pintype "power_in"))
    (pad "4" smd rect (at 0.947 1.18 180) (size 0.7 0.8) (layers "B.Cu" "B.Paste" "B.Mask")
      (net 252 "Net-(U2-FB)") (pinfunction "FB") (pintype "input"))
    (pad "5" smd rect (at -0.001 1.18 180) (size 0.7 0.8) (layers "B.Cu" "B.Paste" "B.Mask")
      (net 270 "Net-(U2-EN)") (pinfunction "EN") (pintype "input"))
    (pad "6" smd rect (at -0.952 1.18 180) (size 0.7 0.8) (layers "B.Cu" "B.Paste" "B.Mask")
      (net 22 "Net-(U2-BST)") (pinfunction "BST") (pintype "output"))
  )

  (footprint "scalenode-cm4-baseboard-footprints:R_0402_1005Metric" (layer "B.Cu")
    (at 109.337 69.661 -90)
    (descr "Resistor SMD 0402")
    (tags "resistor SMD 0402")
    (property "Author" "Antmicro")
    (property "License" "Apache-2.0")
    (property "MPN" "CR0402-FX-75R0GLF")
    (property "Manufacturer" "Bourns")
    (property "Sheetfile" "poe.kicad_sch")
    (property "Sheetname" "PoE")
    (property "Tolerance" "1%")
    (property "Val" "75R")
    (property "ki_description" "75R resistor in 0402 package with 1% tolerance")
    (attr smd)
    (fp_text reference "R28" (at -1.136 -1.463 90) (layer "B.SilkS")
        (effects (font (size 0.7 0.7) (thickness 0.15)) (justify left bottom mirror))
    )
    (fp_text value "R_75R_0402" (at 0 -1.4 90) (layer "B.Fab")
        (effects (font (size 0.7 0.7) (thickness 0.15)) (justify left bottom mirror))
    )
    (fp_text user "License: Apache-2.0" (at -0.95 -5.169 90) (layer "B.Fab") hide
        (effects (font (size 0.7 0.7) (thickness 0.15)) (justify left bottom mirror))
    )
    (fp_text user "Author: Antmicro" (at -0.95 -4.169 90) (layer "B.Fab") hide
        (effects (font (size 0.7 0.7) (thickness 0.15)) (justify left bottom mirror))
    )
    (fp_text user "${REFERENCE}" (at -0.95 -3.168 90) (layer "B.Fab") hide
        (effects (font (size 0.7 0.7) (thickness 0.15)) (justify left bottom mirror))
    )
    (fp_rect (start -0.95 0.48) (end 0.95 -0.48)
      (stroke (width 0.05) (type solid)) (fill none) (layer "B.CrtYd"))
    (fp_rect (start -0.5 0.25) (end 0.5 -0.25)
      (stroke (width 0.15) (type solid)) (fill none) (layer "B.Fab"))
    (pad "1" smd roundrect (at -0.485 0 270) (size 0.59 0.64) (layers "B.Cu" "B.Paste" "B.Mask") (roundrect_rratio 0.25)
      (net 175 "Net-(C25-Pad2)") (pintype "passive"))
    (pad "2" smd roundrect (at 0.485 0 270) (size 0.59 0.64) (layers "B.Cu" "B.Paste" "B.Mask") (roundrect_rratio 0.25)
      (net 223 "Net-(L3-TCT2)") (pintype "passive"))
  )

  (footprint "scalenode-cm4-baseboard-footprints:R_0402_1005Metric" (layer "B.Cu")
    (at 109.39 66.496 -90)
    (descr "Resistor SMD 0402")
    (tags "resistor SMD 0402")
    (property "Author" "Antmicro")
    (property "License" "Apache-2.0")
    (property "MPN" "CR0402-FX-75R0GLF")
    (property "Manufacturer" "Bourns")
    (property "Sheetfile" "poe.kicad_sch")
    (property "Sheetname" "PoE")
    (property "Tolerance" "1%")
    (property "Val" "75R")
    (property "ki_description" "75R resistor in 0402 package with 1% tolerance")
    (attr smd)
    (fp_text reference "R29" (at -1.096 -1.46 -90) (layer "B.SilkS")
        (effects (font (size 0.7 0.7) (thickness 0.15)) (justify left bottom mirror))
    )
    (fp_text value "R_75R_0402" (at 0 -1.4 90) (layer "B.Fab")
        (effects (font (size 0.7 0.7) (thickness 0.15)) (justify left bottom mirror))
    )
    (fp_text user "Author: Antmicro" (at -0.95 -4.169 90) (layer "B.Fab") hide
        (effects (font (size 0.7 0.7) (thickness 0.15)) (justify left bottom mirror))
    )
    (fp_text user "License: Apache-2.0" (at -0.95 -5.169 90) (layer "B.Fab") hide
        (effects (font (size 0.7 0.7) (thickness 0.15)) (justify left bottom mirror))
    )
    (fp_text user "${REFERENCE}" (at -0.95 -3.168 90) (layer "B.Fab") hide
        (effects (font (size 0.7 0.7) (thickness 0.15)) (justify left bottom mirror))
    )
    (fp_rect (start -0.95 0.48) (end 0.95 -0.48)
      (stroke (width 0.05) (type solid)) (fill none) (layer "B.CrtYd"))
    (fp_rect (start -0.5 0.25) (end 0.5 -0.25)
      (stroke (width 0.15) (type solid)) (fill none) (layer "B.Fab"))
    (pad "1" smd roundrect (at -0.485 0 270) (size 0.59 0.64) (layers "B.Cu" "B.Paste" "B.Mask") (roundrect_rratio 0.25)
      (net 175 "Net-(C25-Pad2)") (pintype "passive"))
    (pad "2" smd roundrect (at 0.485 0 270) (size 0.59 0.64) (layers "B.Cu" "B.Paste" "B.Mask") (roundrect_rratio 0.25)
      (net 224 "Net-(L3-TCT3)") (pintype "passive"))
  )

  (footprint "scalenode-cm4-baseboard-footprints:Spacer_Drill1mm_H4mm_97730406332R" locked (layer "B.Cu")
    (at 104.59 76.877)
    (property "Author" "Antmicro")
    (property "License" "Apache-2.0")
    (property "MPN" "97730406332R ")
    (property "Manufacturer" "Würth Elektronik")
    (property "Sheetfile" "nvme-ssd.kicad_sch")
    (property "Sheetname" "NVMe SSD")
    (attr smd)
    (fp_text reference "SP6" (at 1.19 -2.047 unlocked) (layer "B.SilkS")
        (effects (font (size 0.7 0.7) (thickness 0.15)) (justify left bottom mirror))
    )
    (fp_text value "Spacer_Drill1mm_H4mm_97730406332R" (at 5.183069 1.377434 180 unlocked) (layer "B.Fab")
        (effects (font (size 0.7 0.7) (thickness 0.15)) (justify left bottom mirror))
    )
    (fp_text user "Author: Antmicro" (at 5.259356 -1.214823) (layer "B.Fab") hide
        (effects (font (size 0.7 0.7) (thickness 0.15)) (justify right bottom mirror))
    )
    (fp_text user "License: Apache-2.0" (at 5.259356 -2.414823) (layer "B.Fab") hide
        (effects (font (size 0.7 0.7) (thickness 0.15)) (justify right bottom mirror))
    )
    (fp_text user "${REFERENCE}" (at 5.259356 -0.014823) (layer "B.Fab") hide
        (effects (font (size 0.7 0.7) (thickness 0.15)) (justify right bottom mirror))
    )
    (fp_line (start -1.849 -0.569) (end -1.849 0.579)
      (stroke (width 0.12) (type solid)) (layer "B.Paste"))
    (fp_line (start -1.748 -0.819) (end -1.748 0.83)
      (stroke (width 0.12) (type solid)) (layer "B.Paste"))
    (fp_line (start -1.65 -0.998) (end -1.65 1.024)
      (stroke (width 0.12) (type solid)) (layer "B.Paste"))
    (fp_line (start -1.549 -1.149) (end -1.549 1.159)
      (stroke (width 0.12) (type solid)) (layer "B.Paste"))
    (fp_line (start -1.448 -1.274) (end -1.448 1.275)
      (stroke (width 0.12) (type solid)) (layer "B.Paste"))
    (fp_line (start -1.349 -1.375) (end -1.349 1.374)
      (stroke (width 0.12) (type solid)) (layer "B.Paste"))
    (fp_line (start -1.248 -1.476) (end -1.248 1.468)
      (stroke (width 0.12) (type solid)) (layer "B.Paste"))
    (fp_line (start -1.15 -1.551) (end -1.15 1.55)
      (stroke (width 0.12) (type solid)) (layer "B.Paste"))
    (fp_line (start -1.049 -1.625) (end -1.049 1.624)
      (stroke (width 0.12) (type solid)) (layer "B.Paste"))
    (fp_line (start -0.95 -1.676) (end -0.95 1.679)
      (stroke (width 0.12) (type solid)) (layer "B.Paste"))
    (fp_line (start -0.849 -1.726) (end -0.849 1.739)
      (stroke (width 0.12) (type solid)) (layer "B.Paste"))
    (fp_line (start -0.748 -1.774) (end -0.748 1.778)
      (stroke (width 0.12) (type solid)) (layer "B.Paste"))
    (fp_line (start -0.65 -1.825) (end -0.65 1.823)
      (stroke (width 0.12) (type solid)) (layer "B.Paste"))
    (fp_line (start -0.551 1.87) (end -0.551 -1.86)
      (stroke (width 0.12) (type solid)) (layer "B.Paste"))
    (fp_line (start 0.551 -1.87) (end 0.551 1.859)
      (stroke (width 0.12) (type solid)) (layer "B.Paste"))
    (fp_line (start 0.65 1.823) (end 0.65 -1.825)
      (stroke (width 0.12) (type solid)) (layer "B.Paste"))
    (fp_line (start 0.749 1.775) (end 0.749 -1.779)
      (stroke (width 0.12) (type solid)) (layer "B.Paste"))
    (fp_line (start 0.849 1.724) (end 0.849 -1.74)
      (stroke (width 0.12) (type solid)) (layer "B.Paste"))
    (fp_line (start 0.95 1.675) (end 0.95 -1.679)
      (stroke (width 0.12) (type solid)) (layer "B.Paste"))
    (fp_line (start 1.051 1.624) (end 1.051 -1.625)
      (stroke (width 0.12) (type solid)) (layer "B.Paste"))
    (fp_line (start 1.149 1.55) (end 1.149 -1.551)
      (stroke (width 0.12) (type solid)) (layer "B.Paste"))
    (fp_line (start 1.25 1.474) (end 1.25 -1.469)
      (stroke (width 0.12) (type solid)) (layer "B.Paste"))
    (fp_line (start 1.351 1.374) (end 1.351 -1.375)
      (stroke (width 0.12) (type solid)) (layer "B.Paste"))
    (fp_line (start 1.45 1.275) (end 1.45 -1.274)
      (stroke (width 0.12) (type solid)) (layer "B.Paste"))
    (fp_line (start 1.551 1.15) (end 1.551 -1.16)
      (stroke (width 0.12) (type solid)) (layer "B.Paste"))
    (fp_line (start 1.649 0.999) (end 1.649 -1.024)
      (stroke (width 0.12) (type solid)) (layer "B.Paste"))
    (fp_line (start 1.75 0.82) (end 1.75 -0.83)
      (stroke (width 0.12) (type solid)) (layer "B.Paste"))
    (fp_line (start 1.851 0.57) (end 1.851 -0.578)
      (stroke (width 0.12) (type solid)) (layer "B.Paste"))
    (fp_arc (start -0.551 1.874) (mid -1.952999 0.00274) (end -0.557 -1.873)
      (stroke (width 0.1) (type solid)) (layer "B.Paste"))
    (fp_arc (start 0.551 -1.875) (mid 1.953999 -0.002741) (end 0.557 1.874)
      (stroke (width 0.1) (type solid)) (layer "B.Paste"))
    (fp_circle (center 0.001 2.2) (end 0.051 2.2)
      (stroke (width 0.15) (type solid)) (fill solid) (layer "B.SilkS"))
    (fp_rect (start -1.9 1.9) (end 1.89 -1.89)
      (stroke (width 0.05) (type solid)) (fill none) (layer "B.CrtYd"))
    (pad "1" thru_hole custom locked (at 0.001 0) (size 4 4) (drill 1) (layers "B.Cu" "B.Mask")
      (net 221 "unconnected-(SP6-Pad1)") (pinfunction "1") (pintype "passive+no_connect") (solder_paste_margin -1.2) (zone_connect 0)
      (options (clearance outline) (anchor circle))
      (primitives
      ))
  )

  (footprint "scalenode-cm4-baseboard-footprints:C_0402_1005Metric" (layer "B.Cu")
    (at 134.5 86.25 90)
    (descr "Capacitor SMD 0402")
    (tags "capacitor SMD 0402")
    (property "Author" "Antmicro")
    (property "Dielectric" "X5R")
    (property "License" "Apache-2.0")
    (property "MPN" "GRM155R61H104KE14D")
    (property "Manufacturer" "Murata")
    (property "Sheetfile" "supply.kicad_sch")
    (property "Sheetname" "Supply")
    (property "Val" "100n")
    (property "Voltage" "50V")
    (property "ki_description" " ")
    (attr smd)
    (fp_text reference "C17" (at 1.075 1.475 90) (layer "B.SilkS")
        (effects (font (size 0.7 0.7) (thickness 0.15)) (justify left bottom mirror))
    )
    (fp_text value "C_100n_0402" (at 0 -1.4 90) (layer "B.Fab")
        (effects (font (size 0.7 0.7) (thickness 0.15)) (justify right bottom mirror))
    )
    (fp_text user "License: Apache-2.0" (at -0.932 -5.17 90) (layer "B.Fab") hide
        (effects (font (size 0.7 0.7) (thickness 0.15)) (justify right bottom mirror))
    )
    (fp_text user "${REFERENCE}" (at -0.932 -3.168 90) (layer "B.Fab") hide
        (effects (font (size 0.7 0.7) (thickness 0.15)) (justify right bottom mirror))
    )
    (fp_text user "Author: Antmicro" (at -0.932 -4.17 90) (layer "B.Fab") hide
        (effects (font (size 0.7 0.7) (thickness 0.15)) (justify right bottom mirror))
    )
    (fp_rect (start -0.94 0.47) (end 0.94 -0.47)
      (stroke (width 0.05) (type solid)) (fill none) (layer "B.CrtYd"))
    (fp_rect (start -0.499 0.249) (end 0.499 -0.249)
      (stroke (width 0.15) (type solid)) (fill none) (layer "B.Fab"))
    (pad "1" smd roundrect (at -0.484 0 90) (size 0.59 0.64) (layers "B.Cu" "B.Paste" "B.Mask") (roundrect_rratio 0.25)
      (net 19 "Net-(U2-SW)") (pintype "passive"))
    (pad "2" smd roundrect (at 0.484 0 90) (size 0.59 0.64) (layers "B.Cu" "B.Paste" "B.Mask") (roundrect_rratio 0.25)
      (net 22 "Net-(U2-BST)") (pintype "passive"))
  )

  (footprint "scalenode-cm4-baseboard-footprints:Conn_Hermaphroditic_Samtec_LSHM_2x30_LSHM-130-01-XXX-RH-A-S-K-XX" locked (layer "B.Cu")
    (at 199.181 76.7 -90)
    (property "Author" "Antmicro")
    (property "License" "Apache-2.0")
    (property "MPN" "LSHM-130-01-L-RH-A-S-K-TR")
    (property "Manufacturer" "Samtec")
    (property "Sheetfile" "expansion-connectors.kicad_sch")
    (property "Sheetname" "Expansion connectors")
    (attr smd)
    (fp_text reference "J10" (at -6.9 2.011 90) (layer "B.SilkS")
        (effects (font (size 0.7 0.7) (thickness 0.15)) (justify left bottom mirror))
    )
    (fp_text value "Hermaphroditic_Samtec_LSHM_2x30_LSHM-130-01-L-RH-A-S-K-TR" (at 18.35 -0.519 180) (layer "B.Fab")
        (effects (font (size 0.7 0.7) (thickness 0.15)) (justify left bottom mirror))
    )
    (fp_text user "PCB~{EDGE}" (at -13 -10.099 90) (layer "B.Fab") hide
        (effects (font (size 0.7 0.7) (thickness 0.15)) (justify left bottom mirror))
    )
    (fp_text user "License: Apache-2.0" (at -13 -13.699 90) (layer "B.Fab") hide
        (effects (font (size 0.7 0.7) (thickness 0.15)) (justify left bottom mirror))
    )
    (fp_text user "Author: Antmicro" (at -13 -12.499 90) (layer "B.Fab") hide
        (effects (font (size 0.7 0.7) (thickness 0.15)) (justify left bottom mirror))
    )
    (fp_text user "${REFERENCE}" (at -13 -11.299 90) (layer "B.Fab") hide
        (effects (font (size 0.7 0.7) (thickness 0.15)) (justify left bottom mirror))
    )
    (fp_circle (center -10.801 -2.799) (end -10.375 -2.799)
      (stroke (width 0.85) (type solid)) (fill none) (layer "B.Paste"))
    (fp_circle (center 10.8 -2.799) (end 11.224 -2.799)
      (stroke (width 0.85) (type solid)) (fill none) (layer "B.Paste"))
    (fp_poly
      (pts
        (xy -10.456 0.228)
        (xy -10.48 0.237)
        (xy -10.5 0.244)
        (xy -10.52 0.25)
        (xy -10.541 0.256)
        (xy -10.561 0.262)
        (xy -10.582 0.267)
        (xy -10.602 0.272)
        (xy -10.623 0.276)
        (xy -10.644 0.28)
        (xy -10.665 0.283)
        (xy -10.686 0.286)
        (xy -10.707 0.288)
        (xy -10.728 0.29)
        (xy -10.749 0.292)
        (xy -10.77 0.293)
        (xy -10.792 0.293)
        (xy -10.813 0.293)
        (xy -10.834 0.293)
        (xy -10.855 0.292)
        (xy -10.876 0.291)
        (xy -10.897 0.289)
        (xy -10.918 0.286)
        (xy -10.94 0.284)
        (xy -10.96 0.28)
        (xy -10.981 0.277)
        (xy -11.002 0.273)
        (xy -11.023 0.268)
        (xy -11.043 0.263)
        (xy -11.064 0.257)
        (xy -11.091 0.249)
        (xy -11.133 0.233)
        (xy -11.173 0.214)
        (xy -11.213 0.194)
        (xy -11.251 0.171)
        (xy -11.288 0.147)
        (xy -11.324 0.12)
        (xy -11.358 0.092)
        (xy -11.391 0.062)
        (xy -11.422 0.03)
        (xy -11.452 -0.003)
        (xy -11.479 -0.038)
        (xy -11.505 -0.074)
        (xy -11.529 -0.112)
        (xy -11.551 -0.15)
        (xy -11.571 -0.19)
        (xy -11.589 -0.231)
        (xy -11.604 -0.273)
        (xy -11.618 -0.315)
        (xy -11.629 -0.358)
        (xy -11.638 -0.402)
        (xy -11.644 -0.446)
        (xy -11.648 -0.49)
        (xy -11.65 -0.535)
        (xy -11.65 -0.579)
        (xy -11.647 -0.624)
        (xy -11.642 -0.668)
        (xy -11.635 -0.712)
        (xy -11.625 -0.755)
        (xy -11.613 -0.798)
        (xy -11.599 -0.84)
        (xy -11.583 -0.882)
        (xy -11.564 -0.922)
        (xy -11.544 -0.962)
        (xy -11.521 -1)
        (xy -11.497 -1.037)
        (xy -11.47 -1.073)
        (xy -11.442 -1.107)
        (xy -11.412 -1.14)
        (xy -11.38 -1.171)
        (xy -11.347 -1.201)
        (xy -11.312 -1.228)
        (xy -11.276 -1.254)
        (xy -11.238 -1.278)
        (xy -11.2 -1.3)
        (xy -11.16 -1.32)
        (xy -11.119 -1.338)
        (xy -11.077 -1.353)
        (xy -11.035 -1.367)
        (xy -10.992 -1.378)
        (xy -10.948 -1.387)
        (xy -10.904 -1.393)
        (xy -10.86 -1.397)
        (xy -10.815 -1.399)
        (xy -10.771 -1.399)
        (xy -10.726 -1.396)
        (xy -10.682 -1.391)
        (xy -10.638 -1.384)
        (xy -10.595 -1.374)
        (xy -10.552 -1.362)
        (xy -10.51 -1.348)
        (xy -10.489 -1.341)
        (xy -10.469 -1.332)
        (xy -10.449 -1.324)
        (xy -10.43 -1.314)
        (xy -10.41 -1.305)
        (xy -10.391 -1.294)
        (xy -10.372 -1.284)
        (xy -10.353 -1.272)
        (xy -10.335 -1.261)
        (xy -10.317 -1.248)
        (xy -10.299 -1.236)
        (xy -10.281 -1.223)
        (xy -10.264 -1.209)
        (xy -10.248 -1.195)
        (xy -10.231 -1.181)
        (xy -10.215 -1.166)
        (xy -10.2 -1.151)
        (xy -10.184 -1.135)
        (xy -10.17 -1.119)
        (xy -10.155 -1.103)
        (xy -10.141 -1.086)
        (xy -10.128 -1.069)
        (xy -10.114 -1.052)
        (xy -10.102 -1.034)
        (xy -10.09 -1.016)
        (xy -10.078 -0.998)
        (xy -10.067 -0.979)
        (xy -10.056 -0.96)
        (xy -10.045 -0.941)
        (xy -10.037 -0.923)
        (xy -10.456 0.228)
      )

      (stroke (width 0.01) (type solid)) (fill solid) (layer "B.Paste"))
    (fp_poly
      (pts
        (xy -9.57 -1.268)
        (xy -9.581 -1.292)
        (xy -9.59 -1.311)
        (xy -9.598 -1.331)
        (xy -9.606 -1.35)
        (xy -9.613 -1.37)
        (xy -9.62 -1.39)
        (xy -9.626 -1.41)
        (xy -9.632 -1.431)
        (xy -9.638 -1.451)
        (xy -9.643 -1.472)
        (xy -9.648 -1.492)
        (xy -9.652 -1.513)
        (xy -9.656 -1.534)
        (xy -9.659 -1.555)
        (xy -9.662 -1.576)
        (xy -9.664 -1.597)
        (xy -9.666 -1.618)
        (xy -9.668 -1.639)
        (xy -9.668 -1.661)
        (xy -9.669 -1.682)
        (xy -9.669 -1.703)
        (xy -9.669 -1.724)
        (xy -9.668 -1.745)
        (xy -9.666 -1.767)
        (xy -9.664 -1.788)
        (xy -9.662 -1.809)
        (xy -9.659 -1.83)
        (xy -9.656 -1.851)
        (xy -9.652 -1.872)
        (xy -9.647 -1.899)
        (xy -9.634 -1.942)
        (xy -9.619 -1.984)
        (xy -9.602 -2.025)
        (xy -9.583 -2.065)
        (xy -9.562 -2.104)
        (xy -9.538 -2.142)
        (xy -9.513 -2.179)
        (xy -9.486 -2.214)
        (xy -9.457 -2.248)
        (xy -9.427 -2.281)
        (xy -9.394 -2.311)
        (xy -9.36 -2.34)
        (xy -9.325 -2.367)
        (xy -9.288 -2.392)
        (xy -9.25 -2.416)
        (xy -9.211 -2.437)
        (xy -9.171 -2.456)
        (xy -9.13 -2.473)
        (xy -9.088 -2.488)
        (xy -9.045 -2.501)
        (xy -9.002 -2.511)
        (xy -8.958 -2.519)
        (xy -8.914 -2.525)
        (xy -8.87 -2.528)
        (xy -8.825 -2.529)
        (xy -8.781 -2.528)
        (xy -8.737 -2.525)
        (xy -8.693 -2.519)
        (xy -8.649 -2.511)
        (xy -8.606 -2.501)
        (xy -8.563 -2.488)
        (xy -8.521 -2.473)
        (xy -8.48 -2.456)
        (xy -8.44 -2.437)
        (xy -8.401 -2.416)
        (xy -8.363 -2.392)
        (xy -8.326 -2.367)
        (xy -8.291 -2.34)
        (xy -8.257 -2.311)
        (xy -8.224 -2.281)
        (xy -8.194 -2.248)
        (xy -8.165 -2.214)
        (xy -8.138 -2.179)
        (xy -8.113 -2.142)
        (xy -8.089 -2.104)
        (xy -8.068 -2.065)
        (xy -8.049 -2.025)
        (xy -8.032 -1.984)
        (xy -8.017 -1.942)
        (xy -8.004 -1.899)
        (xy -7.994 -1.856)
        (xy -7.986 -1.812)
        (xy -7.98 -1.768)
        (xy -7.977 -1.724)
        (xy -7.976 -1.679)
        (xy -7.977 -1.635)
        (xy -7.98 -1.591)
        (xy -7.986 -1.547)
        (xy -7.994 -1.503)
        (xy -8.004 -1.46)
        (xy -8.01 -1.439)
        (xy -8.017 -1.418)
        (xy -8.024 -1.397)
        (xy -8.031 -1.377)
        (xy -8.039 -1.356)
        (xy -8.048 -1.336)
        (xy -8.057 -1.316)
        (xy -8.066 -1.297)
        (xy -8.077 -1.277)
        (xy -8.087 -1.258)
        (xy -8.098 -1.24)
        (xy -8.11 -1.221)
        (xy -8.122 -1.203)
        (xy -8.134 -1.185)
        (xy -8.147 -1.167)
        (xy -8.16 -1.15)
        (xy -8.174 -1.133)
        (xy -8.188 -1.117)
        (xy -8.203 -1.101)
        (xy -8.218 -1.085)
        (xy -8.233 -1.069)
        (xy -8.249 -1.054)
        (xy -8.265 -1.04)
        (xy -8.282 -1.026)
        (xy -8.299 -1.012)
        (xy -8.316 -0.999)
        (xy -8.334 -0.986)
        (xy -8.352 -0.973)
        (xy -8.37 -0.961)
        (xy -8.387 -0.951)
        (xy -9.57 -1.268)
      )

      (stroke (width 0.01) (type solid)) (fill solid) (layer "B.Paste"))
    (fp_poly
      (pts
        (xy 8.386 -0.951)
        (xy 8.364 -0.966)
        (xy 8.347 -0.978)
        (xy 8.33 -0.991)
        (xy 8.313 -1.004)
        (xy 8.297 -1.018)
        (xy 8.281 -1.032)
        (xy 8.265 -1.046)
        (xy 8.25 -1.061)
        (xy 8.235 -1.075)
        (xy 8.22 -1.091)
        (xy 8.206 -1.106)
        (xy 8.192 -1.122)
        (xy 8.178 -1.138)
        (xy 8.165 -1.155)
        (xy 8.152 -1.172)
        (xy 8.139 -1.189)
        (xy 8.127 -1.206)
        (xy 8.115 -1.224)
        (xy 8.104 -1.242)
        (xy 8.093 -1.26)
        (xy 8.082 -1.278)
        (xy 8.072 -1.297)
        (xy 8.062 -1.315)
        (xy 8.053 -1.335)
        (xy 8.044 -1.354)
        (xy 8.035 -1.373)
        (xy 8.027 -1.393)
        (xy 8.02 -1.413)
        (xy 8.012 -1.432)
        (xy 8.003 -1.46)
        (xy 7.993 -1.503)
        (xy 7.985 -1.547)
        (xy 7.979 -1.591)
        (xy 7.976 -1.635)
        (xy 7.975 -1.679)
        (xy 7.976 -1.724)
        (xy 7.979 -1.768)
        (xy 7.985 -1.812)
        (xy 7.993 -1.856)
        (xy 8.003 -1.899)
        (xy 8.016 -1.942)
        (xy 8.031 -1.984)
        (xy 8.048 -2.025)
        (xy 8.067 -2.065)
        (xy 8.088 -2.104)
        (xy 8.112 -2.142)
        (xy 8.137 -2.179)
        (xy 8.164 -2.214)
        (xy 8.193 -2.248)
        (xy 8.223 -2.281)
        (xy 8.256 -2.311)
        (xy 8.29 -2.34)
        (xy 8.325 -2.367)
        (xy 8.362 -2.392)
        (xy 8.4 -2.416)
        (xy 8.439 -2.437)
        (xy 8.479 -2.456)
        (xy 8.52 -2.473)
        (xy 8.562 -2.488)
        (xy 8.605 -2.501)
        (xy 8.648 -2.511)
        (xy 8.692 -2.519)
        (xy 8.736 -2.525)
        (xy 8.78 -2.528)
        (xy 8.824 -2.529)
        (xy 8.869 -2.528)
        (xy 8.913 -2.525)
        (xy 8.957 -2.519)
        (xy 9.001 -2.511)
        (xy 9.044 -2.501)
        (xy 9.087 -2.488)
        (xy 9.129 -2.473)
        (xy 9.17 -2.456)
        (xy 9.21 -2.437)
        (xy 9.249 -2.416)
        (xy 9.287 -2.392)
        (xy 9.324 -2.367)
        (xy 9.359 -2.34)
        (xy 9.393 -2.311)
        (xy 9.426 -2.281)
        (xy 9.456 -2.248)
        (xy 9.485 -2.214)
        (xy 9.512 -2.179)
        (xy 9.537 -2.142)
        (xy 9.561 -2.104)
        (xy 9.582 -2.065)
        (xy 9.601 -2.025)
        (xy 9.618 -1.984)
        (xy 9.633 -1.942)
        (xy 9.646 -1.899)
        (xy 9.651 -1.878)
        (xy 9.656 -1.857)
        (xy 9.66 -1.836)
        (xy 9.664 -1.814)
        (xy 9.667 -1.793)
        (xy 9.67 -1.771)
        (xy 9.672 -1.749)
        (xy 9.673 -1.728)
        (xy 9.674 -1.706)
        (xy 9.675 -1.684)
        (xy 9.674 -1.662)
        (xy 9.674 -1.64)
        (xy 9.672 -1.619)
        (xy 9.671 -1.597)
        (xy 9.668 -1.575)
        (xy 9.665 -1.554)
        (xy 9.662 -1.532)
        (xy 9.658 -1.511)
        (xy 9.653 -1.489)
        (xy 9.648 -1.468)
        (xy 9.642 -1.447)
        (xy 9.636 -1.426)
        (xy 9.629 -1.406)
        (xy 9.622 -1.385)
        (xy 9.614 -1.365)
        (xy 9.606 -1.345)
        (xy 9.597 -1.325)
        (xy 9.588 -1.305)
        (xy 9.578 -1.285)
        (xy 9.569 -1.268)
        (xy 8.386 -0.951)
      )

      (stroke (width 0.01) (type solid)) (fill solid) (layer "B.Paste"))
    (fp_poly
      (pts
        (xy 10.036 -0.923)
        (xy 10.048 -0.946)
        (xy 10.059 -0.964)
        (xy 10.071 -0.982)
        (xy 10.082 -1)
        (xy 10.094 -1.017)
        (xy 10.107 -1.034)
        (xy 10.12 -1.051)
        (xy 10.133 -1.068)
        (xy 10.146 -1.084)
        (xy 10.16 -1.1)
        (xy 10.175 -1.116)
        (xy 10.189 -1.131)
        (xy 10.204 -1.146)
        (xy 10.219 -1.161)
        (xy 10.235 -1.175)
        (xy 10.251 -1.189)
        (xy 10.267 -1.203)
        (xy 10.284 -1.216)
        (xy 10.3 -1.229)
        (xy 10.318 -1.242)
        (xy 10.335 -1.254)
        (xy 10.353 -1.266)
        (xy 10.37 -1.277)
        (xy 10.389 -1.288)
        (xy 10.407 -1.299)
        (xy 10.426 -1.309)
        (xy 10.444 -1.319)
        (xy 10.463 -1.328)
        (xy 10.483 -1.337)
        (xy 10.509 -1.348)
        (xy 10.551 -1.362)
        (xy 10.594 -1.374)
        (xy 10.637 -1.384)
        (xy 10.681 -1.391)
        (xy 10.725 -1.396)
        (xy 10.77 -1.399)
        (xy 10.814 -1.399)
        (xy 10.859 -1.397)
        (xy 10.903 -1.393)
        (xy 10.947 -1.387)
        (xy 10.991 -1.378)
        (xy 11.034 -1.367)
        (xy 11.076 -1.353)
        (xy 11.118 -1.338)
        (xy 11.159 -1.32)
        (xy 11.199 -1.3)
        (xy 11.237 -1.278)
        (xy 11.275 -1.254)
        (xy 11.311 -1.228)
        (xy 11.346 -1.201)
        (xy 11.379 -1.171)
        (xy 11.411 -1.14)
        (xy 11.441 -1.107)
        (xy 11.469 -1.073)
        (xy 11.496 -1.037)
        (xy 11.52 -1)
        (xy 11.543 -0.962)
        (xy 11.563 -0.922)
        (xy 11.582 -0.882)
        (xy 11.598 -0.84)
        (xy 11.612 -0.798)
        (xy 11.624 -0.755)
        (xy 11.634 -0.712)
        (xy 11.641 -0.668)
        (xy 11.646 -0.624)
        (xy 11.649 -0.579)
        (xy 11.649 -0.535)
        (xy 11.647 -0.49)
        (xy 11.643 -0.446)
        (xy 11.637 -0.402)
        (xy 11.628 -0.358)
        (xy 11.617 -0.315)
        (xy 11.603 -0.273)
        (xy 11.588 -0.231)
        (xy 11.57 -0.19)
        (xy 11.55 -0.15)
        (xy 11.528 -0.112)
        (xy 11.504 -0.074)
        (xy 11.478 -0.038)
        (xy 11.451 -0.003)
        (xy 11.421 0.03)
        (xy 11.39 0.062)
        (xy 11.357 0.092)
        (xy 11.323 0.12)
        (xy 11.287 0.147)
        (xy 11.25 0.171)
        (xy 11.212 0.194)
        (xy 11.172 0.214)
        (xy 11.132 0.233)
        (xy 11.09 0.249)
        (xy 11.07 0.256)
        (xy 11.049 0.263)
        (xy 11.028 0.269)
        (xy 11.007 0.275)
        (xy 10.986 0.28)
        (xy 10.964 0.284)
        (xy 10.943 0.288)
        (xy 10.921 0.292)
        (xy 10.9 0.295)
        (xy 10.878 0.297)
        (xy 10.856 0.299)
        (xy 10.835 0.3)
        (xy 10.813 0.3)
        (xy 10.791 0.301)
        (xy 10.769 0.3)
        (xy 10.747 0.299)
        (xy 10.726 0.297)
        (xy 10.704 0.295)
        (xy 10.682 0.293)
        (xy 10.661 0.289)
        (xy 10.639 0.286)
        (xy 10.618 0.281)
        (xy 10.597 0.276)
        (xy 10.576 0.271)
        (xy 10.555 0.265)
        (xy 10.534 0.258)
        (xy 10.513 0.251)
        (xy 10.493 0.244)
        (xy 10.473 0.236)
        (xy 10.455 0.228)
        (xy 10.036 -0.923)
      )

      (stroke (width 0.01) (type solid)) (fill solid) (layer "B.Paste"))
    (fp_line (start -11.35 -4.4) (end 11.349 -4.4)
      (stroke (width 0.15) (type solid)) (layer "B.SilkS"))
    (fp_line (start -11.35 -3.749) (end -11.35 -4.4)
      (stroke (width 0.15) (type solid)) (layer "B.SilkS"))
    (fp_line (start -11.35 0.401) (end -11.35 1)
      (stroke (width 0.15) (type solid)) (layer "B.SilkS"))
    (fp_line (start -11.35 1) (end -10.33 1)
      (stroke (width 0.15) (type solid)) (layer "B.SilkS"))
    (fp_line (start 10.329 1) (end 11.349 1)
      (stroke (width 0.15) (type solid)) (layer "B.SilkS"))
    (fp_line (start 11.349 -4.4) (end 11.349 -3.749)
      (stroke (width 0.15) (type solid)) (layer "B.SilkS"))
    (fp_line (start 11.349 1) (end 11.349 0.401)
      (stroke (width 0.15) (type solid)) (layer "B.SilkS"))
    (fp_circle (center -7.25 2.05) (end -7.151 2.05)
      (stroke (width 0.1) (type solid)) (fill none) (layer "B.SilkS"))
    (fp_line (start -11.91 -8.09) (end -11.91 1.75)
      (stroke (width 0.05) (type solid)) (layer "B.CrtYd"))
    (fp_line (start -11.91 1.75) (end 11.9 1.75)
      (stroke (width 0.05) (type solid)) (layer "B.CrtYd"))
    (fp_line (start 11.9 -8.09) (end -11.91 -8.09)
      (stroke (width 0.05) (type solid)) (layer "B.CrtYd"))
    (fp_line (start 11.9 1.75) (end 11.9 -8.09)
      (stroke (width 0.05) (type solid)) (layer "B.CrtYd"))
    (fp_line (start -13 -4.4) (end 12.999 -4.4)
      (stroke (width 0.15) (type solid)) (layer "B.Fab"))
    (fp_line (start -11.35 -4.9) (end -11.35 1)
      (stroke (width 0.15) (type solid)) (layer "B.Fab"))
    (fp_line (start -11.35 1) (end 11.349 1)
      (stroke (width 0.15) (type solid)) (layer "B.Fab"))
    (fp_line (start -9.85 -7.849) (end -9.85 -4.9)
      (stroke (width 0.15) (type solid)) (layer "B.Fab"))
    (fp_line (start -9.85 -4.9) (end -11.35 -4.9)
      (stroke (width 0.15) (type solid)) (layer "B.Fab"))
    (fp_line (start 9.849 -7.849) (end -9.85 -7.849)
      (stroke (width 0.15) (type solid)) (layer "B.Fab"))
    (fp_line (start 9.849 -4.9) (end 9.849 -7.849)
      (stroke (width 0.15) (type solid)) (layer "B.Fab"))
    (fp_line (start 11.349 -4.9) (end 9.849 -4.9)
      (stroke (width 0.15) (type solid)) (layer "B.Fab"))
    (fp_line (start 11.349 1) (end 11.349 -4.9)
      (stroke (width 0.15) (type solid)) (layer "B.Fab"))
    (fp_circle (center -7.25 2.05) (end -7.151 2.05)
      (stroke (width 0.15) (type solid)) (fill none) (layer "B.Fab"))
    (pad "" np_thru_hole circle locked (at -9.25 0 270) (size 1.45 1.45) (drill 1.45) (layers "*.Cu" "*.Mask"))
    (pad "" np_thru_hole circle locked (at 9.249 0 270) (size 1.45 1.45) (drill 1.45) (layers "*.Cu" "*.Mask"))
    (pad "01" smd rect locked (at -7.25 0.6 270) (size 0.3 1.8) (layers "B.Cu" "B.Paste" "B.Mask")
      (net 12 "VCC5V0") (pinfunction "01") (pintype "passive"))
    (pad "02" smd rect locked (at -7.25 -2.064 270) (size 0.3 1.63) (layers "B.Cu" "B.Paste" "B.Mask")
      (net 253 "3V3_OUT") (pinfunction "02") (pintype "passive"))
    (pad "03" smd rect locked (at -6.75 0.6 270) (size 0.3 1.8) (layers "B.Cu" "B.Paste" "B.Mask")
      (net 12 "VCC5V0") (pinfunction "03") (pintype "passive"))
    (pad "04" smd rect locked (at -6.75 -2.064 270) (size 0.3 1.63) (layers "B.Cu" "B.Paste" "B.Mask")
      (net 253 "3V3_OUT") (pinfunction "04") (pintype "passive"))
    (pad "05" smd rect locked (at -6.25 0.6 270) (size 0.3 1.8) (layers "B.Cu" "B.Paste" "B.Mask")
      (net 12 "VCC5V0") (pinfunction "05") (pintype "passive"))
    (pad "06" smd rect locked (at -6.25 -2.064 270) (size 0.3 1.63) (layers "B.Cu" "B.Paste" "B.Mask")
      (net 253 "3V3_OUT") (pinfunction "06") (pintype "passive"))
    (pad "07" smd rect locked (at -5.75 0.6 270) (size 0.3 1.8) (layers "B.Cu" "B.Paste" "B.Mask")
      (net 12 "VCC5V0") (pinfunction "07") (pintype "passive"))
    (pad "08" smd rect locked (at -5.75 -2.064 270) (size 0.3 1.63) (layers "B.Cu" "B.Paste" "B.Mask")
      (net 253 "3V3_OUT") (pinfunction "08") (pintype "passive"))
    (pad "09" smd rect locked (at -5.25 0.6 270) (size 0.3 1.8) (layers "B.Cu" "B.Paste" "B.Mask")
      (net 12 "VCC5V0") (pinfunction "09") (pintype "passive"))
    (pad "10" smd rect locked (at -5.25 -2.064 270) (size 0.3 1.63) (layers "B.Cu" "B.Paste" "B.Mask")
      (net 253 "3V3_OUT") (pinfunction "10") (pintype "passive"))
    (pad "11" smd rect locked (at -4.75 0.6 270) (size 0.3 1.8) (layers "B.Cu" "B.Paste" "B.Mask")
      (net 12 "VCC5V0") (pinfunction "11") (pintype "passive"))
    (pad "12" smd rect locked (at -4.75 -2.064 270) (size 0.3 1.63) (layers "B.Cu" "B.Paste" "B.Mask")
      (net 253 "3V3_OUT") (pinfunction "12") (pintype "passive"))
    (pad "13" smd rect locked (at -4.25 0.6 270) (size 0.3 1.8) (layers "B.Cu" "B.Paste" "B.Mask")
      (net 211 "unconnected-(J10-Pad13)") (pinfunction "13") (pintype "passive+no_connect"))
    (pad "14" smd rect locked (at -4.25 -2.064 270) (size 0.3 1.63) (layers "B.Cu" "B.Paste" "B.Mask")
      (net 212 "unconnected-(J10-Pad14)") (pinfunction "14") (pintype "passive+no_connect"))
    (pad "15" smd rect locked (at -3.75 0.6 270) (size 0.3 1.8) (layers "B.Cu" "B.Paste" "B.Mask")
      (net 213 "unconnected-(J10-Pad15)") (pinfunction "15") (pintype "passive+no_connect"))
    (pad "16" smd rect locked (at -3.75 -2.064 270) (size 0.3 1.63) (layers "B.Cu" "B.Paste" "B.Mask")
      (net 214 "unconnected-(J10-Pad16)") (pinfunction "16") (pintype "passive+no_connect"))
    (pad "17" smd rect locked (at -3.25 0.6 270) (size 0.3 1.8) (layers "B.Cu" "B.Paste" "B.Mask")
      (net 11 "GND") (pinfunction "17") (pintype "passive"))
    (pad "18" smd rect locked (at -3.25 -2.064 270) (size 0.3 1.63) (layers "B.Cu" "B.Paste" "B.Mask")
      (net 11 "GND") (pinfunction "18") (pintype "passive"))
    (pad "19" smd rect locked (at -2.75 0.6 270) (size 0.3 1.8) (layers "B.Cu" "B.Paste" "B.Mask")
      (net 11 "GND") (pinfunction "19") (pintype "passive"))
    (pad "20" smd rect locked (at -2.75 -2.064 270) (size 0.3 1.63) (layers "B.Cu" "B.Paste" "B.Mask")
      (net 11 "GND") (pinfunction "20") (pintype "passive"))
    (pad "21" smd rect locked (at -2.25 0.6 270) (size 0.3 1.8) (layers "B.Cu" "B.Paste" "B.Mask")
      (net 11 "GND") (pinfunction "21") (pintype "passive"))
    (pad "22" smd rect locked (at -2.25 -2.064 270) (size 0.3 1.63) (layers "B.Cu" "B.Paste" "B.Mask")
      (net 11 "GND") (pinfunction "22") (pintype "passive"))
    (pad "23" smd rect locked (at -1.75 0.6 270) (size 0.3 1.8) (layers "B.Cu" "B.Paste" "B.Mask")
      (net 11 "GND") (pinfunction "23") (pintype "passive"))
    (pad "24" smd rect locked (at -1.75 -2.064 270) (size 0.3 1.63) (layers "B.Cu" "B.Paste" "B.Mask")
      (net 11 "GND") (pinfunction "24") (pintype "passive"))
    (pad "25" smd rect locked (at -1.25 0.6 270) (size 0.3 1.8) (layers "B.Cu" "B.Paste" "B.Mask")
      (net 11 "GND") (pinfunction "25") (pintype "passive"))
    (pad "26" smd rect locked (at -1.25 -2.064 270) (size 0.3 1.63) (layers "B.Cu" "B.Paste" "B.Mask")
      (net 11 "GND") (pinfunction "26") (pintype "passive"))
    (pad "27" smd rect locked (at -0.75 0.6 270) (size 0.3 1.8) (layers "B.Cu" "B.Paste" "B.Mask")
      (net 152 "HDMI0_SCL") (pinfunction "27") (pintype "passive"))
    (pad "28" smd rect locked (at -0.75 -2.064 270) (size 0.3 1.63) (layers "B.Cu" "B.Paste" "B.Mask")
      (net 237 "Adapter_RXD") (pinfunction "28") (pintype "passive"))
    (pad "29" smd rect locked (at -0.25 0.6 270) (size 0.3 1.8) (layers "B.Cu" "B.Paste" "B.Mask")
      (net 151 "HDMI0_SDA") (pinfunction "29") (pintype "passive"))
    (pad "30" smd rect locked (at -0.25 -2.064 270) (size 0.3 1.63) (layers "B.Cu" "B.Paste" "B.Mask")
      (net 238 "Adapter_TXD") (pinfunction "30") (pintype "passive"))
    (pad "31" smd rect locked (at 0.249 0.6 270) (size 0.3 1.8) (layers "B.Cu" "B.Paste" "B.Mask")
      (net 125 "HDMI0_CEC") (pinfunction "31") (pintype "passive"))
    (pad "32" smd rect locked (at 0.249 -2.064 270) (size 0.3 1.63) (layers "B.Cu" "B.Paste" "B.Mask")
      (net 11 "GND") (pinfunction "32") (pintype "passive"))
    (pad "33" smd rect locked (at 0.749 0.6 270) (size 0.3 1.8) (layers "B.Cu" "B.Paste" "B.Mask")
      (net 127 "HDMI0_HOTPLUG") (pinfunction "33") (pintype "passive"))
    (pad "34" smd rect locked (at 0.749 -2.064 270) (size 0.3 1.63) (layers "B.Cu" "B.Paste" "B.Mask")
      (net 240 "Adapter_USB_N") (pinfunction "34") (pintype "passive"))
    (pad "35" smd rect locked (at 1.249 0.6 270) (size 0.3 1.8) (layers "B.Cu" "B.Paste" "B.Mask")
      (net 11 "GND") (pinfunction "35") (pintype "passive"))
    (pad "36" smd rect locked (at 1.249 -2.064 270) (size 0.3 1.63) (layers "B.Cu" "B.Paste" "B.Mask")
      (net 239 "Adapter_USB_P") (pinfunction "36") (pintype "passive"))
    (pad "37" smd rect locked (at 1.749 0.6 270) (size 0.3 1.8) (layers "B.Cu" "B.Paste" "B.Mask")
      (net 36 "HDMI0_D2_P") (pinfunction "37") (pintype "passive"))
    (pad "38" smd rect locked (at 1.749 -2.064 270) (size 0.3 1.63) (layers "B.Cu" "B.Paste" "B.Mask")
      (net 11 "GND") (pinfunction "38") (pintype "passive"))
    (pad "39" smd rect locked (at 2.249 0.6 270) (size 0.3 1.8) (layers "B.Cu" "B.Paste" "B.Mask")
      (net 37 "HDMI0_D2_N") (pinfunction "39") (pintype "passive"))
    (pad "40" smd rect locked (at 2.249 -2.064 270) (size 0.3 1.63) (layers "B.Cu" "B.Paste" "B.Mask")
      (net 53 "SCL0") (pinfunction "40") (pintype "passive"))
    (pad "41" smd rect locked (at 2.749 0.6 270) (size 0.3 1.8) (layers "B.Cu" "B.Paste" "B.Mask")
      (net 11 "GND") (pinfunction "41") (pintype "passive"))
    (pad "42" smd rect locked (at 2.749 -2.064 270) (size 0.3 1.63) (layers "B.Cu" "B.Paste" "B.Mask")
      (net 52 "SDA0") (pinfunction "42") (pintype "passive"))
    (pad "43" smd rect locked (at 3.249 0.6 270) (size 0.3 1.8) (layers "B.Cu" "B.Paste" "B.Mask")
      (net 38 "HDMI0_D1_P") (pinfunction "43") (pintype "passive"))
    (pad "44" smd rect locked (at 3.249 -2.064 270) (size 0.3 1.63) (layers "B.Cu" "B.Paste" "B.Mask")
      (net 11 "GND") (pinfunction "44") (pintype "passive"))
    (pad "45" smd rect locked (at 3.749 0.6 270) (size 0.3 1.8) (layers "B.Cu" "B.Paste" "B.Mask")
      (net 39 "HDMI0_D1_N") (pinfunction "45") (pintype "passive"))
    (pad "46" smd rect locked (at 3.749 -2.064 270) (size 0.3 1.63) (layers "B.Cu" "B.Paste" "B.Mask")
      (net 80 "GPIO26") (pinfunction "46") (pintype "passive"))
    (pad "47" smd rect locked (at 4.249 0.6 270) (size 0.3 1.8) (layers "B.Cu" "B.Paste" "B.Mask")
      (net 11 "GND") (pinfunction "47") (pintype "passive"))
    (pad "48" smd rect locked (at 4.249 -2.064 270) (size 0.3 1.63) (layers "B.Cu" "B.Paste" "B.Mask")
      (net 61 "GPIO18") (pinfunction "48") (pintype "passive"))
    (pad "49" smd rect locked (at 4.749 0.6 270) (size 0.3 1.8) (layers "B.Cu" "B.Paste" "B.Mask")
      (net 142 "HDMI0_D0_P") (pinfunction "49") (pintype "passive"))
    (pad "50" smd rect locked (at 4.749 -2.064 270) (size 0.3 1.63) (layers "B.Cu" "B.Paste" "B.Mask")
      (net 11 "GND") (pinfunction "50") (pintype "passive"))
    (pad "51" smd rect locked (at 5.249 0.6 270) (size 0.3 1.8) (layers "B.Cu" "B.Paste" "B.Mask")
      (net 144 "HDMI0_D0_N") (pinfunction "51") (pintype "passive"))
    (pad "52" smd rect locked (at 5.249 -2.064 270) (size 0.3 1.63) (layers "B.Cu" "B.Paste" "B.Mask")
      (net 71 "GPIO7") (pinfunction "52") (pintype "passive"))
    (pad "53" smd rect locked (at 5.749 0.6 270) (size 0.3 1.8) (layers "B.Cu" "B.Paste" "B.Mask")
      (net 11 "GND") (pinfunction "53") (pintype "passive"))
    (pad "54" smd rect locked (at 5.749 -2.064 270) (size 0.3 1.63) (layers "B.Cu" "B.Paste" "B.Mask")
      (net 69 "GPIO8") (pinfunction "54") (pintype "passive"))
    (pad "55" smd rect locked (at 6.249 0.6 270) (size 0.3 1.8) (layers "B.Cu" "B.Paste" "B.Mask")
      (net 40 "HDMI0_CK_P") (pinfunction "55") (pintype "passive"))
    (pad "56" smd rect locked (at 6.249 -2.064 270) (size 0.3 1.63) (layers "B.Cu" "B.Paste" "B.Mask")
      (net 11 "GND") (pinfunction "56") (pintype "passive"))
    (pad "57" smd rect locked (at 6.749 0.6 270) (size 0.3 1.8) (layers "B.Cu" "B.Paste" "B.Mask")
      (net 41 "HDMI0_CK_N") (pinfunction "57") (pintype "passive"))
    (pad "58" smd rect locked (at 6.749 -2.064 270) (size 0.3 1.63) (layers "B.Cu" "B.Paste" "B.Mask")
      (net 65 "GPIO24") (pinfunction "58") (pintype "passive"))
    (pad "59" smd rect locked (at 7.249 0.6 270) (size 0.3 1.8) (layers "B.Cu" "B.Paste" "B.Mask")
      (net 11 "GND") (pinfunction "59") (pintype "passive"))
    (pad "60" smd rect locked (at 7.249 -2.064 270) (size 0.3 1.63) (layers "B.Cu" "B.Paste" "B.Mask")
      (net 67 "GPIO25") (pinfunction "60") (pintype "passive"))
    (pad "S1" thru_hole circle locked (at -8.825 -1.679 270) (size 1.208 1.208) (drill 0.7) (layers "*.Cu" "*.Mask")
      (net 11 "GND") (pinfunction "SHIELD") (pintype "passive"))
    (pad "S2" thru_hole circle locked (at 8.824 -1.679 270) (size 1.208 1.208) (drill 0.7) (layers "*.Cu" "*.Mask")
      (net 11 "GND") (pinfunction "SHIELD") (pintype "passive"))
    (pad "WT1" thru_hole circle locked (at -10.801 -0.55 270) (size 1.208 1.208) (drill 0.7) (layers "*.Cu" "*.Mask"))
    (pad "WT2" thru_hole circle locked (at -10.801 -2.799 270) (size 1.208 1.208) (drill 0.7) (layers "*.Cu" "*.Mask"))
    (pad "WT3" thru_hole circle locked (at 10.8 -0.55 270) (size 1.208 1.208) (drill 0.7) (layers "*.Cu" "*.Mask"))
    (pad "WT4" thru_hole circle locked (at 10.8 -2.799 270) (size 1.208 1.208) (drill 0.7) (layers "*.Cu" "*.Mask"))
  )

  (footprint "scalenode-cm4-baseboard-footprints:R_1206_3216Metric" (layer "B.Cu")
    (at 151.6 89 -90)
    (property "Author" "Antmicro")
    (property "Current" "2A")
    (property "License" "Apache-2.0")
    (property "MPN" "MCMR12X000_PTL")
    (property "Manufacturer" "Multicomp Pro")
    (property "Sheetfile" "expansion-connectors.kicad_sch")
    (property "Sheetname" "Expansion connectors")
    (property "Tolerance" "~")
    (property "Val" "0R")
    (property "ki_description" "0R resistor in 1206 package with unspecified tolerance")
    (attr smd)
    (fp_text reference "R62" (at -0.825 1.325 90) (layer "B.SilkS")
        (effects (font (size 0.7 0.7) (thickness 0.15)) (justify left bottom mirror))
    )
    (fp_text value "R_0R_1206" (at 0 -2 90) (layer "B.Fab")
        (effects (font (size 0.7 0.7) (thickness 0.15)) (justify left bottom mirror))
    )
    (fp_text user "License: Apache-2.0" (at -2.401 -6.3 90) (layer "B.Fab") hide
        (effects (font (size 0.7 0.7) (thickness 0.15)) (justify left bottom mirror))
    )
    (fp_text user "Author: Antmicro" (at -2.401 -4.899 90) (layer "B.Fab") hide
        (effects (font (size 0.7 0.7) (thickness 0.15)) (justify left bottom mirror))
    )
    (fp_text user "${REFERENCE}" (at -2.401 -3.5 90) (layer "B.Fab") hide
        (effects (font (size 0.7 0.7) (thickness 0.15)) (justify left bottom mirror))
    )
    (fp_line (start 0 -0.9) (end -0.5 -0.9)
      (stroke (width 0.15) (type solid)) (layer "B.SilkS"))
    (fp_line (start 0 -0.9) (end 0.498 -0.9)
      (stroke (width 0.15) (type solid)) (layer "B.SilkS"))
    (fp_line (start 0 0.902) (end -0.5 0.902)
      (stroke (width 0.15) (type solid)) (layer "B.SilkS"))
    (fp_line (start 0 0.902) (end 0.498 0.902)
      (stroke (width 0.15) (type solid)) (layer "B.SilkS"))
    (fp_rect (start -2.25 1.05) (end 2.25 -1.05)
      (stroke (width 0.05) (type solid)) (fill none) (layer "B.CrtYd"))
    (fp_line (start -1.601 -0.8) (end 1.6 -0.8)
      (stroke (width 0.15) (type solid)) (layer "B.Fab"))
    (fp_line (start -1.601 0.802) (end -1.601 -0.8)
      (stroke (width 0.15) (type solid)) (layer "B.Fab"))
    (fp_line (start -1.601 0.802) (end 1.6 0.802)
      (stroke (width 0.15) (type solid)) (layer "B.Fab"))
    (fp_line (start 1.6 0.802) (end 1.6 -0.8)
      (stroke (width 0.15) (type solid)) (layer "B.Fab"))
    (pad "1" smd roundrect (at -1.5 0 270) (size 1.2 1.8) (layers "B.Cu" "B.Paste" "B.Mask") (roundrect_rratio 0.15)
      (net 253 "3V3_OUT") (pintype "passive"))
    (pad "2" smd roundrect (at 1.499 0 270) (size 1.2 1.8) (layers "B.Cu" "B.Paste" "B.Mask") (roundrect_rratio 0.15)
      (net 170 "3V3_SSD") (pintype "passive"))
  )

  (footprint "scalenode-cm4-baseboard-footprints:R_1206_3216Metric" (layer "B.Cu")
    (at 151.6 85.4 90)
    (property "Author" "Antmicro")
    (property "Current" "2A")
    (property "DNP" "DNP")
    (property "License" "Apache-2.0")
    (property "MPN" "MCMR12X000_PTL")
    (property "Manufacturer" "Multicomp Pro")
    (property "Sheetfile" "expansion-connectors.kicad_sch")
    (property "Sheetname" "Expansion connectors")
    (property "Tolerance" "~")
    (property "Val" "0R")
    (property "dnp" "")
    (property "exclude_from_bom" "")
    (property "ki_description" "0R resistor in 1206 package with unspecified tolerance")
    (attr exclude_from_pos_files exclude_from_bom)
    (fp_text reference "R63" (at 1.225 -1.35 270) (layer "B.SilkS")
        (effects (font (size 0.7 0.7) (thickness 0.15)) (justify left bottom mirror))
    )
    (fp_text value "R_0R_1206" (at 0 -2 270) (layer "B.Fab")
        (effects (font (size 0.7 0.7) (thickness 0.15)) (justify left bottom mirror))
    )
    (fp_text user "Author: Antmicro" (at -2.401 -4.899 270) (layer "B.Fab") hide
        (effects (font (size 0.7 0.7) (thickness 0.15)) (justify left bottom mirror))
    )
    (fp_text user "${REFERENCE}" (at -2.401 -3.5 270) (layer "B.Fab") hide
        (effects (font (size 0.7 0.7) (thickness 0.15)) (justify left bottom mirror))
    )
    (fp_text user "License: Apache-2.0" (at -2.401 -6.3 270) (layer "B.Fab") hide
        (effects (font (size 0.7 0.7) (thickness 0.15)) (justify left bottom mirror))
    )
    (fp_line (start 0 -0.9) (end -0.5 -0.9)
      (stroke (width 0.15) (type solid)) (layer "B.SilkS"))
    (fp_line (start 0 -0.9) (end 0.498 -0.9)
      (stroke (width 0.15) (type solid)) (layer "B.SilkS"))
    (fp_line (start 0 0.902) (end -0.5 0.902)
      (stroke (width 0.15) (type solid)) (layer "B.SilkS"))
    (fp_line (start 0 0.902) (end 0.498 0.902)
      (stroke (width 0.15) (type solid)) (layer "B.SilkS"))
    (fp_rect (start -2.25 1.05) (end 2.25 -1.05)
      (stroke (width 0.05) (type solid)) (fill none) (layer "B.CrtYd"))
    (fp_line (start -1.601 -0.8) (end 1.6 -0.8)
      (stroke (width 0.15) (type solid)) (layer "B.Fab"))
    (fp_line (start -1.601 0.802) (end -1.601 -0.8)
      (stroke (width 0.15) (type solid)) (layer "B.Fab"))
    (fp_line (start -1.601 0.802) (end 1.6 0.802)
      (stroke (width 0.15) (type solid)) (layer "B.Fab"))
    (fp_line (start 1.6 0.802) (end 1.6 -0.8)
      (stroke (width 0.15) (type solid)) (layer "B.Fab"))
    (pad "1" smd roundrect (at -1.5 0 90) (size 1.2 1.8) (layers "B.Cu" "B.Paste" "B.Mask") (roundrect_rratio 0.15)
      (net 253 "3V3_OUT") (pintype "passive"))
    (pad "2" smd roundrect (at 1.499 0 90) (size 1.2 1.8) (layers "B.Cu" "B.Paste" "B.Mask") (roundrect_rratio 0.15)
      (net 232 "3V3_RPi") (pintype "passive"))
  )

  (footprint "scalenode-cm4-baseboard-footprints:TP_SMD_1mm" (layer "B.Cu")
    (at 134 83.75 180)
    (property "Author" "Antmicro")
    (property "License" "Apache-2.0")
    (property "MPN" "")
    (property "Manufacturer" "")
    (property "Sheetfile" "supply.kicad_sch")
    (property "Sheetname" "Supply")
    (property "ki_description" "Test Point 1mm")
    (attr exclude_from_pos_files)
    (fp_text reference "TP2" (at -1.275 0.65) (layer "B.SilkS")
        (effects (font (size 0.7 0.7) (thickness 0.15)) (justify left bottom mirror))
    )
    (fp_text value "TP_1mm_SMD" (at 0 -1.4) (layer "B.Fab")
        (effects (font (size 0.7 0.7) (thickness 0.15)) (justify left bottom mirror))
    )
    (fp_text user "License: Apache-2.0" (at -0.5 -5.2) (layer "B.Fab") hide
        (effects (font (size 0.7 0.7) (thickness 0.15)) (justify left bottom mirror))
    )
    (fp_text user "${REFERENCE}" (at -0.5 -2.8) (layer "B.Fab") hide
        (effects (font (size 0.7 0.7) (thickness 0.15)) (justify left bottom mirror))
    )
    (fp_text user "Author: Antmicro" (at -0.5 -4) (layer "B.Fab") hide
        (effects (font (size 0.7 0.7) (thickness 0.15)) (justify left bottom mirror))
    )
    (pad "1" smd circle (at 0 0 180) (size 1 1) (layers "B.Cu" "B.Mask")
      (net 270 "Net-(U2-EN)") (pinfunction "1") (pintype "passive"))
  )

  (footprint "scalenode-cm4-baseboard-footprints:SOIC-8-1EP_3.9x4.9x1.75mm_P1.27mm" (layer "B.Cu")
    (at 99.05 91.506)
    (tags "Integrated Circuit")
    (property "Author" "Antmicro")
    (property "License" "Apache-2.0")
    (property "MPN" "TPS2378DDA")
    (property "Manufacturer" "Texas Instruments")
    (property "Sheetfile" "poe.kicad_sch")
    (property "Sheetname" "PoE")
    (property "ki_description" "IEEE 802.3at PoE High-Power PD Interface with AUX Control")
    (attr smd)
    (fp_text reference "U8" (at 0.95 3.744 180) (layer "B.SilkS")
        (effects (font (size 0.7 0.7) (thickness 0.15)) (justify left bottom mirror))
    )
    (fp_text value "TPS2378DDA" (at 0 -3.65 180) (layer "B.Fab")
        (effects (font (size 0.7 0.7) (thickness 0.15)) (justify left bottom mirror))
    )
    (fp_text user "${REFERENCE}" (at -3.476 -7.099 180) (layer "B.Fab") hide
        (effects (font (size 0.7 0.7) (thickness 0.15)) (justify left bottom mirror))
    )
    (fp_text user "License: Apache-2.0" (at -3.476 -5.099 180) (layer "B.Fab") hide
        (effects (font (size 0.7 0.7) (thickness 0.15)) (justify left bottom mirror))
    )
    (fp_text user "Author: Antmicro" (at -3.476 -6.099 180) (layer "B.Fab") hide
        (effects (font (size 0.7 0.7) (thickness 0.15)) (justify left bottom mirror))
    )
    (fp_line (start 1.95 -2.55) (end -1.95 -2.55)
      (stroke (width 0.15) (type solid)) (layer "B.SilkS"))
    (fp_line (start 1.95 2.55) (end -1.95 2.55)
      (stroke (width 0.15) (type solid)) (layer "B.SilkS"))
    (fp_circle (center -2.5 2.45) (end -2.45 2.4)
      (stroke (width 0.15) (type solid)) (fill solid) (layer "B.SilkS"))
    (fp_rect (start -3.55 2.7) (end 3.55 -2.7)
      (stroke (width 0.05) (type solid)) (fill none) (layer "B.CrtYd"))
    (fp_line (start -1.95 -2.45) (end -1.95 1.18)
      (stroke (width 0.15) (type solid)) (layer "B.Fab"))
    (fp_line (start -1.95 1.18) (end -0.683 2.452)
      (stroke (width 0.15) (type solid)) (layer "B.Fab"))
    (fp_line (start -0.683 2.452) (end 1.949 2.452)
      (stroke (width 0.15) (type solid)) (layer "B.Fab"))
    (fp_line (start 1.949 -2.45) (end -1.95 -2.45)
      (stroke (width 0.15) (type solid)) (layer "B.Fab"))
    (fp_line (start 1.949 2.452) (end 1.949 -2.45)
      (stroke (width 0.15) (type solid)) (layer "B.Fab"))
    (pad "1" smd roundrect (at -2.714 1.905 270) (size 0.65 1.525) (layers "B.Cu" "B.Paste" "B.Mask") (roundrect_rratio 0.25)
      (net 6 "/PoE/VDD_POE_IN") (pinfunction "VDD") (pintype "power_in"))
    (pad "2" smd roundrect (at -2.714 0.635 270) (size 0.65 1.525) (layers "B.Cu" "B.Paste" "B.Mask") (roundrect_rratio 0.25)
      (net 256 "Net-(U8-DEN)") (pinfunction "DEN") (pintype "passive"))
    (pad "3" smd roundrect (at -2.714 -0.632 270) (size 0.65 1.525) (layers "B.Cu" "B.Paste" "B.Mask") (roundrect_rratio 0.25)
      (net 255 "Net-(U8-CLS)") (pinfunction "CLS") (pintype "passive"))
    (pad "4" smd roundrect (at -2.714 -1.902 270) (size 0.65 1.525) (layers "B.Cu" "B.Paste" "B.Mask") (roundrect_rratio 0.25)
      (net 5 "VSS") (pinfunction "VSS") (pintype "power_in"))
    (pad "5" smd roundrect (at 2.712 -1.902 270) (size 0.65 1.525) (layers "B.Cu" "B.Paste" "B.Mask") (roundrect_rratio 0.25)
      (net 4 "GNDD") (pinfunction "RTN") (pintype "passive"))
    (pad "6" smd roundrect (at 2.712 -0.632 270) (size 0.65 1.525) (layers "B.Cu" "B.Paste" "B.Mask") (roundrect_rratio 0.25)
      (net 34 "/PoE/POE_ACTIVE") (pinfunction "CDB") (pintype "passive"))
    (pad "7" smd roundrect (at 2.712 0.635 270) (size 0.65 1.525) (layers "B.Cu" "B.Paste" "B.Mask") (roundrect_rratio 0.25)
      (net 278 "unconnected-(U8-T2P-Pad7)") (pinfunction "T2P") (pintype "passive+no_connect"))
    (pad "8" smd roundrect (at 2.712 1.905 270) (size 0.65 1.525) (layers "B.Cu" "B.Paste" "B.Mask") (roundrect_rratio 0.25)
      (net 4 "GNDD") (pinfunction "APD") (pintype "passive"))
    (pad "9" smd roundrect (at 0 0) (size 2.29 3.1) (layers "B.Cu" "B.Paste" "B.Mask") (roundrect_rratio 0.05)
      (net 5 "VSS") (pinfunction "EP") (pintype "power_in"))
  )

  (footprint "scalenode-cm4-baseboard-footprints:Bus_M.2_Socket_Key_M_Amphenol_MDT580M01001" locked (layer "B.Cu")
    (at 183.464 76.877 90)
    (property "Author" "Antmicro")
    (property "License" "Apache-2.0")
    (property "MPN" "MDT580M01001")
    (property "Manufacturer" "Amphenol")
    (property "Sheetfile" "nvme-ssd.kicad_sch")
    (property "Sheetname" "NVMe SSD")
    (property "ki_description" "PCI Express / PCI Connectors M.2 RA M Key 5.80H")
    (attr smd)
    (fp_text reference "J3" (at -10.013 5.926 90) (layer "B.SilkS")
        (effects (font (size 0.7 0.7) (thickness 0.15)) (justify right bottom mirror))
    )
    (fp_text value "Bus_M.2_MDT580M01001" (at 0 -5.9 90) (layer "B.Fab")
        (effects (font (size 0.7 0.7) (thickness 0.15)) (justify right bottom mirror))
    )
    (fp_text user "License: Apache-2.0" (at -13 -10.899 90) (layer "B.Fab") hide
        (effects (font (size 0.7 0.7) (thickness 0.15)) (justify right bottom mirror))
    )
    (fp_text user "Author: Antmicro" (at -13 -8.499 90) (layer "B.Fab") hide
        (effects (font (size 0.7 0.7) (thickness 0.15)) (justify right bottom mirror))
    )
    (fp_text user "${REFERENCE}" (at -13 -9.698 90) (layer "B.Fab") hide
        (effects (font (size 0.7 0.7) (thickness 0.15)) (justify right bottom mirror))
    )
    (fp_line (start -10.071 -4.626) (end -11.151 -4.626)
      (stroke (width 0.15) (type solid)) (layer "B.SilkS"))
    (fp_line (start -10.071 -4.626) (end -10.071 -2.205)
      (stroke (width 0.15) (type solid)) (layer "B.SilkS"))
    (fp_line (start -10.071 -0.624) (end 9.499 -0.624)
      (stroke (width 0.15) (type solid)) (layer "B.SilkS"))
    (fp_line (start 9.768 -4.626) (end 9.768 -2.346)
      (stroke (width 0.15) (type solid)) (layer "B.SilkS"))
    (fp_line (start 10.848 -4.626) (end 9.768 -4.626)
      (stroke (width 0.15) (type solid)) (layer "B.SilkS"))
    (fp_circle (center -9.7 4.7) (end -9.65 4.7)
      (stroke (width 0.15) (type solid)) (fill solid) (layer "B.SilkS"))
    (fp_rect (start -11.5 5) (end 11.5 -4.9)
      (stroke (width 0.05) (type solid)) (fill none) (layer "B.CrtYd"))
    (fp_line (start -10.985 4.13) (end -10.859 4.255)
      (stroke (width 0.15) (type solid)) (layer "B.Fab"))
    (fp_rect (start -11 -4.275) (end 10.999 4.276)
      (stroke (width 0.15) (type solid)) (fill none) (layer "B.Fab"))
    (pad "" np_thru_hole circle locked (at -10 -1.425 90) (size 1.1 1.1) (drill 1.1) (layers "F&B.Cu" "*.Mask"))
    (pad "" np_thru_hole circle locked (at 9.999 -1.425 90) (size 1.6 1.6) (drill 1.6) (layers "F&B.Cu" "*.Mask"))
    (pad "1" smd rect locked (at -9.25 3.848 90) (size 0.3 1.55) (layers "B.Cu" "B.Paste" "B.Mask")
      (net 11 "GND") (pinfunction "GND") (pintype "passive"))
    (pad "2" smd rect locked (at -9 -3.7 90) (size 0.3 1.55) (layers "B.Cu" "B.Paste" "B.Mask")
      (net 170 "3V3_SSD") (pinfunction "3V3") (pintype "passive"))
    (pad "3" smd rect locked (at -8.75 3.848 90) (size 0.3 1.55) (layers "B.Cu" "B.Paste" "B.Mask")
      (net 11 "GND") (pinfunction "GND") (pintype "passive"))
    (pad "4" smd rect locked (at -8.5 -3.7 90) (size 0.3 1.55) (layers "B.Cu" "B.Paste" "B.Mask")
      (net 170 "3V3_SSD") (pinfunction "3V3") (pintype "passive"))
    (pad "5" smd rect locked (at -8.25 3.848 90) (size 0.3 1.55) (layers "B.Cu" "B.Paste" "B.Mask")
      (net 163 "unconnected-(J3-PER3_N-Pad5)") (pinfunction "PER3_N") (pintype "passive+no_connect"))
    (pad "6" smd rect locked (at -8 -3.7 90) (size 0.3 1.55) (layers "B.Cu" "B.Paste" "B.Mask")
      (net 164 "unconnected-(J3-NC-Pad6)") (pinfunction "NC") (pintype "no_connect"))
    (pad "7" smd rect locked (at -7.75 3.848 90) (size 0.3 1.55) (layers "B.Cu" "B.Paste" "B.Mask")
      (net 165 "unconnected-(J3-PER3_P-Pad7)") (pinfunction "PER3_P") (pintype "passive+no_connect"))
    (pad "8" smd rect locked (at -7.5 -3.7 90) (size 0.3 1.55) (layers "B.Cu" "B.Paste" "B.Mask")
      (net 166 "unconnected-(J3-NC-Pad8)") (pinfunction "NC") (pintype "no_connect"))
    (pad "9" smd rect locked (at -7.25 3.848 90) (size 0.3 1.55) (layers "B.Cu" "B.Paste" "B.Mask")
      (net 11 "GND") (pinfunction "GND") (pintype "passive"))
    (pad "10" smd rect locked (at -7 -3.7 90) (size 0.3 1.55) (layers "B.Cu" "B.Paste" "B.Mask")
      (net 26 "Net-(J3-LED)") (pinfunction "LED") (pintype "passive"))
    (pad "11" smd rect locked (at -6.75 3.848 90) (size 0.3 1.55) (layers "B.Cu" "B.Paste" "B.Mask")
      (net 167 "unconnected-(J3-PET3_N-Pad11)") (pinfunction "PET3_N") (pintype "passive+no_connect"))
    (pad "12" smd rect locked (at -6.5 -3.7 90) (size 0.3 1.55) (layers "B.Cu" "B.Paste" "B.Mask")
      (net 170 "3V3_SSD") (pinfunction "3V3") (pintype "passive"))
    (pad "13" smd rect locked (at -6.25 3.848 90) (size 0.3 1.55) (layers "B.Cu" "B.Paste" "B.Mask")
      (net 168 "unconnected-(J3-PET3_P-Pad13)") (pinfunction "PET3_P") (pintype "passive+no_connect"))
    (pad "14" smd rect locked (at -6 -3.7 90) (size 0.3 1.55) (layers "B.Cu" "B.Paste" "B.Mask")
      (net 170 "3V3_SSD") (pinfunction "3V3") (pintype "passive"))
    (pad "15" smd rect locked (at -5.75 3.848 90) (size 0.3 1.55) (layers "B.Cu" "B.Paste" "B.Mask")
      (net 11 "GND") (pinfunction "GND") (pintype "passive"))
    (pad "16" smd rect locked (at -5.5 -3.7 90) (size 0.3 1.55) (layers "B.Cu" "B.Paste" "B.Mask")
      (net 170 "3V3_SSD") (pinfunction "3V3") (pintype "passive"))
    (pad "17" smd rect locked (at -5.25 3.848 90) (size 0.3 1.55) (layers "B.Cu" "B.Paste" "B.Mask")
      (net 169 "unconnected-(J3-PER2_N-Pad17)") (pinfunction "PER2_N") (pintype "passive+no_connect"))
    (pad "18" smd rect locked (at -5 -3.7 90) (size 0.3 1.55) (layers "B.Cu" "B.Paste" "B.Mask")
      (net 170 "3V3_SSD") (pinfunction "3V3") (pintype "passive"))
    (pad "19" smd rect locked (at -4.75 3.848 90) (size 0.3 1.55) (layers "B.Cu" "B.Paste" "B.Mask")
      (net 171 "unconnected-(J3-PER2_P-Pad19)") (pinfunction "PER2_P") (pintype "passive+no_connect"))
    (pad "20" smd rect locked (at -4.5 -3.7 90) (size 0.3 1.55) (layers "B.Cu" "B.Paste" "B.Mask")
      (net 172 "unconnected-(J3-NC-Pad20)") (pinfunction "NC") (pintype "no_connect"))
    (pad "21" smd rect locked (at -4.25 3.848 90) (size 0.3 1.55) (layers "B.Cu" "B.Paste" "B.Mask")
      (net 11 "GND") (pinfunction "GND") (pintype "passive"))
    (pad "22" smd rect locked (at -4 -3.7 90) (size 0.3 1.55) (layers "B.Cu" "B.Paste" "B.Mask")
      (net 173 "unconnected-(J3-NC-Pad22)") (pinfunction "NC") (pintype "no_connect"))
    (pad "23" smd rect locked (at -3.75 3.848 90) (size 0.3 1.55) (layers "B.Cu" "B.Paste" "B.Mask")
      (net 174 "unconnected-(J3-PET2_N-Pad23)") (pinfunction "PET2_N") (pintype "passive+no_connect"))
    (pad "24" smd rect locked (at -3.5 -3.7 90) (size 0.3 1.55) (layers "B.Cu" "B.Paste" "B.Mask")
      (net 176 "unconnected-(J3-NC-Pad24)") (pinfunction "NC") (pintype "no_connect"))
    (pad "25" smd rect locked (at -3.25 3.848 90) (size 0.3 1.55) (layers "B.Cu" "B.Paste" "B.Mask")
      (net 177 "unconnected-(J3-PET2_P-Pad25)") (pinfunction "PET2_P") (pintype "passive+no_connect"))
    (pad "26" smd rect locked (at -3 -3.7 90) (size 0.3 1.55) (layers "B.Cu" "B.Paste" "B.Mask")
      (net 178 "unconnected-(J3-NC-Pad26)") (pinfunction "NC") (pintype "no_connect"))
    (pad "27" smd rect locked (at -2.75 3.848 90) (size 0.3 1.55) (layers "B.Cu" "B.Paste" "B.Mask")
      (net 11 "GND") (pinfunction "GND") (pintype "passive"))
    (pad "28" smd rect locked (at -2.5 -3.7 90) (size 0.3 1.55) (layers "B.Cu" "B.Paste" "B.Mask")
      (net 179 "unconnected-(J3-NC-Pad28)") (pinfunction "NC") (pintype "no_connect"))
    (pad "29" smd rect locked (at -2.25 3.848 90) (size 0.3 1.55) (layers "B.Cu" "B.Paste" "B.Mask")
      (net 180 "unconnected-(J3-PER1_N-Pad29)") (pinfunction "PER1_N") (pintype "passive+no_connect"))
    (pad "30" smd rect locked (at -2 -3.7 90) (size 0.3 1.55) (layers "B.Cu" "B.Paste" "B.Mask")
      (net 181 "unconnected-(J3-NC-Pad30)") (pinfunction "NC") (pintype "no_connect"))
    (pad "31" smd rect locked (at -1.75 3.848 90) (size 0.3 1.55) (layers "B.Cu" "B.Paste" "B.Mask")
      (net 182 "unconnected-(J3-PER1_P-Pad31)") (pinfunction "PER1_P") (pintype "passive+no_connect"))
    (pad "32" smd rect locked (at -1.5 -3.7 90) (size 0.3 1.55) (layers "B.Cu" "B.Paste" "B.Mask")
      (net 183 "unconnected-(J3-NC-Pad32)") (pinfunction "NC") (pintype "no_connect"))
    (pad "33" smd rect locked (at -1.25 3.848 90) (size 0.3 1.55) (layers "B.Cu" "B.Paste" "B.Mask")
      (net 11 "GND") (pinfunction "GND") (pintype "passive"))
    (pad "34" smd rect locked (at -1 -3.7 90) (size 0.3 1.55) (layers "B.Cu" "B.Paste" "B.Mask")
      (net 184 "unconnected-(J3-NC-Pad34)") (pinfunction "NC") (pintype "no_connect"))
    (pad "35" smd rect locked (at -0.75 3.848 90) (size 0.3 1.55) (layers "B.Cu" "B.Paste" "B.Mask")
      (net 185 "unconnected-(J3-PET1_N-Pad35)") (pinfunction "PET1_N") (pintype "passive+no_connect"))
    (pad "36" smd rect locked (at -0.5 -3.7 90) (size 0.3 1.55) (layers "B.Cu" "B.Paste" "B.Mask")
      (net 186 "unconnected-(J3-NC-Pad36)") (pinfunction "NC") (pintype "no_connect"))
    (pad "37" smd rect locked (at -0.25 3.848 90) (size 0.3 1.55) (layers "B.Cu" "B.Paste" "B.Mask")
      (net 187 "unconnected-(J3-PET1_P-Pad37)") (pinfunction "PET1_P") (pintype "passive+no_connect"))
    (pad "38" smd rect locked (at 0 -3.7 90) (size 0.3 1.55) (layers "B.Cu" "B.Paste" "B.Mask")
      (net 189 "unconnected-(J3-NC-Pad38)") (pinfunction "NC") (pintype "no_connect"))
    (pad "39" smd rect locked (at 0.246 3.848 90) (size 0.3 1.55) (layers "B.Cu" "B.Paste" "B.Mask")
      (net 11 "GND") (pinfunction "GND") (pintype "passive"))
    (pad "40" smd rect locked (at 0.496 -3.7 90) (size 0.3 1.55) (layers "B.Cu" "B.Paste" "B.Mask")
      (net 190 "unconnected-(J3-SMB_CLK-Pad40)") (pinfunction "SMB_CLK") (pintype "passive+no_connect"))
    (pad "41" smd rect locked (at 0.747 3.848 90) (size 0.3 1.55) (layers "B.Cu" "B.Paste" "B.Mask")
      (net 16 "PCIE_RX_N") (pinfunction "PER0_N") (pintype "passive"))
    (pad "42" smd rect locked (at 0.996 -3.7 90) (size 0.3 1.55) (layers "B.Cu" "B.Paste" "B.Mask")
      (net 192 "unconnected-(J3-SMB_DATA-Pad42)") (pinfunction "SMB_DATA") (pintype "passive+no_connect"))
    (pad "43" smd rect locked (at 1.249 3.848 90) (size 0.3 1.55) (layers "B.Cu" "B.Paste" "B.Mask")
      (net 18 "PCIE_RX_P") (pinfunction "PER0_P") (pintype "passive"))
    (pad "44" smd rect locked (at 1.499 -3.7 90) (size 0.3 1.55) (layers "B.Cu" "B.Paste" "B.Mask")
      (net 193 "unconnected-(J3-ALERT-Pad44)") (pinfunction "ALERT") (pintype "passive+no_connect"))
    (pad "45" smd rect locked (at 1.749 3.848 90) (size 0.3 1.55) (layers "B.Cu" "B.Paste" "B.Mask")
      (net 11 "GND") (pinfunction "GND") (pintype "passive"))
    (pad "46" smd rect locked (at 1.999 -3.7 90) (size 0.3 1.55) (layers "B.Cu" "B.Paste" "B.Mask")
      (net 194 "unconnected-(J3-NC-Pad46)") (pinfunction "NC") (pintype "no_connect"))
    (pad "47" smd rect locked (at 2.249 3.848 90) (size 0.3 1.55) (layers "B.Cu" "B.Paste" "B.Mask")
      (net 15 "PCIE_TX_N") (pinfunction "PET0_N") (pintype "passive"))
    (pad "48" smd rect locked (at 2.499 -3.7 90) (size 0.3 1.55) (layers "B.Cu" "B.Paste" "B.Mask")
      (net 195 "unconnected-(J3-NC-Pad48)") (pinfunction "NC") (pintype "no_connect"))
    (pad "49" smd rect locked (at 2.749 3.848 90) (size 0.3 1.55) (layers "B.Cu" "B.Paste" "B.Mask")
      (net 17 "PCIE_TX_P") (pinfunction "PET0_P") (pintype "passive"))
    (pad "50" smd rect locked (at 2.999 -3.7 90) (size 0.3 1.55) (layers "B.Cu" "B.Paste" "B.Mask")
      (net 99 "PSCIE_nRST") (pinfunction "PERST#") (pintype "passive"))
    (pad "51" smd rect locked (at 3.249 3.848 90) (size 0.3 1.55) (layers "B.Cu" "B.Paste" "B.Mask")
      (net 11 "GND") (pinfunction "GND") (pintype "passive"))
    (pad "52" smd rect locked (at 3.499 -3.7 90) (size 0.3 1.55) (layers "B.Cu" "B.Paste" "B.Mask")
      (net 96 "PCIE_CLK_nREQ") (pinfunction "CLKREQ#") (pintype "passive"))
    (pad "53" smd rect locked (at 3.749 3.848 90) (size 0.3 1.55) (layers "B.Cu" "B.Paste" "B.Mask")
      (net 102 "PCIE_CLK_N") (pinfunction "REFCLK_N") (pintype "passive"))
    (pad "54" smd rect locked (at 3.999 -3.7 90) (size 0.3 1.55) (layers "B.Cu" "B.Paste" "B.Mask")
      (net 162 "PCIE_WAKE") (pinfunction "PEWAKE#") (pintype "passive"))
    (pad "55" smd rect locked (at 4.248 3.848 90) (size 0.3 1.55) (layers "B.Cu" "B.Paste" "B.Mask")
      (net 100 "PCIE_CLK_P") (pinfunction "REFCLK_P") (pintype "passive"))
    (pad "56" smd rect locked (at 4.498 -3.7 90) (size 0.3 1.55) (layers "B.Cu" "B.Paste" "B.Mask")
      (net 196 "unconnected-(J3-NC-Pad56)") (pinfunction "NC") (pintype "no_connect"))
    (pad "57" smd rect locked (at 4.748 3.848 90) (size 0.3 1.55) (layers "B.Cu" "B.Paste" "B.Mask")
      (net 11 "GND") (pinfunction "GND") (pintype "passive"))
    (pad "58" smd rect locked (at 4.998 -3.7 90) (size 0.3 1.55) (layers "B.Cu" "B.Paste" "B.Mask")
      (net 197 "unconnected-(J3-NC-Pad58)") (pinfunction "NC") (pintype "no_connect"))
    (pad "67" smd rect locked (at 7.249 3.848 90) (size 0.3 1.55) (layers "B.Cu" "B.Paste" "B.Mask")
      (net 198 "unconnected-(J3-NC-Pad67)") (pinfunction "NC") (pintype "no_connect"))
    (pad "68" smd rect locked (at 7.498 -3.7 90) (size 0.3 1.55) (layers "B.Cu" "B.Paste" "B.Mask")
      (net 199 "unconnected-(J3-SUSCLK-Pad68)") (pinfunction "SUSCLK") (pintype "passive+no_connect"))
    (pad "69" smd rect locked (at 7.748 3.848 90) (size 0.3 1.55) (layers "B.Cu" "B.Paste" "B.Mask")
      (net 200 "unconnected-(J3-NC-Pad69)") (pinfunction "NC") (pintype "no_connect"))
    (pad "70" smd rect locked (at 7.998 -3.7 90) (size 0.3 1.55) (layers "B.Cu" "B.Paste" "B.Mask")
      (net 170 "3V3_SSD") (pinfunction "3V3") (pintype "passive"))
    (pad "71" smd rect locked (at 8.249 3.848 90) (size 0.3 1.55) (layers "B.Cu" "B.Paste" "B.Mask")
      (net 11 "GND") (pinfunction "GND") (pintype "passive"))
    (pad "72" smd rect locked (at 8.499 -3.7 90) (size 0.3 1.55) (layers "B.Cu" "B.Paste" "B.Mask")
      (net 170 "3V3_SSD") (pinfunction "3V3") (pintype "passive"))
    (pad "73" smd rect locked (at 8.749 3.848 90) (size 0.3 1.55) (layers "B.Cu" "B.Paste" "B.Mask")
      (net 11 "GND") (pinfunction "GND") (pintype "passive"))
    (pad "74" smd rect locked (at 8.999 -3.7 90) (size 0.3 1.55) (layers "B.Cu" "B.Paste" "B.Mask")
      (net 170 "3V3_SSD") (pinfunction "3V3") (pintype "passive"))
    (pad "75" smd rect locked (at 9.249 3.848 90) (size 0.3 1.55) (layers "B.Cu" "B.Paste" "B.Mask")
      (net 11 "GND") (pinfunction "GND") (pintype "passive"))
    (pad "SH1" smd rect locked (at -10.35 3.073 90) (size 1.2 2.75) (layers "B.Cu" "B.Paste" "B.Mask")
      (net 11 "GND") (pinfunction "SHIELD") (pintype "passive"))
    (pad "SH2" smd rect locked (at 10.348 3.073 90) (size 1.2 2.75) (layers "B.Cu" "B.Paste" "B.Mask")
      (net 11 "GND") (pinfunction "SHIELD") (pintype "passive"))
  )

  (footprint "scalenode-cm4-baseboard-footprints:R_0603_1608Metric" (layer "B.Cu")
    (at 177.594 70.146 -90)
    (descr "Resistor SMD 0603")
    (tags "resistor SMD 0603")
    (property "Author" "Antmicro")
    (property "License" "Apache-2.0")
    (property "MPN" "CR0603-FX-1002ELF")
    (property "Manufacturer" "Bourns")
    (property "Sheetfile" "nvme-ssd.kicad_sch")
    (property "Sheetname" "NVMe SSD")
    (property "Tolerance" "1%")
    (property "Val" "10k")
    (property "ki_description" "10k resistor in 0603 package with 1% tolerance")
    (attr smd)
    (fp_text reference "R1" (at 1.471048 -0.377352 90) (layer "B.SilkS")
        (effects (font (size 0.7 0.7) (thickness 0.15)) (justify left bottom mirror))
    )
    (fp_text value "R_10k_0603" (at 0 -1.6 90) (layer "B.Fab")
        (effects (font (size 0.7 0.7) (thickness 0.15)) (justify left bottom mirror))
    )
    (fp_text user "License: Apache-2.0" (at -1.25 -5.9 90) (layer "B.Fab") hide
        (effects (font (size 0.7 0.7) (thickness 0.15)) (justify left bottom mirror))
    )
    (fp_text user "${REFERENCE}" (at -1.25 -3.898 90) (layer "B.Fab") hide
        (effects (font (size 0.7 0.7) (thickness 0.15)) (justify left bottom mirror))
    )
    (fp_text user "Author: Antmicro" (at -1.25 -4.9 90) (layer "B.Fab") hide
        (effects (font (size 0.7 0.7) (thickness 0.15)) (justify left bottom mirror))
    )
    (fp_line (start -0.3 -0.3) (end 0.3 -0.3)
      (stroke (width 0.15) (type solid)) (layer "B.SilkS"))
    (fp_line (start -0.3 0.3) (end 0.3 0.3)
      (stroke (width 0.15) (type solid)) (layer "B.SilkS"))
    (fp_rect (start -1.25 0.7) (end 1.25 -0.7)
      (stroke (width 0.05) (type solid)) (fill none) (layer "B.CrtYd"))
    (fp_rect (start -0.8 0.4) (end 0.8 -0.4)
      (stroke (width 0.15) (type solid)) (fill none) (layer "B.Fab"))
    (pad "1" smd roundrect (at -0.7 0 270) (size 0.6 0.8) (layers "B.Cu" "B.Paste" "B.Mask") (roundrect_rratio 0.2)
      (net 170 "3V3_SSD") (pintype "passive"))
    (pad "2" smd roundrect (at 0.7 0 270) (size 0.6 0.8) (layers "B.Cu" "B.Paste" "B.Mask") (roundrect_rratio 0.2)
      (net 162 "PCIE_WAKE") (pintype "passive"))
  )

  (footprint "scalenode-cm4-baseboard-footprints:C_0603_1608Metric" (layer "B.Cu")
    (at 134.8 93.496 -90)
    (descr "Capacitor SMD 0603")
    (tags "capacitor 0603")
    (property "Author" "Antmicro")
    (property "Dielectric" "")
    (property "License" "Apache-2.0")
    (property "MPN" "GRM188R60J476ME15D")
    (property "Manufacturer" "Murata")
    (property "Sheetfile" "poe.kicad_sch")
    (property "Sheetname" "PoE")
    (property "Val" "47u")
    (property "Voltage" "")
    (property "ki_description" " ")
    (attr smd)
    (fp_text reference "C36" (at -1.071 -1.65 90) (layer "B.SilkS")
        (effects (font (size 0.7 0.7) (thickness 0.15)) (justify left bottom mirror))
    )
    (fp_text value "C_47u_0603" (at -8.371 0.345 90) (layer "B.Fab")
        (effects (font (size 0.7 0.7) (thickness 0.15)) (justify left bottom mirror))
    )
    (fp_text user "${REFERENCE}" (at -1.682 -3.895 90) (layer "B.Fab") hide
        (effects (font (size 0.7 0.7) (thickness 0.15)) (justify left bottom mirror))
    )
    (fp_text user "License: Apache-2.0" (at -1.682 -5.895 90) (layer "B.Fab") hide
        (effects (font (size 0.7 0.7) (thickness 0.15)) (justify left bottom mirror))
    )
    (fp_text user "Author: Antmicro" (at -1.682 -4.894 90) (layer "B.Fab") hide
        (effects (font (size 0.7 0.7) (thickness 0.15)) (justify left bottom mirror))
    )
    (fp_line (start -0.3 -0.3) (end 0.3 -0.3)
      (stroke (width 0.15) (type solid)) (layer "B.SilkS"))
    (fp_line (start -0.3 0.3) (end 0.3 0.3)
      (stroke (width 0.15) (type solid)) (layer "B.SilkS"))
    (fp_rect (start -1.24 0.7) (end 1.24 -0.7)
      (stroke (width 0.05) (type solid)) (fill none) (layer "B.CrtYd"))
    (fp_rect (start -0.8 0.4) (end 0.8 -0.4)
      (stroke (width 0.15) (type solid)) (fill none) (layer "B.Fab"))
    (pad "1" smd roundrect (at -0.7 0 270) (size 0.6 0.8) (layers "B.Cu" "B.Paste" "B.Mask") (roundrect_rratio 0.2)
      (net 11 "GND") (pintype "passive"))
    (pad "2" smd roundrect (at 0.7 0 270) (size 0.6 0.8) (layers "B.Cu" "B.Paste" "B.Mask") (roundrect_rratio 0.2)
      (net 13 "/PoE/VO5V") (pintype "passive"))
  )

  (footprint "scalenode-cm4-baseboard-footprints:C_0402_1005Metric" (layer "B.Cu")
    (at 101.233401 73.516445 -90)
    (descr "Capacitor SMD 0402")
    (tags "capacitor SMD 0402")
    (property "Author" "Antmicro")
    (property "Dielectric" "X7R")
    (property "License" "Apache-2.0")
    (property "MPN" "GRM155R71H103KA88D")
    (property "Manufacturer" "Murata")
    (property "Sheetfile" "poe.kicad_sch")
    (property "Sheetname" "PoE")
    (property "Val" "10n")
    (property "Voltage" "50V")
    (property "ki_description" " ")
    (attr smd)
    (fp_text reference "C27" (at -3.176445 -0.386599 -270) (layer "B.SilkS")
        (effects (font (size 0.7 0.7) (thickness 0.15)) (justify left bottom mirror))
    )
    (fp_text value "C_10n_0402" (at 0 -1.4 -270) (layer "B.Fab")
        (effects (font (size 0.7 0.7) (thickness 0.15)) (justify left bottom mirror))
    )
    (fp_text user "${REFERENCE}" (at -0.932 -3.168 -270) (layer "B.Fab") hide
        (effects (font (size 0.7 0.7) (thickness 0.15)) (justify left bottom mirror))
    )
    (fp_text user "Author: Antmicro" (at -0.932 -4.17 -270) (layer "B.Fab") hide
        (effects (font (size 0.7 0.7) (thickness 0.15)) (justify left bottom mirror))
    )
    (fp_text user "License: Apache-2.0" (at -0.932 -5.17 -270) (layer "B.Fab") hide
        (effects (font (size 0.7 0.7) (thickness 0.15)) (justify left bottom mirror))
    )
    (fp_rect (start -0.94 0.47) (end 0.94 -0.47)
      (stroke (width 0.05) (type solid)) (fill none) (layer "B.CrtYd"))
    (fp_rect (start -0.499 0.249) (end 0.499 -0.249)
      (stroke (width 0.15) (type solid)) (fill none) (layer "B.Fab"))
    (pad "1" smd roundrect (at -0.484 0 270) (size 0.59 0.64) (layers "B.Cu" "B.Paste" "B.Mask") (roundrect_rratio 0.25)
      (net 7 "Net-(C27-Pad1)") (pintype "passive"))
    (pad "2" smd roundrect (at 0.484 0 270) (size 0.59 0.64) (layers "B.Cu" "B.Paste" "B.Mask") (roundrect_rratio 0.25)
      (net 1 "/PoE/PAIR12") (pintype "passive"))
  )

  (footprint "scalenode-cm4-baseboard-footprints:C_0402_1005Metric" (layer "B.Cu")
    (at 102.8 64.506 180)
    (descr "Capacitor SMD 0402")
    (tags "capacitor SMD 0402")
    (property "Author" "Antmicro")
    (property "Dielectric" "X7R")
    (property "License" "Apache-2.0")
    (property "MPN" "GRM155R71H103KA88D")
    (property "Manufacturer" "Murata")
    (property "Sheetfile" "poe.kicad_sch")
    (property "Sheetname" "PoE")
    (property "Val" "10n")
    (property "Voltage" "50V")
    (property "ki_description" " ")
    (attr smd)
    (fp_text reference "C34" (at -1.15 0.731) (layer "B.SilkS")
        (effects (font (size 0.7 0.7) (thickness 0.15)) (justify left bottom mirror))
    )
    (fp_text value "C_10n_0402" (at 0 -1.4) (layer "B.Fab")
        (effects (font (size 0.7 0.7) (thickness 0.15)) (justify left bottom mirror))
    )
    (fp_text user "License: Apache-2.0" (at -0.932 -5.17) (layer "B.Fab") hide
        (effects (font (size 0.7 0.7) (thickness 0.15)) (justify left bottom mirror))
    )
    (fp_text user "${REFERENCE}" (at -0.932 -3.168) (layer "B.Fab") hide
        (effects (font (size 0.7 0.7) (thickness 0.15)) (justify left bottom mirror))
    )
    (fp_text user "Author: Antmicro" (at -0.932 -4.17) (layer "B.Fab") hide
        (effects (font (size 0.7 0.7) (thickness 0.15)) (justify left bottom mirror))
    )
    (fp_rect (start -0.94 0.47) (end 0.94 -0.47)
      (stroke (width 0.05) (type solid)) (fill none) (layer "B.CrtYd"))
    (fp_rect (start -0.499 0.249) (end 0.499 -0.249)
      (stroke (width 0.15) (type solid)) (fill none) (layer "B.Fab"))
    (pad "1" smd roundrect (at -0.484 0 180) (size 0.59 0.64) (layers "B.Cu" "B.Paste" "B.Mask") (roundrect_rratio 0.25)
      (net 14 "Net-(C34-Pad1)") (pintype "passive"))
    (pad "2" smd roundrect (at 0.484 0 180) (size 0.59 0.64) (layers "B.Cu" "B.Paste" "B.Mask") (roundrect_rratio 0.25)
      (net 20 "/PoE/PAIR78") (pintype "passive"))
  )

  (footprint "scalenode-cm4-baseboard-footprints:C_0402_1005Metric" (layer "B.Cu")
    (at 132 93.181 -90)
    (descr "Capacitor SMD 0402")
    (tags "capacitor SMD 0402")
    (property "Author" "Antmicro")
    (property "Dielectric" "X5R")
    (property "License" "Apache-2.0")
    (property "MPN" "GRM155R61H104KE14D")
    (property "Manufacturer" "Murata")
    (property "Sheetfile" "poe.kicad_sch")
    (property "Sheetname" "PoE")
    (property "Val" "100n")
    (property "Voltage" "50V")
    (property "ki_description" " ")
    (attr smd)
    (fp_text reference "C37" (at -0.981 0.65 90) (layer "B.SilkS")
        (effects (font (size 0.7 0.7) (thickness 0.15)) (justify left bottom mirror))
    )
    (fp_text value "C_100n_0402" (at -7.511 -0.28 90) (layer "B.Fab")
        (effects (font (size 0.7 0.7) (thickness 0.15)) (justify left bottom mirror))
    )
    (fp_text user "${REFERENCE}" (at -0.932 -3.168 90) (layer "B.Fab") hide
        (effects (font (size 0.7 0.7) (thickness 0.15)) (justify left bottom mirror))
    )
    (fp_text user "License: Apache-2.0" (at -0.932 -5.17 90) (layer "B.Fab") hide
        (effects (font (size 0.7 0.7) (thickness 0.15)) (justify left bottom mirror))
    )
    (fp_text user "Author: Antmicro" (at -0.932 -4.17 90) (layer "B.Fab") hide
        (effects (font (size 0.7 0.7) (thickness 0.15)) (justify left bottom mirror))
    )
    (fp_rect (start -0.94 0.47) (end 0.94 -0.47)
      (stroke (width 0.05) (type solid)) (fill none) (layer "B.CrtYd"))
    (fp_rect (start -0.499 0.249) (end 0.499 -0.249)
      (stroke (width 0.15) (type solid)) (fill none) (layer "B.Fab"))
    (pad "1" smd roundrect (at -0.484 0 270) (size 0.59 0.64) (layers "B.Cu" "B.Paste" "B.Mask") (roundrect_rratio 0.25)
      (net 11 "GND") (pintype "passive"))
    (pad "2" smd roundrect (at 0.484 0 270) (size 0.59 0.64) (layers "B.Cu" "B.Paste" "B.Mask") (roundrect_rratio 0.25)
      (net 13 "/PoE/VO5V") (pintype "passive"))
  )

  (footprint "scalenode-cm4-baseboard-footprints:F_1206_3216Metric" (layer "B.Cu")
    (at 127 91.896 180)
    (property "Author" "Antmicro")
    (property "License" "Apache-2.0")
    (property "MPN" "1206L450SLWR")
    (property "Manufacturer" "Littelfuse")
    (property "Sheetfile" "poe.kicad_sch")
    (property "Sheetname" "PoE")
    (property "ki_description" "POLY-FUSE LoRho Series, 6 VDC, 4.5 A")
    (property "ki_keywords" "fuse ptc pptc 1206L450SLWR")
    (attr smd)
    (fp_text reference "F1" (at -0.675 1.196) (layer "B.SilkS")
        (effects (font (size 0.7 0.7) (thickness 0.15)) (justify left bottom mirror))
    )
    (fp_text value "PTC_4.5A_1206" (at 0 -2) (layer "B.Fab")
        (effects (font (size 0.7 0.7) (thickness 0.15)) (justify left bottom mirror))
    )
    (fp_text user "License: Apache-2.0" (at -1.95 -5.2) (layer "B.Fab") hide
        (effects (font (size 0.7 0.7) (thickness 0.15)) (justify left bottom mirror))
    )
    (fp_text user "${REFERENCE}" (at -1.95 -4) (layer "B.Fab") hide
        (effects (font (size 0.7 0.7) (thickness 0.15)) (justify left bottom mirror))
    )
    (fp_text user "Author: Antmicro" (at -1.95 -6.4) (layer "B.Fab") hide
        (effects (font (size 0.7 0.7) (thickness 0.15)) (justify left bottom mirror))
    )
    (fp_line (start -0.413 -0.792) (end 0.36 -0.792)
      (stroke (width 0.15) (type solid)) (layer "B.SilkS"))
    (fp_line (start -0.413 0.861) (end 0.36 0.861)
      (stroke (width 0.15) (type solid)) (layer "B.SilkS"))
    (fp_rect (start -1.95 1) (end 1.95 -1)
      (stroke (width 0.05) (type solid)) (fill none) (layer "B.CrtYd"))
    (fp_line (start -1.677 -0.792) (end -1.677 0.861)
      (stroke (width 0.15) (type solid)) (layer "B.Fab"))
    (fp_line (start -1.677 0.861) (end 1.624 0.861)
      (stroke (width 0.15) (type solid)) (layer "B.Fab"))
    (fp_line (start 1.624 -0.792) (end -1.677 -0.792)
      (stroke (width 0.15) (type solid)) (layer "B.Fab"))
    (fp_line (start 1.624 0.861) (end 1.624 -0.792)
      (stroke (width 0.15) (type solid)) (layer "B.Fab"))
    (pad "1" smd rect (at -1.35 0 180) (size 1.143 2.032) (layers "B.Cu" "B.Paste" "B.Mask")
      (net 13 "/PoE/VO5V") (pintype "passive"))
    (pad "2" smd rect (at 1.35 0 180) (size 1.143 2.032) (layers "B.Cu" "B.Paste" "B.Mask")
      (net 12 "VCC5V0") (pintype "passive"))
  )

  (footprint "scalenode-cm4-baseboard-footprints:R_0402_1005Metric" (layer "B.Cu")
    (at 102.8 65.706)
    (descr "Resistor SMD 0402")
    (tags "resistor SMD 0402")
    (property "Author" "Antmicro")
    (property "License" "Apache-2.0")
    (property "MPN" "CR0402-FX-75R0GLF")
    (property "Manufacturer" "Bourns")
    (property "Sheetfile" "poe.kicad_sch")
    (property "Sheetname" "PoE")
    (property "Tolerance" "1%")
    (property "Val" "75R")
    (property "ki_description" "75R resistor in 0402 package with 1% tolerance")
    (attr smd)
    (fp_text reference "R32" (at 3.05 0.769 180) (layer "B.SilkS")
        (effects (font (size 0.7 0.7) (thickness 0.15)) (justify left bottom mirror))
    )
    (fp_text value "R_75R_0402" (at 0 -1.4 180) (layer "B.Fab")
        (effects (font (size 0.7 0.7) (thickness 0.15)) (justify left bottom mirror))
    )
    (fp_text user "License: Apache-2.0" (at -0.95 -5.169 180) (layer "B.Fab") hide
        (effects (font (size 0.7 0.7) (thickness 0.15)) (justify left bottom mirror))
    )
    (fp_text user "Author: Antmicro" (at -0.95 -4.169 180) (layer "B.Fab") hide
        (effects (font (size 0.7 0.7) (thickness 0.15)) (justify left bottom mirror))
    )
    (fp_text user "${REFERENCE}" (at -0.95 -3.168 180) (layer "B.Fab") hide
        (effects (font (size 0.7 0.7) (thickness 0.15)) (justify left bottom mirror))
    )
    (fp_rect (start -0.95 0.48) (end 0.95 -0.48)
      (stroke (width 0.05) (type solid)) (fill none) (layer "B.CrtYd"))
    (fp_rect (start -0.5 0.25) (end 0.5 -0.25)
      (stroke (width 0.15) (type solid)) (fill none) (layer "B.Fab"))
    (pad "1" smd roundrect (at -0.485 0) (size 0.59 0.64) (layers "B.Cu" "B.Paste" "B.Mask") (roundrect_rratio 0.25)
      (net 14 "Net-(C34-Pad1)") (pintype "passive"))
    (pad "2" smd roundrect (at 0.485 0) (size 0.59 0.64) (layers "B.Cu" "B.Paste" "B.Mask") (roundrect_rratio 0.25)
      (net 8 "Net-(C31-Pad1)") (pintype "passive"))
  )

  (footprint "scalenode-cm4-baseboard-footprints:R_0603_1608Metric" (layer "B.Cu")
    (at 176.07 70.146 -90)
    (descr "Resistor SMD 0603")
    (tags "resistor SMD 0603")
    (property "Author" "Antmicro")
    (property "License" "Apache-2.0")
    (property "MPN" "CR0603-FX-1002ELF")
    (property "Manufacturer" "Bourns")
    (property "Sheetfile" "nvme-ssd.kicad_sch")
    (property "Sheetname" "NVMe SSD")
    (property "Tolerance" "1%")
    (property "Val" "10k")
    (property "ki_description" "10k resistor in 0603 package with 1% tolerance")
    (attr smd)
    (fp_text reference "R3" (at 1.428129 -0.405341 90) (layer "B.SilkS")
        (effects (font (size 0.7 0.7) (thickness 0.15)) (justify left bottom mirror))
    )
    (fp_text value "R_10k_0603" (at 0 -1.6 90) (layer "B.Fab")
        (effects (font (size 0.7 0.7) (thickness 0.15)) (justify left bottom mirror))
    )
    (fp_text user "License: Apache-2.0" (at -1.25 -5.9 90) (layer "B.Fab") hide
        (effects (font (size 0.7 0.7) (thickness 0.15)) (justify left bottom mirror))
    )
    (fp_text user "Author: Antmicro" (at -1.25 -4.9 90) (layer "B.Fab") hide
        (effects (font (size 0.7 0.7) (thickness 0.15)) (justify left bottom mirror))
    )
    (fp_text user "${REFERENCE}" (at -1.25 -3.898 90) (layer "B.Fab") hide
        (effects (font (size 0.7 0.7) (thickness 0.15)) (justify left bottom mirror))
    )
    (fp_line (start -0.3 -0.3) (end 0.3 -0.3)
      (stroke (width 0.15) (type solid)) (layer "B.SilkS"))
    (fp_line (start -0.3 0.3) (end 0.3 0.3)
      (stroke (width 0.15) (type solid)) (layer "B.SilkS"))
    (fp_rect (start -1.25 0.7) (end 1.25 -0.7)
      (stroke (width 0.05) (type solid)) (fill none) (layer "B.CrtYd"))
    (fp_rect (start -0.8 0.4) (end 0.8 -0.4)
      (stroke (width 0.15) (type solid)) (fill none) (layer "B.Fab"))
    (pad "1" smd roundrect (at -0.7 0 270) (size 0.6 0.8) (layers "B.Cu" "B.Paste" "B.Mask") (roundrect_rratio 0.2)
      (net 170 "3V3_SSD") (pintype "passive"))
    (pad "2" smd roundrect (at 0.7 0 270) (size 0.6 0.8) (layers "B.Cu" "B.Paste" "B.Mask") (roundrect_rratio 0.2)
      (net 96 "PCIE_CLK_nREQ") (pintype "passive"))
  )

  (footprint "scalenode-cm4-baseboard-footprints:C_0603_1608Metric" (layer "B.Cu")
    (at 133.3 93.496 -90)
    (descr "Capacitor SMD 0603")
    (tags "capacitor 0603")
    (property "Author" "Antmicro")
    (property "Dielectric" "")
    (property "License" "Apache-2.0")
    (property "MPN" "GRM188R60J476ME15D")
    (property "Manufacturer" "Murata")
    (property "Sheetfile" "poe.kicad_sch")
    (property "Sheetname" "PoE")
    (property "Val" "47u")
    (property "Voltage" "")
    (property "ki_description" " ")
    (attr smd)
    (fp_text reference "C35" (at 2.279 -1.125 180) (layer "B.SilkS")
        (effects (font (size 0.7 0.7) (thickness 0.15)) (justify left bottom mirror))
    )
    (fp_text value "C_47u_0603" (at -8.671 -1.705 90) (layer "B.Fab")
        (effects (font (size 0.7 0.7) (thickness 0.15)) (justify left bottom mirror))
    )
    (fp_text user "${REFERENCE}" (at -1.682 -3.895 90) (layer "B.Fab") hide
        (effects (font (size 0.7 0.7) (thickness 0.15)) (justify left bottom mirror))
    )
    (fp_text user "License: Apache-2.0" (at -1.682 -5.895 90) (layer "B.Fab") hide
        (effects (font (size 0.7 0.7) (thickness 0.15)) (justify left bottom mirror))
    )
    (fp_text user "Author: Antmicro" (at -1.682 -4.894 90) (layer "B.Fab") hide
        (effects (font (size 0.7 0.7) (thickness 0.15)) (justify left bottom mirror))
    )
    (fp_line (start -0.3 -0.3) (end 0.3 -0.3)
      (stroke (width 0.15) (type solid)) (layer "B.SilkS"))
    (fp_line (start -0.3 0.3) (end 0.3 0.3)
      (stroke (width 0.15) (type solid)) (layer "B.SilkS"))
    (fp_rect (start -1.24 0.7) (end 1.24 -0.7)
      (stroke (width 0.05) (type solid)) (fill none) (layer "B.CrtYd"))
    (fp_rect (start -0.8 0.4) (end 0.8 -0.4)
      (stroke (width 0.15) (type solid)) (fill none) (layer "B.Fab"))
    (pad "1" smd roundrect (at -0.7 0 270) (size 0.6 0.8) (layers "B.Cu" "B.Paste" "B.Mask") (roundrect_rratio 0.2)
      (net 11 "GND") (pintype "passive"))
    (pad "2" smd roundrect (at 0.7 0 270) (size 0.6 0.8) (layers "B.Cu" "B.Paste" "B.Mask") (roundrect_rratio 0.2)
      (net 13 "/PoE/VO5V") (pintype "passive"))
  )

  (footprint "scalenode-cm4-baseboard-footprints:R_0402_1005Metric" (layer "B.Cu")
    (at 102.8 68.206)
    (descr "Resistor SMD 0402")
    (tags "resistor SMD 0402")
    (property "Author" "Antmicro")
    (property "License" "Apache-2.0")
    (property "MPN" "CR0402-FX-75R0GLF")
    (property "Manufacturer" "Bourns")
    (property "Sheetfile" "poe.kicad_sch")
    (property "Sheetname" "PoE")
    (property "Tolerance" "1%")
    (property "Val" "75R")
    (property "ki_description" "75R resistor in 0402 package with 1% tolerance")
    (attr smd)
    (fp_text reference "R31" (at 3.05 0.344 180) (layer "B.SilkS")
        (effects (font (size 0.7 0.7) (thickness 0.15)) (justify left bottom mirror))
    )
    (fp_text value "R_75R_0402" (at 0 -1.4 180) (layer "B.Fab")
        (effects (font (size 0.7 0.7) (thickness 0.15)) (justify left bottom mirror))
    )
    (fp_text user "${REFERENCE}" (at -0.95 -3.168 180) (layer "B.Fab") hide
        (effects (font (size 0.7 0.7) (thickness 0.15)) (justify left bottom mirror))
    )
    (fp_text user "Author: Antmicro" (at -0.95 -4.169 180) (layer "B.Fab") hide
        (effects (font (size 0.7 0.7) (thickness 0.15)) (justify left bottom mirror))
    )
    (fp_text user "License: Apache-2.0" (at -0.95 -5.169 180) (layer "B.Fab") hide
        (effects (font (size 0.7 0.7) (thickness 0.15)) (justify left bottom mirror))
    )
    (fp_rect (start -0.95 0.48) (end 0.95 -0.48)
      (stroke (width 0.05) (type solid)) (fill none) (layer "B.CrtYd"))
    (fp_rect (start -0.5 0.25) (end 0.5 -0.25)
      (stroke (width 0.15) (type solid)) (fill none) (layer "B.Fab"))
    (pad "1" smd roundrect (at -0.485 0) (size 0.59 0.64) (layers "B.Cu" "B.Paste" "B.Mask") (roundrect_rratio 0.25)
      (net 10 "Net-(C33-Pad1)") (pintype "passive"))
    (pad "2" smd roundrect (at 0.485 0) (size 0.59 0.64) (layers "B.Cu" "B.Paste" "B.Mask") (roundrect_rratio 0.25)
      (net 8 "Net-(C31-Pad1)") (pintype "passive"))
  )

  (footprint "scalenode-cm4-baseboard-footprints:C_1210_3225Metric" (layer "B.Cu")
    (at 98 59.506 180)
    (descr "Capacitor SMD 1210")
    (tags "capacitor SMD 1210")
    (property "Author" "Antmicro")
    (property "Dielectric" "")
    (property "License" "Apache-2.0")
    (property "MPN" "C1210C102KGRACTU")
    (property "Manufacturer" "KEMET")
    (property "Sheetfile" "poe.kicad_sch")
    (property "Sheetname" "PoE")
    (property "Val" "1n")
    (property "Voltage" "2kV")
    (property "ki_description" " ")
    (attr smd)
    (fp_text reference "C31" (at -1 1.756) (layer "B.SilkS")
        (effects (font (size 0.7 0.7) (thickness 0.15)) (justify left bottom mirror))
    )
    (fp_text value "C_1n_1210_2kV" (at 0 -2.749) (layer "B.Fab")
        (effects (font (size 0.7 0.7) (thickness 0.15)) (justify left bottom mirror))
    )
    (fp_text user "License: Apache-2.0" (at -2.1 -6.749) (layer "B.Fab") hide
        (effects (font (size 0.7 0.7) (thickness 0.15)) (justify left bottom mirror))
    )
    (fp_text user "Author: Antmicro" (at -2.1 -5.749) (layer "B.Fab") hide
        (effects (font (size 0.7 0.7) (thickness 0.15)) (justify left bottom mirror))
    )
    (fp_text user "${REFERENCE}" (at -2.1 -4.749) (layer "B.Fab") hide
        (effects (font (size 0.7 0.7) (thickness 0.15)) (justify left bottom mirror))
    )
    (fp_line (start -0.3 -1.39) (end 0.3 -1.39)
      (stroke (width 0.15) (type solid)) (layer "B.SilkS"))
    (fp_line (start -0.3 1.39) (end 0.3 1.39)
      (stroke (width 0.15) (type solid)) (layer "B.SilkS"))
    (fp_rect (start -2.1 1.75) (end 2.1 -1.75)
      (stroke (width 0.05) (type solid)) (fill none) (layer "B.CrtYd"))
    (fp_rect (start -1.6 1.25) (end 1.6 -1.25)
      (stroke (width 0.15) (type solid)) (fill none) (layer "B.Fab"))
    (pad "1" smd rect (at -1.145 0 180) (size 1.52 3.05) (layers "B.Cu" "B.Paste" "B.Mask")
      (net 8 "Net-(C31-Pad1)") (pintype "passive"))
    (pad "2" smd rect (at 1.145 0 180) (size 1.52 3.05) (layers "B.Cu" "B.Paste" "B.Mask")
      (net 230 "Earth") (pintype "passive"))
  )

  (footprint "scalenode-cm4-baseboard-footprints:DO-214AC" (layer "B.Cu")
    (at 127 94.796 180)
    (property "Author" "Antmicro")
    (property "License" "Apache-2.0")
    (property "MPN" "SMAJ6.5A")
    (property "Manufacturer" "YAGEO")
    (property "Sheetfile" "poe.kicad_sch")
    (property "Sheetname" "PoE")
    (attr smd)
    (fp_text reference "D8" (at 3.425 0.596 90) (layer "B.SilkS")
        (effects (font (size 0.7 0.7) (thickness 0.15)) (justify left bottom mirror))
    )
    (fp_text value "SMAJ6.5A" (at -0.025 -0.029) (layer "B.Fab")
        (effects (font (size 0.7 0.7) (thickness 0.15)) (justify left bottom mirror))
    )
    (fp_text user "${REFERENCE}" (at -3.301 -4.45) (layer "B.Fab") hide
        (effects (font (size 0.7 0.7) (thickness 0.15)) (justify left bottom mirror))
    )
    (fp_text user "License: Apache-2.0" (at -3.301 -6.85) (layer "B.Fab") hide
        (effects (font (size 0.7 0.7) (thickness 0.15)) (justify left bottom mirror))
    )
    (fp_text user "Author: Antmicro" (at -3.301 -5.65) (layer "B.Fab") hide
        (effects (font (size 0.7 0.7) (thickness 0.15)) (justify left bottom mirror))
    )
    (fp_line (start -3.301 -1.5) (end 0 -1.5)
      (stroke (width 0.15) (type solid)) (layer "B.SilkS"))
    (fp_line (start -3.301 1.5) (end -3.301 -1.5)
      (stroke (width 0.15) (type solid)) (layer "B.SilkS"))
    (fp_line (start 0 1.5) (end -3.301 1.5)
      (stroke (width 0.15) (type solid)) (layer "B.SilkS"))
    (fp_rect (start -3.25 1.55) (end 3.25 -1.55)
      (stroke (width 0.05) (type solid)) (fill none) (layer "B.CrtYd"))
    (fp_line (start -2.15 -1.3) (end 2.148 -1.3)
      (stroke (width 0.15) (type solid)) (layer "B.Fab"))
    (fp_line (start -2.15 1.301) (end -2.15 -1.3)
      (stroke (width 0.15) (type solid)) (layer "B.Fab"))
    (fp_line (start -2.15 1.301) (end 2.148 1.301)
      (stroke (width 0.15) (type solid)) (layer "B.Fab"))
    (fp_line (start -1.442 -1.3) (end -1.365 -1.3)
      (stroke (width 0.15) (type solid)) (layer "B.Fab"))
    (fp_line (start -1.363 1.301) (end -1.442 1.301)
      (stroke (width 0.15) (type solid)) (layer "B.Fab"))
    (fp_line (start 2.148 1.301) (end 2.148 -1.3)
      (stroke (width 0.15) (type solid)) (layer "B.Fab"))
    (fp_rect (start -1.363 1.301) (end -1.1 -1.3)
      (stroke (width 0.15) (type solid)) (fill solid) (layer "B.Fab"))
    (pad "A" smd roundrect (at 1.999 0 180) (size 2 2.1) (layers "B.Cu" "B.Paste" "B.Mask") (roundrect_rratio 0.1)
      (net 11 "GND") (pinfunction "A") (pintype "passive"))
    (pad "K" smd roundrect (at -2 0 180) (size 2 2.1) (layers "B.Cu" "B.Paste" "B.Mask") (roundrect_rratio 0.1)
      (net 13 "/PoE/VO5V") (pinfunction "K") (pintype "passive"))
  )

  (footprint "scalenode-cm4-baseboard-footprints:C_2220_5650Metric" (layer "B.Cu")
    (at 113.550264 92.575272 -90)
    (descr "Capacitor SMD 2220")
    (tags "capacitor SMD 2220")
    (property "Author" "Antmicro")
    (property "Dielectric" "X7S")
    (property "License" "Apache-2.0")
    (property "MPN" "C5750X7S2A226M280KB")
    (property "Manufacturer" "TDK")
    (property "Sheetfile" "poe.kicad_sch")
    (property "Sheetname" "PoE")
    (property "Val" "22u")
    (property "Voltage" "100V")
    (property "ki_description" " ")
    (attr smd)
    (fp_text reference "C26" (at -4.085272 -1.039736 180) (layer "B.SilkS")
        (effects (font (size 0.7 0.7) (thickness 0.15)) (justify left bottom mirror))
    )
    (fp_text value "C_22u_100V_2220" (at -9.416 -2.833 90) (layer "B.Fab")
        (effects (font (size 0.7 0.7) (thickness 0.15)) (justify left bottom mirror))
    )
    (fp_text user "License: Apache-2.0" (at -3.7 -6.9 90) (layer "B.Fab") hide
        (effects (font (size 0.7 0.7) (thickness 0.15)) (justify left bottom mirror))
    )
    (fp_text user "${REFERENCE}" (at -3.7 -5.9 90) (layer "B.Fab") hide
        (effects (font (size 0.7 0.7) (thickness 0.15)) (justify left bottom mirror))
    )
    (fp_text user "Author: Antmicro" (at -3.7 -7.9 90) (layer "B.Fab") hide
        (effects (font (size 0.7 0.7) (thickness 0.15)) (justify left bottom mirror))
    )
    (fp_line (start -1.415 -2.61) (end 1.415 -2.61)
      (stroke (width 0.15) (type solid)) (layer "B.SilkS"))
    (fp_line (start -1.415 2.61) (end 1.415 2.61)
      (stroke (width 0.15) (type solid)) (layer "B.SilkS"))
    (fp_rect (start -3.7 2.95) (end 3.7 -2.95)
      (stroke (width 0.05) (type solid)) (fill none) (layer "B.CrtYd"))
    (fp_rect (start -2.85 2.5) (end 2.85 -2.5)
      (stroke (width 0.15) (type solid)) (fill none) (layer "B.Fab"))
    (pad "1" smd roundrect (at -2.55 0 270) (size 1.8 5.4) (layers "B.Cu" "B.Paste" "B.Mask") (roundrect_rratio 0.138889)
      (net 4 "GNDD") (pintype "passive"))
    (pad "2" smd roundrect (at 2.55 0 270) (size 1.8 5.4) (layers "B.Cu" "B.Paste" "B.Mask") (roundrect_rratio 0.138889)
      (net 6 "/PoE/VDD_POE_IN") (pintype "passive"))
  )

  (footprint "scalenode-cm4-baseboard-footprints:FB_0805_2012Metric" (layer "B.Cu")
    (at 85.2 95.3)
    (property "Author" "Antmicro")
    (property "License" "Apache-2.0")
    (property "MPN" "BLM21PG221SN1D")
    (property "Manufacturer" "Murata")
    (property "Sheetfile" "poe.kicad_sch")
    (property "Sheetname" "PoE")
    (attr smd)
    (fp_text reference "FB2" (at -1.75 0.5 180) (layer "B.SilkS")
        (effects (font (size 0.7 0.7) (thickness 0.15)) (justify left bottom mirror))
    )
    (fp_text value "FB_220Z_2A_Murata-BLM21PG_0805" (at 0 -1.8 180) (layer "B.Fab")
        (effects (font (size 0.7 0.7) (thickness 0.15)) (justify left bottom mirror))
    )
    (fp_text user "License: Apache-2.0" (at -1.9 -5.75 180) (layer "B.Fab") hide
        (effects (font (size 0.7 0.7) (thickness 0.15)) (justify left bottom mirror))
    )
    (fp_text user "Author: Antmicro" (at -1.9 -4.4 180) (layer "B.Fab") hide
        (effects (font (size 0.7 0.7) (thickness 0.15)) (justify left bottom mirror))
    )
    (fp_text user "${REFERENCE}" (at -1.9 -3.1 180) (layer "B.Fab") hide
        (effects (font (size 0.7 0.7) (thickness 0.15)) (justify left bottom mirror))
    )
    (fp_line (start -0.32 -0.699) (end 0.28 -0.699)
      (stroke (width 0.15) (type solid)) (layer "B.SilkS"))
    (fp_line (start -0.3 0.701) (end 0.298 0.701)
      (stroke (width 0.15) (type solid)) (layer "B.SilkS"))
    (fp_rect (start -1.75 0.85) (end 1.75 -0.85)
      (stroke (width 0.05) (type solid)) (fill none) (layer "B.CrtYd"))
    (fp_line (start -0.951 -0.68) (end 0.949 -0.68)
      (stroke (width 0.15) (type solid)) (layer "B.Fab"))
    (fp_line (start -0.951 0.677) (end -0.951 -0.675)
      (stroke (width 0.15) (type solid)) (layer "B.Fab"))
    (fp_line (start -0.951 0.682) (end 0.949 0.682)
      (stroke (width 0.15) (type solid)) (layer "B.Fab"))
    (fp_line (start 0.949 0.677) (end 0.949 -0.675)
      (stroke (width 0.15) (type solid)) (layer "B.Fab"))
    (pad "1" smd roundrect (at -1.1 0.001) (size 1 1.4) (layers "B.Cu" "B.Paste" "B.Mask") (roundrect_rratio 0.15)
      (net 191 "Net-(D4-Pad1)") (pintype "passive"))
    (pad "2" smd roundrect (at 1.1 0.001) (size 1 1.4) (layers "B.Cu" "B.Paste" "B.Mask") (roundrect_rratio 0.15)
      (net 6 "/PoE/VDD_POE_IN") (pintype "passive"))
  )

  (footprint "scalenode-cm4-baseboard-footprints:SOIC-4_W3.9mm" (layer "B.Cu")
    (at 98.455 65.746 90)
    (property "Author" "Antmicro")
    (property "License" "Apache-2.0")
    (property "MPN" "MB10S")
    (property "Manufacturer" "Multicomp Pro")
    (property "Sheetfile" "poe.kicad_sch")
    (property "Sheetname" "PoE")
    (property "ki_description" "Bridge Rectifier")
    (attr smd)
    (fp_text reference "D5" (at 0.546 -2.88 270) (layer "B.SilkS")
        (effects (font (size 0.7 0.7) (thickness 0.15)) (justify left bottom mirror))
    )
    (fp_text value "MB10S" (at 0 -3.6 270) (layer "B.Fab")
        (effects (font (size 0.7 0.7) (thickness 0.15)) (justify left bottom mirror))
    )
    (fp_text user "${REFERENCE}" (at -4.111 -5.347 270) (layer "B.Fab") hide
        (effects (font (size 0.7 0.7) (thickness 0.15)) (justify left bottom mirror))
    )
    (fp_text user "Author: Antmicro" (at -4.111 -6.546 270) (layer "B.Fab") hide
        (effects (font (size 0.7 0.7) (thickness 0.15)) (justify left bottom mirror))
    )
    (fp_text user "License: Apache-2.0" (at -4.111 -7.746 270) (layer "B.Fab") hide
        (effects (font (size 0.7 0.7) (thickness 0.15)) (justify left bottom mirror))
    )
    (fp_line (start -3.9 2.48) (end 2.1 2.48)
      (stroke (width 0.15) (type solid)) (layer "B.SilkS"))
    (fp_line (start -2.101 -2.479) (end 2.1 -2.479)
      (stroke (width 0.15) (type solid)) (layer "B.SilkS"))
    (fp_circle (center -3.301 3.101) (end -3.202 3.101)
      (stroke (width 0.15) (type solid)) (fill solid) (layer "B.SilkS"))
    (fp_line (start -4.13 -2.72) (end 4.11 -2.72)
      (stroke (width 0.05) (type solid)) (layer "B.CrtYd"))
    (fp_line (start -4.13 2.73) (end -4.13 -2.72)
      (stroke (width 0.05) (type solid)) (layer "B.CrtYd"))
    (fp_line (start 4.11 -2.72) (end 4.11 2.73)
      (stroke (width 0.05) (type solid)) (layer "B.CrtYd"))
    (fp_line (start 4.11 2.73) (end -4.13 2.73)
      (stroke (width 0.05) (type solid)) (layer "B.CrtYd"))
    (fp_line (start -2.101 -2.479) (end -2.101 2.48)
      (stroke (width 0.15) (type solid)) (layer "B.Fab"))
    (fp_line (start -2.101 2.48) (end 2.1 2.48)
      (stroke (width 0.15) (type solid)) (layer "B.Fab"))
    (fp_line (start 2.1 -2.479) (end -2.101 -2.479)
      (stroke (width 0.15) (type solid)) (layer "B.Fab"))
    (fp_line (start 2.1 2.48) (end 2.1 -2.479)
      (stroke (width 0.15) (type solid)) (layer "B.Fab"))
    (pad "1" smd roundrect (at -2.851 1.226 90) (size 1.8 1) (layers "B.Cu" "B.Paste" "B.Mask") (roundrect_rratio 0.25)
      (net 191 "Net-(D4-Pad1)") (pinfunction "1") (pintype "passive"))
    (pad "2" smd roundrect (at -2.851 -1.225 90) (size 1.8 1) (layers "B.Cu" "B.Paste" "B.Mask") (roundrect_rratio 0.25)
      (net 231 "Net-(D4-Pad2)") (pinfunction "2") (pintype "passive"))
    (pad "3" smd roundrect (at 2.85 -1.225 90) (size 1.8 1) (layers "B.Cu" "B.Paste" "B.Mask") (roundrect_rratio 0.25)
      (net 3 "/PoE/PAIR45") (pinfunction "3") (pintype "passive"))
    (pad "4" smd roundrect (at 2.85 1.226 90) (size 1.8 1) (layers "B.Cu" "B.Paste" "B.Mask") (roundrect_rratio 0.25)
      (net 20 "/PoE/PAIR78") (pinfunction "4") (pintype "passive"))
  )

  (footprint "scalenode-cm4-baseboard-footprints:FB_0805_2012Metric" (layer "B.Cu")
    (at 86.1 92.5)
    (property "Author" "Antmicro")
    (property "License" "Apache-2.0")
    (property "MPN" "BLM21PG221SN1D")
    (property "Manufacturer" "Murata")
    (property "Sheetfile" "poe.kicad_sch")
    (property "Sheetname" "PoE")
    (attr smd)
    (fp_text reference "FB1" (at -1.75 0.325 180) (layer "B.SilkS")
        (effects (font (size 0.7 0.7) (thickness 0.15)) (justify left bottom mirror))
    )
    (fp_text value "FB_220Z_2A_Murata-BLM21PG_0805" (at 0 -1.8 180) (layer "B.Fab")
        (effects (font (size 0.7 0.7) (thickness 0.15)) (justify left bottom mirror))
    )
    (fp_text user "${REFERENCE}" (at -1.9 -3.1 180) (layer "B.Fab") hide
        (effects (font (size 0.7 0.7) (thickness 0.15)) (justify left bottom mirror))
    )
    (fp_text user "Author: Antmicro" (at -1.9 -4.4 180) (layer "B.Fab") hide
        (effects (font (size 0.7 0.7) (thickness 0.15)) (justify left bottom mirror))
    )
    (fp_text user "License: Apache-2.0" (at -1.9 -5.75 180) (layer "B.Fab") hide
        (effects (font (size 0.7 0.7) (thickness 0.15)) (justify left bottom mirror))
    )
    (fp_line (start -0.32 -0.699) (end 0.28 -0.699)
      (stroke (width 0.15) (type solid)) (layer "B.SilkS"))
    (fp_line (start -0.3 0.701) (end 0.298 0.701)
      (stroke (width 0.15) (type solid)) (layer "B.SilkS"))
    (fp_rect (start -1.75 0.85) (end 1.75 -0.85)
      (stroke (width 0.05) (type solid)) (fill none) (layer "B.CrtYd"))
    (fp_line (start -0.951 -0.68) (end 0.949 -0.68)
      (stroke (width 0.15) (type solid)) (layer "B.Fab"))
    (fp_line (start -0.951 0.677) (end -0.951 -0.675)
      (stroke (width 0.15) (type solid)) (layer "B.Fab"))
    (fp_line (start -0.951 0.682) (end 0.949 0.682)
      (stroke (width 0.15) (type solid)) (layer "B.Fab"))
    (fp_line (start 0.949 0.677) (end 0.949 -0.675)
      (stroke (width 0.15) (type solid)) (layer "B.Fab"))
    (pad "1" smd roundrect (at -1.1 0.001) (size 1 1.4) (layers "B.Cu" "B.Paste" "B.Mask") (roundrect_rratio 0.15)
      (net 231 "Net-(D4-Pad2)") (pintype "passive"))
    (pad "2" smd roundrect (at 1.1 0.001) (size 1 1.4) (layers "B.Cu" "B.Paste" "B.Mask") (roundrect_rratio 0.15)
      (net 5 "VSS") (pintype "passive"))
  )

  (footprint "scalenode-cm4-baseboard-footprints:SOIC-4_W3.9mm" (layer "B.Cu")
    (at 97.47 77.136 -90)
    (property "Author" "Antmicro")
    (property "License" "Apache-2.0")
    (property "MPN" "MB10S")
    (property "Manufacturer" "Multicomp Pro")
    (property "Sheetfile" "poe.kicad_sch")
    (property "Sheetname" "PoE")
    (property "ki_description" "Bridge Rectifier")
    (attr smd)
    (fp_text reference "D4" (at 0 2.9 90) (layer "B.SilkS")
        (effects (font (size 0.7 0.7) (thickness 0.15)) (justify left bottom mirror))
    )
    (fp_text value "MB10S" (at 0 -3.6 90) (layer "B.Fab")
        (effects (font (size 0.7 0.7) (thickness 0.15)) (justify left bottom mirror))
    )
    (fp_text user "License: Apache-2.0" (at -4.111 -7.746 90) (layer "B.Fab") hide
        (effects (font (size 0.7 0.7) (thickness 0.15)) (justify left bottom mirror))
    )
    (fp_text user "${REFERENCE}" (at -4.111 -5.347 90) (layer "B.Fab") hide
        (effects (font (size 0.7 0.7) (thickness 0.15)) (justify left bottom mirror))
    )
    (fp_text user "Author: Antmicro" (at -4.111 -6.546 90) (layer "B.Fab") hide
        (effects (font (size 0.7 0.7) (thickness 0.15)) (justify left bottom mirror))
    )
    (fp_line (start -3.9 2.48) (end 2.1 2.48)
      (stroke (width 0.15) (type solid)) (layer "B.SilkS"))
    (fp_line (start -2.101 -2.479) (end 2.1 -2.479)
      (stroke (width 0.15) (type solid)) (layer "B.SilkS"))
    (fp_circle (center -3.301 3.101) (end -3.202 3.101)
      (stroke (width 0.15) (type solid)) (fill solid) (layer "B.SilkS"))
    (fp_line (start -4.13 -2.72) (end 4.11 -2.72)
      (stroke (width 0.05) (type solid)) (layer "B.CrtYd"))
    (fp_line (start -4.13 2.73) (end -4.13 -2.72)
      (stroke (width 0.05) (type solid)) (layer "B.CrtYd"))
    (fp_line (start 4.11 -2.72) (end 4.11 2.73)
      (stroke (width 0.05) (type solid)) (layer "B.CrtYd"))
    (fp_line (start 4.11 2.73) (end -4.13 2.73)
      (stroke (width 0.05) (type solid)) (layer "B.CrtYd"))
    (fp_line (start -2.101 -2.479) (end -2.101 2.48)
      (stroke (width 0.15) (type solid)) (layer "B.Fab"))
    (fp_line (start -2.101 2.48) (end 2.1 2.48)
      (stroke (width 0.15) (type solid)) (layer "B.Fab"))
    (fp_line (start 2.1 -2.479) (end -2.101 -2.479)
      (stroke (width 0.15) (type solid)) (layer "B.Fab"))
    (fp_line (start 2.1 2.48) (end 2.1 -2.479)
      (stroke (width 0.15) (type solid)) (layer "B.Fab"))
    (pad "1" smd roundrect (at -2.851 1.226 270) (size 1.8 1) (layers "B.Cu" "B.Paste" "B.Mask") (roundrect_rratio 0.25)
      (net 191 "Net-(D4-Pad1)") (pinfunction "1") (pintype "passive"))
    (pad "2" smd roundrect (at -2.851 -1.225 270) (size 1.8 1) (layers "B.Cu" "B.Paste" "B.Mask") (roundrect_rratio 0.25)
      (net 231 "Net-(D4-Pad2)") (pinfunction "2") (pintype "passive"))
    (pad "3" smd roundrect (at 2.85 -1.225 270) (size 1.8 1) (layers "B.Cu" "B.Paste" "B.Mask") (roundrect_rratio 0.25)
      (net 1 "/PoE/PAIR12") (pinfunction "3") (pintype "passive"))
    (pad "4" smd roundrect (at 2.85 1.226 270) (size 1.8 1) (layers "B.Cu" "B.Paste" "B.Mask") (roundrect_rratio 0.25)
      (net 2 "/PoE/PAIR36") (pinfunction "4") (pintype "passive"))
  )

  (footprint "scalenode-cm4-baseboard-footprints:R_0603_1608Metric" (layer "B.Cu")
    (at 174.546 70.146 -90)
    (descr "Resistor SMD 0603")
    (tags "resistor SMD 0603")
    (property "Author" "Antmicro")
    (property "License" "Apache-2.0")
    (property "MPN" "CR0603-FX-1002ELF")
    (property "Manufacturer" "Bourns")
    (property "Sheetfile" "nvme-ssd.kicad_sch")
    (property "Sheetname" "NVMe SSD")
    (property "Tolerance" "1%")
    (property "Val" "10k")
    (property "ki_description" "10k resistor in 0603 package with 1% tolerance")
    (attr smd)
    (fp_text reference "R4" (at 1.368385 -0.404591 90) (layer "B.SilkS")
        (effects (font (size 0.7 0.7) (thickness 0.15)) (justify left bottom mirror))
    )
    (fp_text value "R_10k_0603" (at 0 -1.6 90) (layer "B.Fab")
        (effects (font (size 0.7 0.7) (thickness 0.15)) (justify left bottom mirror))
    )
    (fp_text user "License: Apache-2.0" (at -1.25 -5.9 90) (layer "B.Fab") hide
        (effects (font (size 0.7 0.7) (thickness 0.15)) (justify left bottom mirror))
    )
    (fp_text user "Author: Antmicro" (at -1.25 -4.9 90) (layer "B.Fab") hide
        (effects (font (size 0.7 0.7) (thickness 0.15)) (justify left bottom mirror))
    )
    (fp_text user "${REFERENCE}" (at -1.25 -3.898 90) (layer "B.Fab") hide
        (effects (font (size 0.7 0.7) (thickness 0.15)) (justify left bottom mirror))
    )
    (fp_line (start -0.3 -0.3) (end 0.3 -0.3)
      (stroke (width 0.15) (type solid)) (layer "B.SilkS"))
    (fp_line (start -0.3 0.3) (end 0.3 0.3)
      (stroke (width 0.15) (type solid)) (layer "B.SilkS"))
    (fp_rect (start -1.25 0.7) (end 1.25 -0.7)
      (stroke (width 0.05) (type solid)) (fill none) (layer "B.CrtYd"))
    (fp_rect (start -0.8 0.4) (end 0.8 -0.4)
      (stroke (width 0.15) (type solid)) (fill none) (layer "B.Fab"))
    (pad "1" smd roundrect (at -0.7 0 270) (size 0.6 0.8) (layers "B.Cu" "B.Paste" "B.Mask") (roundrect_rratio 0.2)
      (net 170 "3V3_SSD") (pintype "passive"))
    (pad "2" smd roundrect (at 0.7 0 270) (size 0.6 0.8) (layers "B.Cu" "B.Paste" "B.Mask") (roundrect_rratio 0.2)
      (net 99 "PSCIE_nRST") (pintype "passive"))
  )

  (footprint "scalenode-cm4-baseboard-footprints:R_0402_1005Metric" (layer "B.Cu")
    (at 102.8 70.906)
    (descr "Resistor SMD 0402")
    (tags "resistor SMD 0402")
    (property "Author" "Antmicro")
    (property "License" "Apache-2.0")
    (property "MPN" "CR0402-FX-75R0GLF")
    (property "Manufacturer" "Bourns")
    (property "Sheetfile" "poe.kicad_sch")
    (property "Sheetname" "PoE")
    (property "Tolerance" "1%")
    (property "Val" "75R")
    (property "ki_description" "75R resistor in 0402 package with 1% tolerance")
    (attr smd)
    (fp_text reference "R26" (at 3.075 0.369 180) (layer "B.SilkS")
        (effects (font (size 0.7 0.7) (thickness 0.15)) (justify left bottom mirror))
    )
    (fp_text value "R_75R_0402" (at 0 -1.4 180) (layer "B.Fab")
        (effects (font (size 0.7 0.7) (thickness 0.15)) (justify left bottom mirror))
    )
    (fp_text user "Author: Antmicro" (at -0.95 -4.169 180) (layer "B.Fab") hide
        (effects (font (size 0.7 0.7) (thickness 0.15)) (justify left bottom mirror))
    )
    (fp_text user "${REFERENCE}" (at -0.95 -3.168 180) (layer "B.Fab") hide
        (effects (font (size 0.7 0.7) (thickness 0.15)) (justify left bottom mirror))
    )
    (fp_text user "License: Apache-2.0" (at -0.95 -5.169 180) (layer "B.Fab") hide
        (effects (font (size 0.7 0.7) (thickness 0.15)) (justify left bottom mirror))
    )
    (fp_rect (start -0.95 0.48) (end 0.95 -0.48)
      (stroke (width 0.05) (type solid)) (fill none) (layer "B.CrtYd"))
    (fp_rect (start -0.5 0.25) (end 0.5 -0.25)
      (stroke (width 0.15) (type solid)) (fill none) (layer "B.Fab"))
    (pad "1" smd roundrect (at -0.485 0) (size 0.59 0.64) (layers "B.Cu" "B.Paste" "B.Mask") (roundrect_rratio 0.25)
      (net 9 "Net-(C30-Pad1)") (pintype "passive"))
    (pad "2" smd roundrect (at 0.485 0) (size 0.59 0.64) (layers "B.Cu" "B.Paste" "B.Mask") (roundrect_rratio 0.25)
      (net 8 "Net-(C31-Pad1)") (pintype "passive"))
  )

  (footprint "scalenode-cm4-baseboard-footprints:DO-214AC" (layer "B.Cu")
    (at 90.5 92.006 90)
    (property "Author" "Antmicro")
    (property "License" "Apache-2.0")
    (property "MPN" "SMAJ58A-13-F")
    (property "Manufacturer" "Diodes Incorporated")
    (property "Sheetfile" "poe.kicad_sch")
    (property "Sheetname" "PoE")
    (attr smd)
    (fp_text reference "D6" (at 3.481 0.925) (layer "B.SilkS")
        (effects (font (size 0.7 0.7) (thickness 0.15)) (justify left bottom mirror))
    )
    (fp_text value "SMAJ58A-13-F" (at 3.881 -2.75 270) (layer "B.Fab")
        (effects (font (size 0.7 0.7) (thickness 0.15)) (justify left bottom mirror))
    )
    (fp_text user "Author: Antmicro" (at -3.301 -5.65 270) (layer "B.Fab") hide
        (effects (font (size 0.7 0.7) (thickness 0.15)) (justify left bottom mirror))
    )
    (fp_text user "License: Apache-2.0" (at -3.301 -6.85 270) (layer "B.Fab") hide
        (effects (font (size 0.7 0.7) (thickness 0.15)) (justify left bottom mirror))
    )
    (fp_text user "${REFERENCE}" (at -3.301 -4.45 270) (layer "B.Fab") hide
        (effects (font (size 0.7 0.7) (thickness 0.15)) (justify left bottom mirror))
    )
    (fp_line (start -3.301 -1.5) (end 0 -1.5)
      (stroke (width 0.15) (type solid)) (layer "B.SilkS"))
    (fp_line (start -3.301 1.5) (end -3.301 -1.5)
      (stroke (width 0.15) (type solid)) (layer "B.SilkS"))
    (fp_line (start 0 1.5) (end -3.301 1.5)
      (stroke (width 0.15) (type solid)) (layer "B.SilkS"))
    (fp_rect (start -3.25 1.55) (end 3.25 -1.55)
      (stroke (width 0.05) (type solid)) (fill none) (layer "B.CrtYd"))
    (fp_line (start -2.15 -1.3) (end 2.148 -1.3)
      (stroke (width 0.15) (type solid)) (layer "B.Fab"))
    (fp_line (start -2.15 1.301) (end -2.15 -1.3)
      (stroke (width 0.15) (type solid)) (layer "B.Fab"))
    (fp_line (start -2.15 1.301) (end 2.148 1.301)
      (stroke (width 0.15) (type solid)) (layer "B.Fab"))
    (fp_line (start -1.442 -1.3) (end -1.365 -1.3)
      (stroke (width 0.15) (type solid)) (layer "B.Fab"))
    (fp_line (start -1.363 1.301) (end -1.442 1.301)
      (stroke (width 0.15) (type solid)) (layer "B.Fab"))
    (fp_line (start 2.148 1.301) (end 2.148 -1.3)
      (stroke (width 0.15) (type solid)) (layer "B.Fab"))
    (fp_rect (start -1.363 1.301) (end -1.1 -1.3)
      (stroke (width 0.15) (type solid)) (fill solid) (layer "B.Fab"))
    (pad "A" smd roundrect (at 1.999 0 90) (size 2 2.1) (layers "B.Cu" "B.Paste" "B.Mask") (roundrect_rratio 0.1)
      (net 5 "VSS") (pinfunction "A") (pintype "passive"))
    (pad "K" smd roundrect (at -2 0 90) (size 2 2.1) (layers "B.Cu" "B.Paste" "B.Mask") (roundrect_rratio 0.1)
      (net 6 "/PoE/VDD_POE_IN") (pinfunction "K") (pintype "passive"))
  )

  (footprint "scalenode-cm4-baseboard-footprints:R_0402_1005Metric" (layer "B.Cu")
    (at 102.8 73.506)
    (descr "Resistor SMD 0402")
    (tags "resistor SMD 0402")
    (property "Author" "Antmicro")
    (property "License" "Apache-2.0")
    (property "MPN" "CR0402-FX-75R0GLF")
    (property "Manufacturer" "Bourns")
    (property "Sheetfile" "poe.kicad_sch")
    (property "Sheetname" "PoE")
    (property "Tolerance" "1%")
    (property "Val" "75R")
    (property "ki_description" "75R resistor in 0402 package with 1% tolerance")
    (attr smd)
    (fp_text reference "R25" (at 3.06 0.174 180) (layer "B.SilkS")
        (effects (font (size 0.7 0.7) (thickness 0.15)) (justify left bottom mirror))
    )
    (fp_text value "R_75R_0402" (at 0 -1.4 180) (layer "B.Fab")
        (effects (font (size 0.7 0.7) (thickness 0.15)) (justify left bottom mirror))
    )
    (fp_text user "License: Apache-2.0" (at -0.95 -5.169 180) (layer "B.Fab") hide
        (effects (font (size 0.7 0.7) (thickness 0.15)) (justify left bottom mirror))
    )
    (fp_text user "${REFERENCE}" (at -0.95 -3.168 180) (layer "B.Fab") hide
        (effects (font (size 0.7 0.7) (thickness 0.15)) (justify left bottom mirror))
    )
    (fp_text user "Author: Antmicro" (at -0.95 -4.169 180) (layer "B.Fab") hide
        (effects (font (size 0.7 0.7) (thickness 0.15)) (justify left bottom mirror))
    )
    (fp_rect (start -0.95 0.48) (end 0.95 -0.48)
      (stroke (width 0.05) (type solid)) (fill none) (layer "B.CrtYd"))
    (fp_rect (start -0.5 0.25) (end 0.5 -0.25)
      (stroke (width 0.15) (type solid)) (fill none) (layer "B.Fab"))
    (pad "1" smd roundrect (at -0.485 0) (size 0.59 0.64) (layers "B.Cu" "B.Paste" "B.Mask") (roundrect_rratio 0.25)
      (net 7 "Net-(C27-Pad1)") (pintype "passive"))
    (pad "2" smd roundrect (at 0.485 0) (size 0.59 0.64) (layers "B.Cu" "B.Paste" "B.Mask") (roundrect_rratio 0.25)
      (net 8 "Net-(C31-Pad1)") (pintype "passive"))
  )

  (footprint "scalenode-cm4-baseboard-footprints:C_2220_5650Metric" (layer "B.Cu")
    (at 107.354191 92.524276 -90)
    (descr "Capacitor SMD 2220")
    (tags "capacitor SMD 2220")
    (property "Author" "Antmicro")
    (property "Dielectric" "X7S")
    (property "License" "Apache-2.0")
    (property "MPN" "C5750X7S2A226M280KB")
    (property "Manufacturer" "TDK")
    (property "Sheetfile" "poe.kicad_sch")
    (property "Sheetname" "PoE")
    (property "Val" "22u")
    (property "Voltage" "100V")
    (property "ki_description" " ")
    (attr smd)
    (fp_text reference "C28" (at -4.054276 -1.485809 180) (layer "B.SilkS")
        (effects (font (size 0.7 0.7) (thickness 0.15)) (justify left bottom mirror))
    )
    (fp_text value "C_22u_100V_2220" (at -9.416 -2.833 90) (layer "B.Fab")
        (effects (font (size 0.7 0.7) (thickness 0.15)) (justify left bottom mirror))
    )
    (fp_text user "License: Apache-2.0" (at -3.7 -6.9 90) (layer "B.Fab") hide
        (effects (font (size 0.7 0.7) (thickness 0.15)) (justify left bottom mirror))
    )
    (fp_text user "Author: Antmicro" (at -3.7 -7.9 90) (layer "B.Fab") hide
        (effects (font (size 0.7 0.7) (thickness 0.15)) (justify left bottom mirror))
    )
    (fp_text user "${REFERENCE}" (at -3.7 -5.9 90) (layer "B.Fab") hide
        (effects (font (size 0.7 0.7) (thickness 0.15)) (justify left bottom mirror))
    )
    (fp_line (start -1.415 -2.61) (end 1.415 -2.61)
      (stroke (width 0.15) (type solid)) (layer "B.SilkS"))
    (fp_line (start -1.415 2.61) (end 1.415 2.61)
      (stroke (width 0.15) (type solid)) (layer "B.SilkS"))
    (fp_rect (start -3.7 2.95) (end 3.7 -2.95)
      (stroke (width 0.05) (type solid)) (fill none) (layer "B.CrtYd"))
    (fp_rect (start -2.85 2.5) (end 2.85 -2.5)
      (stroke (width 0.15) (type solid)) (fill none) (layer "B.Fab"))
    (pad "1" smd roundrect (at -2.55 0 270) (size 1.8 5.4) (layers "B.Cu" "B.Paste" "B.Mask") (roundrect_rratio 0.138889)
      (net 4 "GNDD") (pintype "passive"))
    (pad "2" smd roundrect (at 2.55 0 270) (size 1.8 5.4) (layers "B.Cu" "B.Paste" "B.Mask") (roundrect_rratio 0.138889)
      (net 6 "/PoE/VDD_POE_IN") (pintype "passive"))
  )

  (footprint "scalenode-cm4-baseboard-footprints:C_0402_1005Metric" (layer "B.Cu")
    (at 102.785 67.006 180)
    (descr "Capacitor SMD 0402")
    (tags "capacitor SMD 0402")
    (property "Author" "Antmicro")
    (property "Dielectric" "X7R")
    (property "License" "Apache-2.0")
    (property "MPN" "GRM155R71H103KA88D")
    (property "Manufacturer" "Murata")
    (property "Sheetfile" "poe.kicad_sch")
    (property "Sheetname" "PoE")
    (property "Val" "10n")
    (property "Voltage" "50V")
    (property "ki_description" " ")
    (attr smd)
    (fp_text reference "C33" (at -3.115 -0.444) (layer "B.SilkS")
        (effects (font (size 0.7 0.7) (thickness 0.15)) (justify left bottom mirror))
    )
    (fp_text value "C_10n_0402" (at 0 -1.4) (layer "B.Fab")
        (effects (font (size 0.7 0.7) (thickness 0.15)) (justify left bottom mirror))
    )
    (fp_text user "${REFERENCE}" (at -0.932 -3.168) (layer "B.Fab") hide
        (effects (font (size 0.7 0.7) (thickness 0.15)) (justify left bottom mirror))
    )
    (fp_text user "Author: Antmicro" (at -0.932 -4.17) (layer "B.Fab") hide
        (effects (font (size 0.7 0.7) (thickness 0.15)) (justify left bottom mirror))
    )
    (fp_text user "License: Apache-2.0" (at -0.932 -5.17) (layer "B.Fab") hide
        (effects (font (size 0.7 0.7) (thickness 0.15)) (justify left bottom mirror))
    )
    (fp_rect (start -0.94 0.47) (end 0.94 -0.47)
      (stroke (width 0.05) (type solid)) (fill none) (layer "B.CrtYd"))
    (fp_rect (start -0.499 0.249) (end 0.499 -0.249)
      (stroke (width 0.15) (type solid)) (fill none) (layer "B.Fab"))
    (pad "1" smd roundrect (at -0.484 0 180) (size 0.59 0.64) (layers "B.Cu" "B.Paste" "B.Mask") (roundrect_rratio 0.25)
      (net 10 "Net-(C33-Pad1)") (pintype "passive"))
    (pad "2" smd roundrect (at 0.484 0 180) (size 0.59 0.64) (layers "B.Cu" "B.Paste" "B.Mask") (roundrect_rratio 0.25)
      (net 3 "/PoE/PAIR45") (pintype "passive"))
  )

  (footprint "scalenode-cm4-baseboard-footprints:C_0402_1005Metric" (layer "B.Cu")
    (at 102.8 72.206 180)
    (descr "Capacitor SMD 0402")
    (tags "capacitor SMD 0402")
    (property "Author" "Antmicro")
    (property "Dielectric" "X7R")
    (property "License" "Apache-2.0")
    (property "MPN" "GRM155R71H103KA88D")
    (property "Manufacturer" "Murata")
    (property "Sheetfile" "poe.kicad_sch")
    (property "Sheetname" "PoE")
    (property "Val" "10n")
    (property "Voltage" "50V")
    (property "ki_description" " ")
    (attr smd)
    (fp_text reference "C30" (at -3.13 -0.314) (layer "B.SilkS")
        (effects (font (size 0.7 0.7) (thickness 0.15)) (justify left bottom mirror))
    )
    (fp_text value "C_10n_0402" (at 0 -1.4) (layer "B.Fab")
        (effects (font (size 0.7 0.7) (thickness 0.15)) (justify left bottom mirror))
    )
    (fp_text user "License: Apache-2.0" (at -0.932 -5.17) (layer "B.Fab") hide
        (effects (font (size 0.7 0.7) (thickness 0.15)) (justify left bottom mirror))
    )
    (fp_text user "Author: Antmicro" (at -0.932 -4.17) (layer "B.Fab") hide
        (effects (font (size 0.7 0.7) (thickness 0.15)) (justify left bottom mirror))
    )
    (fp_text user "${REFERENCE}" (at -0.932 -3.168) (layer "B.Fab") hide
        (effects (font (size 0.7 0.7) (thickness 0.15)) (justify left bottom mirror))
    )
    (fp_rect (start -0.94 0.47) (end 0.94 -0.47)
      (stroke (width 0.05) (type solid)) (fill none) (layer "B.CrtYd"))
    (fp_rect (start -0.499 0.249) (end 0.499 -0.249)
      (stroke (width 0.15) (type solid)) (fill none) (layer "B.Fab"))
    (pad "1" smd roundrect (at -0.484 0 180) (size 0.59 0.64) (layers "B.Cu" "B.Paste" "B.Mask") (roundrect_rratio 0.25)
      (net 9 "Net-(C30-Pad1)") (pintype "passive"))
    (pad "2" smd roundrect (at 0.484 0 180) (size 0.59 0.64) (layers "B.Cu" "B.Paste" "B.Mask") (roundrect_rratio 0.25)
      (net 2 "/PoE/PAIR36") (pintype "passive"))
  )

  (footprint "scalenode-cm4-baseboard-footprints:R_0402_1005Metric" (layer "B.Cu")
    (at 94.65 90.306 -90)
    (descr "Resistor SMD 0402")
    (tags "resistor SMD 0402")
    (property "Author" "Antmicro")
    (property "License" "Apache-2.0")
    (property "MPN" "CR0402-FX-63R4GLF")
    (property "Manufacturer" "Bourns")
    (property "Sheetfile" "poe.kicad_sch")
    (property "Sheetname" "PoE")
    (property "Tolerance" "1%")
    (property "Val" "63R4")
    (property "ki_description" "63R4 resistor in 0402 package with 1% tolerance")
    (attr smd)
    (fp_text reference "R23" (at -0.881 -0.375 -90) (layer "B.SilkS")
        (effects (font (size 0.7 0.7) (thickness 0.15)) (justify right bottom mirror))
    )
    (fp_text value "R_63R4_0402" (at -1.246 -2.07 90) (layer "B.Fab")
        (effects (font (size 0.7 0.7) (thickness 0.15)) (justify left bottom mirror))
    )
    (fp_text user "${REFERENCE}" (at -0.95 -3.168 90) (layer "B.Fab") hide
        (effects (font (size 0.7 0.7) (thickness 0.15)) (justify left bottom mirror))
    )
    (fp_text user "License: Apache-2.0" (at -0.95 -5.169 90) (layer "B.Fab") hide
        (effects (font (size 0.7 0.7) (thickness 0.15)) (justify left bottom mirror))
    )
    (fp_text user "Author: Antmicro" (at -0.95 -4.169 90) (layer "B.Fab") hide
        (effects (font (size 0.7 0.7) (thickness 0.15)) (justify left bottom mirror))
    )
    (fp_rect (start -0.95 0.48) (end 0.95 -0.48)
      (stroke (width 0.05) (type solid)) (fill none) (layer "B.CrtYd"))
    (fp_rect (start -0.5 0.25) (end 0.5 -0.25)
      (stroke (width 0.15) (type solid)) (fill none) (layer "B.Fab"))
    (pad "1" smd roundrect (at -0.485 0 270) (size 0.59 0.64) (layers "B.Cu" "B.Paste" "B.Mask") (roundrect_rratio 0.25)
      (net 5 "VSS") (pintype "passive"))
    (pad "2" smd roundrect (at 0.485 0 270) (size 0.59 0.64) (layers "B.Cu" "B.Paste" "B.Mask") (roundrect_rratio 0.25)
      (net 255 "Net-(U8-CLS)") (pintype "passive"))
  )

  (footprint "scalenode-cm4-baseboard-footprints:C_0805_2012Metric" (layer "B.Cu")
    (at 93 91.506 -90)
    (descr "Capacitor SMD 0805")
    (tags "capacitor SMD 0805")
    (property "Author" "Antmicro")
    (property "Dielectric" "X7R")
    (property "License" "Apache-2.0")
    (property "MPN" "CL21B104KCFNNNE")
    (property "Manufacturer" "Samsung Electro-Mechanics")
    (property "Sheetfile" "poe.kicad_sch")
    (property "Sheetname" "PoE")
    (property "Val" "100n")
    (property "Voltage" "100V")
    (property "ki_description" " ")
    (attr smd)
    (fp_text reference "C20" (at 0 1.176 90) (layer "B.SilkS")
        (effects (font (size 0.7 0.7) (thickness 0.15)) (justify left bottom mirror))
    )
    (fp_text value "C_100n_100V_0805" (at -9.416 -0.88 90) (layer "B.Fab")
        (effects (font (size 0.7 0.7) (thickness 0.15)) (justify left bottom mirror))
    )
    (fp_text user "Author: Antmicro" (at -1.9 -5.947 90) (layer "B.Fab") hide
        (effects (font (size 0.7 0.7) (thickness 0.15)) (justify left bottom mirror))
    )
    (fp_text user "${REFERENCE}" (at -1.9 -3.947 90) (layer "B.Fab") hide
        (effects (font (size 0.7 0.7) (thickness 0.15)) (justify left bottom mirror))
    )
    (fp_text user "License: Apache-2.0" (at -1.9 -4.947 90) (layer "B.Fab") hide
        (effects (font (size 0.7 0.7) (thickness 0.15)) (justify left bottom mirror))
    )
    (fp_line (start -0.3 -0.8) (end 0.3 -0.8)
      (stroke (width 0.15) (type solid)) (layer "B.SilkS"))
    (fp_line (start -0.3 0.8) (end 0.3 0.8)
      (stroke (width 0.15) (type solid)) (layer "B.SilkS"))
    (fp_rect (start -1.9 0.93) (end 1.9 -0.93)
      (stroke (width 0.05) (type solid)) (fill none) (layer "B.CrtYd"))
    (fp_rect (start -0.95 0.675) (end 0.95 -0.675)
      (stroke (width 0.15) (type solid)) (fill none) (layer "B.Fab"))
    (pad "1" smd rect (at -1.05 0 270) (size 1.2 1.2) (layers "B.Cu" "B.Paste" "B.Mask")
      (net 5 "VSS") (pintype "passive"))
    (pad "2" smd rect (at 1.05 0 270) (size 1.2 1.2) (layers "B.Cu" "B.Paste" "B.Mask")
      (net 6 "/PoE/VDD_POE_IN") (pintype "passive"))
  )

  (footprint "scalenode-cm4-baseboard-footprints:R_0402_1005Metric" (layer "B.Cu")
    (at 94.65 92.756 90)
    (descr "Resistor SMD 0402")
    (tags "resistor SMD 0402")
    (property "Author" "Antmicro")
    (property "License" "Apache-2.0")
    (property "MPN" "CR0402-FX-2492GLF")
    (property "Manufacturer" "Bourns")
    (property "Sheetfile" "poe.kicad_sch")
    (property "Sheetname" "PoE")
    (property "Tolerance" "1%")
    (property "Val" "24k9")
    (property "ki_description" "24k9 resistor in 0402 package with 1% tolerance")
    (attr smd)
    (fp_text reference "R24" (at -1.019 0.375 90) (layer "B.SilkS")
        (effects (font (size 0.7 0.7) (thickness 0.15)) (justify left bottom mirror))
    )
    (fp_text value "R_24k9_0402" (at 5.106 -0.15 270) (layer "B.Fab")
        (effects (font (size 0.7 0.7) (thickness 0.15)) (justify left bottom mirror))
    )
    (fp_text user "License: Apache-2.0" (at -0.95 -5.169 270) (layer "B.Fab") hide
        (effects (font (size 0.7 0.7) (thickness 0.15)) (justify left bottom mirror))
    )
    (fp_text user "Author: Antmicro" (at -0.95 -4.169 270) (layer "B.Fab") hide
        (effects (font (size 0.7 0.7) (thickness 0.15)) (justify left bottom mirror))
    )
    (fp_text user "${REFERENCE}" (at -0.95 -3.168 270) (layer "B.Fab") hide
        (effects (font (size 0.7 0.7) (thickness 0.15)) (justify left bottom mirror))
    )
    (fp_rect (start -0.95 0.48) (end 0.95 -0.48)
      (stroke (width 0.05) (type solid)) (fill none) (layer "B.CrtYd"))
    (fp_rect (start -0.5 0.25) (end 0.5 -0.25)
      (stroke (width 0.15) (type solid)) (fill none) (layer "B.Fab"))
    (pad "1" smd roundrect (at -0.485 0 90) (size 0.59 0.64) (layers "B.Cu" "B.Paste" "B.Mask") (roundrect_rratio 0.25)
      (net 6 "/PoE/VDD_POE_IN") (pintype "passive"))
    (pad "2" smd roundrect (at 0.485 0 90) (size 0.59 0.64) (layers "B.Cu" "B.Paste" "B.Mask") (roundrect_rratio 0.25)
      (net 256 "Net-(U8-DEN)") (pintype "passive"))
  )
  (gr_line (start 75.1 96.7) (end 203.6 96.7)
    (stroke (width 0.12) (type solid)) (layer "Edge.Cuts"))
  (gr_line (start 75.1 56.7) (end 203.6 56.7)
    (stroke (width 0.12) (type solid)) (layer "Edge.Cuts"))
  (gr_line (start 75.1 59.456) (end 77.216 59.456)
    (stroke (width 0.12) (type solid)) (layer "Edge.Cuts"))
  (gr_arc (start 77.216 59.456) (mid 77.463487 59.558513) (end 77.566 59.806)
    (stroke (width 0.12) (type solid)) (layer "Edge.Cuts"))
  (gr_line (start 77.566 59.806) (end 87.291 59.806)
    (stroke (width 0.12) (type solid)) (layer "Edge.Cuts"))
  (gr_arc (start 87.291 59.806) (mid 88.059198 59.487802) (end 87.741 60.256)
    (stroke (width 0.12) (type solid)) (layer "Edge.Cuts"))
  (gr_line (start 87.741 60.256) (end 87.741 75.556)
    (stroke (width 0.12) (type solid)) (layer "Edge.Cuts"))
  (gr_arc (start 87.741 75.556) (mid 88.059198 76.324198) (end 87.291 76.006)
    (stroke (width 0.12) (type solid)) (layer "Edge.Cuts"))
  (gr_line (start 87.291 76.006) (end 77.591 76.006)
    (stroke (width 0.12) (type solid)) (layer "Edge.Cuts"))
  (gr_arc (start 77.591 76.006) (mid 77.504544 76.237662) (end 77.287447 76.356)
    (stroke (width 0.12) (type solid)) (layer "Edge.Cuts"))
  (gr_line (start 77.287447 76.356) (end 75.1 76.356)
    (stroke (width 0.12) (type solid)) (layer "Edge.Cuts"))
  (gr_line (start 75.1 59.456) (end 75.1 56.7)
    (stroke (width 0.12) (type solid)) (layer "Edge.Cuts"))
  (gr_line (start 75.1 96.7) (end 75.1 76.356)
    (stroke (width 0.12) (type solid)) (layer "Edge.Cuts"))
  (gr_line (start 203.6 56.7) (end 203.6 96.7)
    (stroke (width 0.12) (type solid)) (layer "Edge.Cuts"))
  (gr_text "Scalenode CM4 \nBaseboard" (at 94 81.51) (layer "F.Cu")
    (effects (font (size 0.7 0.7) (thickness 0.15)) (justify left))
  )
  (gr_text "Rev. ${REVISION}" (at 96.4 83.11) (layer "F.Cu")
    (effects (font (size 0.6 0.6) (thickness 0.15)))
  )

  (segment (start 99.933 73.803) (end 100.881 74.751) (width 0.5) (layer "F.Cu") (net 1))
  (segment (start 97.887 73.803) (end 99.933 73.803) (width 0.5) (layer "F.Cu") (net 1))
  (via (at 100.881 74.751) (size 0.5) (drill 0.15) (layers "F.Cu" "B.Cu") (net 1))
  (segment (start 100.881 74.751) (end 100.881 74.352846) (width 0.5) (layer "B.Cu") (net 1))
  (segment (start 100.881 76.672) (end 100.881 74.751) (width 0.5) (layer "B.Cu") (net 1))
  (segment (start 98.693 78.86) (end 100.881 76.672) (width 0.5) (layer "B.Cu") (net 1))
  (segment (start 100.881 74.352846) (end 101.233401 74.000445) (width 0.5) (layer "B.Cu") (net 1))
  (segment (start 98.693 79.966) (end 98.693 78.86) (width 0.5) (layer "B.Cu") (net 1))
  (segment (start 100.825 72.155) (end 100.881 72.211) (width 0.4) (layer "F.Cu") (net 2))
  (segment (start 97.887 69.993) (end 98.872002 69.993) (width 0.5) (layer "F.Cu") (net 2))
  (segment (start 100.881 72.001998) (end 100.881 72.211) (width 0.5) (layer "F.Cu") (net 2))
  (segment (start 98.872002 69.993) (end 100.881 72.001998) (width 0.5) (layer "F.Cu") (net 2))
  (via (at 100.881 72.211) (size 0.5) (drill 0.15) (layers "F.Cu" "B.Cu") (net 2))
  (segment (start 101.389 72.211) (end 102.301 72.211) (width 0.4) (layer "B.Cu") (net 2))
  (segment (start 101.135 72.211) (end 101.389 72.211) (width 0.4) (layer "B.Cu") (net 2))
  (segment (start 101.389 72.211) (end 100.881 72.211) (width 0.4) (layer "B.Cu") (net 2))
  (segment (start 99.901 75.472) (end 99.901 73.191) (width 0.5) (layer "B.Cu") (net 2))
  (segment (start 96.243 79.966) (end 96.243 79.13) (width 0.5) (layer "B.Cu") (net 2))
  (segment (start 99.901 73.191) (end 100.881 72.211) (width 0.5) (layer "B.Cu") (net 2))
  (segment (start 96.243 79.13) (end 99.901 75.472) (width 0.5) (layer "B.Cu") (net 2))
  (segment (start 100.432 66.183) (end 100.881 65.734) (width 0.5) (layer "F.Cu") (net 3))
  (segment (start 97.887 66.183) (end 100.432 66.183) (width 0.5) (layer "F.Cu") (net 3))
  (via (at 100.881 65.734) (size 0.5) (drill 0.15) (layers "F.Cu" "B.Cu") (net 3))
  (segment (start 97.243 62.884) (end 97.243 64.128) (width 0.4) (layer "B.Cu") (net 3))
  (segment (start 97.243 64.128) (end 98.849 65.734) (width 0.4) (layer "B.Cu") (net 3))
  (segment (start 98.849 65.734) (end 101.008 65.734) (width 0.4) (layer "B.Cu") (net 3))
  (segment (start 101.008 65.734) (end 102.278 67.004) (width 0.4) (layer "B.Cu") (net 3))
  (segment (start 101.025 93.425) (end 101.025 91.571) (width 0.254) (layer "F.Cu") (net 4))
  (segment (start 101.025 91.571) (end 100.304 90.85) (width 0.254) (layer "F.Cu") (net 4))
  (segment (start 100.304 90.85) (end 99.65 90.85) (width 0.254) (layer "F.Cu") (net 4))
  (segment (start 100.025 93.85) (end 99.625 94.25) (width 0.254) (layer "F.Cu") (net 4))
  (segment (start 100.6 93.85) (end 101.025 93.425) (width 0.254) (layer "F.Cu") (net 4))
  (segment (start 100.6 93.85) (end 100.025 93.85) (width 0.254) (layer "F.Cu") (net 4))
  (via (at 110 87.96) (size 0.5) (drill 0.15) (layers "F.Cu" "B.Cu") (free) (net 4))
  (via (at 104 93.75) (size 0.5) (drill 0.15) (layers "F.Cu" "B.Cu") (free) (net 4))
  (via (at 110 83.96) (size 0.5) (drill 0.15) (layers "F.Cu" "B.Cu") (free) (net 4))
  (via (at 110 85.96) (size 0.5) (drill 0.15) (layers "F.Cu" "B.Cu") (free) (net 4))
  (via (at 104 89.75) (size 0.5) (drill 0.15) (layers "F.Cu" "B.Cu") (free) (net 4))
  (via (at 110 86.96) (size 0.5) (drill 0.15) (layers "F.Cu" "B.Cu") (free) (net 4))
  (via (at 104 90.75) (size 0.5) (drill 0.15) (layers "F.Cu" "B.Cu") (free) (net 4))
  (via (at 110 84.96) (size 0.5) (drill 0.15) (layers "F.Cu" "B.Cu") (free) (net 4))
  (via (at 104 92.75) (size 0.5) (drill 0.15) (layers "F.Cu" "B.Cu") (free) (net 4))
  (via (at 104 91.75) (size 0.5) (drill 0.15) (layers "F.Cu" "B.Cu") (free) (net 4))
  (via (at 100.6 93.85) (size 0.5) (drill 0.15) (layers "F.Cu" "B.Cu") (net 4))
  (segment (start 101.377 93.85) (end 101.78 93.447) (width 0.254) (layer "B.Cu") (net 4))
  (segment (start 100.6 93.85) (end 101.377 93.85) (width 0.254) (layer "B.Cu") (net 4))
  (segment (start 93.0405 92.075) (end 92.3905 91.425) (width 0.254) (layer "F.Cu") (net 5))
  (via (at 88.1 92.7) (size 0.5) (drill 0.15) (layers "F.Cu" "B.Cu") (free) (net 5))
  (via (at 88.5 92.2) (size 0.5) (drill 0.15) (layers "F.Cu" "B.Cu") (free) (net 5))
  (via (at 88.9 92.7) (size 0.5) (drill 0.15) (layers "F.Cu" "B.Cu") (free) (net 5))
  (via (at 88.9 91.7) (size 0.5) (drill 0.15) (layers "F.Cu" "B.Cu") (free) (net 5))
  (via (at 88.1 91.7) (size 0.5) (drill 0.15) (layers "F.Cu" "B.Cu") (free) (net 5))
  (segment (start 98.916 91.566) (end 98.916 89.402) (width 0.254) (layer "F.Cu") (net 6))
  (segment (start 99.95 92.6) (end 98.916 91.566) (width 0.254) (layer "F.Cu") (net 6))
  (segment (start 90.073 87.327) (end 90.073 90.099) (width 0.15) (layer "F.Cu") (net 6))
  (segment (start 90.785 86.615) (end 90.073 87.327) (width 0.15) (layer "F.Cu") (net 6))
  (segment (start 97.57 93.72) (end 98.225 94.375) (width 0.254) (layer "F.Cu") (net 6))
  (segment (start 93.8 86.615) (end 91 86.615) (width 0.15) (layer "F.Cu") (net 6))
  (segment (start 99.95 92.65) (end 98.225 94.375) (width 0.254) (layer "F.Cu") (net 6))
  (via (at 88.2 93.9) (size 0.5) (drill 0.15) (layers "F.Cu" "B.Cu") (free) (net 6))
  (via (at 117 92.25) (size 0.5) (drill 0.15) (layers "F.Cu" "B.Cu") (free) (net 6))
  (via (at 117 91.5) (size 0.5) (drill 0.15) (layers "F.Cu" "B.Cu") (free) (net 6))
  (via (at 117 90) (size 0.5) (drill 0.15) (layers "F.Cu" "B.Cu") (free) (net 6))
  (via (at 87.25 93.9) (size 0.5) (drill 0.15) (layers "F.Cu" "B.Cu") (free) (net 6))
  (via (at 87.75 94.5) (size 0.5) (drill 0.15) (layers "F.Cu" "B.Cu") (free) (net 6))
  (via (at 117 93) (size 0.5) (drill 0.15) (layers "F.Cu" "B.Cu") (free) (net 6))
  (via (at 117 90.75) (size 0.5) (drill 0.15) (layers "F.Cu" "B.Cu") (free) (net 6))
  (via (at 88.2 95.1) (size 0.5) (drill 0.15) (layers "F.Cu" "B.Cu") (free) (net 6))
  (via (at 87.25 95.1) (size 0.5) (drill 0.15) (layers "F.Cu" "B.Cu") (free) (net 6))
  (via (at 97.57 93.72) (size 0.5) (drill 0.15) (layers "F.Cu" "B.Cu") (net 6))
  (segment (start 97.57 93.72) (end 96.647 93.72) (width 0.254) (layer "B.Cu") (net 6))
  (segment (start 96.647 93.72) (end 96.338 93.411) (width 0.254) (layer "B.Cu") (net 6))
  (segment (start 101.706956 73.506) (end 101.233401 73.032445) (width 0.254) (layer "B.Cu") (net 7))
  (segment (start 102.315 73.506) (end 101.706956 73.506) (width 0.254) (layer "B.Cu") (net 7))
  (segment (start 103.8655 68.274) (end 104.31 67.8295) (width 0.4) (layer "B.Cu") (net 8))
  (segment (start 104.31 67.8295) (end 104.31 66.1785) (width 0.4) (layer "B.Cu") (net 8))
  (segment (start 104.31 66.1785) (end 103.8655 65.734) (width 0.4) (layer "B.Cu") (net 8))
  (segment (start 103.8655 65.734) (end 103.675 65.734) (width 0.4) (layer "B.Cu") (net 8))
  (segment (start 103.271 68.274) (end 103.8655 68.274) (width 0.4) (layer "B.Cu") (net 8))
  (segment (start 103.8655 68.274) (end 104.31 68.7185) (width 0.4) (layer "B.Cu") (net 8))
  (segment (start 104.31 68.7185) (end 104.31 70.4965) (width 0.4) (layer "B.Cu") (net 8))
  (segment (start 104.31 70.4965) (end 103.8655 70.941) (width 0.4) (layer "B.Cu") (net 8))
  (segment (start 103.271 70.941) (end 103.8655 70.941) (width 0.4) (layer "B.Cu") (net 8))
  (segment (start 103.8655 70.941) (end 104.31 71.3855) (width 0.4) (layer "B.Cu") (net 8))
  (segment (start 104.31 71.3855) (end 104.31 72.973) (width 0.4) (layer "B.Cu") (net 8))
  (segment (start 104.31 72.973) (end 103.802 73.481) (width 0.4) (layer "B.Cu") (net 8))
  (segment (start 103.802 73.481) (end 103.271 73.481) (width 0.4) (layer "B.Cu") (net 8))
  (segment (start 103.675 65.734) (end 103.271 65.734) (width 0.4) (layer "B.Cu") (net 8))
  (segment (start 104.31 65.2895) (end 104.31 64.101) (width 0.4) (layer "B.Cu") (net 8))
  (segment (start 99.72 59.511) (end 99.121 59.511) (width 0.4) (layer "B.Cu") (net 8))
  (segment (start 103.8655 65.734) (end 104.31 65.2895) (width 0.4) (layer "B.Cu") (net 8))
  (segment (start 104.31 64.101) (end 99.72 59.511) (width 0.4) (layer "B.Cu") (net 8))
  (segment (start 102.301 70.941) (end 102.301 71.345) (width 0.254) (layer "B.Cu") (net 9))
  (segment (start 102.301 71.345) (end 102.532 71.576) (width 0.254) (layer "B.Cu") (net 9))
  (segment (start 102.532 71.576) (end 103.04 71.576) (width 0.254) (layer "B.Cu") (net 9))
  (segment (start 103.04 71.576) (end 103.271 71.807) (width 0.254) (layer "B.Cu") (net 9))
  (segment (start 103.271 71.807) (end 103.271 72.211) (width 0.254) (layer "B.Cu") (net 9))
  (segment (start 102.956 67.639) (end 103.271 67.324) (width 0.25) (layer "B.Cu") (net 10))
  (segment (start 102.301 67.992232) (end 102.654232 67.639) (width 0.25) (layer "B.Cu") (net 10))
  (segment (start 103.271 67.324) (end 103.271 67.004) (width 0.25) (layer "B.Cu") (net 10))
  (segment (start 102.654232 67.639) (end 102.956 67.639) (width 0.25) (layer "B.Cu") (net 10))
  (segment (start 102.301 68.274) (end 102.301 67.992232) (width 0.25) (layer "B.Cu") (net 10))
  (segment (start 170.97772 96.07228) (end 170.942 96.108) (width 0.254) (layer "F.Cu") (net 11))
  (segment (start 80.077158 79.5) (end 80.633579 80.056421) (width 0.5) (layer "F.Cu") (net 11))
  (segment (start 167.37772 95.34168) (end 167.37772 96.09972) (width 0.2) (layer "F.Cu") (net 11))
  (segment (start 166.57772 57.66772) (end 166.57772 58.26168) (width 0.2) (layer "F.Cu") (net 11))
  (segment (start 163.77772 96.09678) (end 163.7665 96.108) (width 0.2) (layer "F.Cu") (net 11))
  (segment (start 157.775 62.0445) (end 157.77772 62.04178) (width 0.254) (layer "F.Cu") (net 11))
  (segment (start 169.77772 91.55728) (end 169.799 91.536) (width 0.254) (layer "F.Cu") (net 11))
  (segment (start 170.584 58.2554) (end 170.57772 58.26168) (width 0.2) (layer "F.Cu") (net 11))
  (segment (start 160.157279 91.64) (end 161.245062 91.64) (width 0.2) (layer "F.Cu") (net 11))
  (segment (start 174.76 57.19) (end 174.57772 57.37228) (width 0.2) (layer "F.Cu") (net 11))
  (segment (start 123.2858 69.5942) (end 123.2858 68.8842) (width 0.254) (layer "F.Cu") (net 11))
  (segment (start 161.245062 91.64) (end 161.37772 91.772658) (width 0.2) (layer "F.Cu") (net 11))
  (segment (start 173.47 62.1) (end 173.34 62.1) (width 0.2) (layer "F.Cu") (net 11))
  (segment (start 169.1288 70.177) (end 169.1264 70.1746) (width 0.254) (layer "F.Cu") (net 11))
  (segment (start 162.57772 92.26168) (end 162.57772 91.64528) (width 0.2) (layer "F.Cu") (net 11))
  (segment (start 175.959 84.701) (end 175.959 83.428285) (width 0.4) (layer "F.Cu") (net 11))
  (segment (start 166.57 57.66) (end 166.57772 57.66772) (width 0.2) (layer "F.Cu") (net 11))
  (segment (start 174.57772 95.737039) (end 174.57772 95.34168) (width 0.15) (layer "F.Cu") (net 11))
  (segment (start 173.37772 95.34168) (end 173.37772 96.08528) (width 0.2) (layer "F.Cu") (net 11))
  (segment (start 157.77772 92.26168) (end 157.77772 91.428784) (width 0.2) (layer "F.Cu") (net 11))
  (segment (start 166.17772 96.10622) (end 166.1795 96.108) (width 0.2) (layer "F.Cu") (net 11))
  (segment (start 172.17772 96.07372) (end 172.212 96.108) (width 0.2) (layer "F.Cu") (net 11))
  (segment (start 170.859398 57.57) (end 170.584 57.845398) (width 0.2) (layer "F.Cu") (net 11))
  (segment (start 169.77772 92.26168) (end 169.77772 91.55728) (width 0.2) (layer "F.Cu") (net 11))
  (segment (start 162.57772 62.02071) (end 162.6235 62.06649) (width 0.254) (layer "F.Cu") (net 11))
  (segment (start 163.77772 95.34168) (end 163.77772 96.09678) (width 0.2) (layer "F.Cu") (net 11))
  (segment (start 166.74956 71.34872) (end 165.87456 71.34872) (width 0.254) (layer "F.Cu") (net 11))
  (segment (start 123.2458 69.6342) (end 123.2858 69.5942) (width 0.254) (layer "F.Cu") (net 11))
  (segment (start 162.814 91.409) (end 163.83 91.409) (width 0.2) (layer "F.Cu") (net 11))
  (segment (start 168.57772 96.05928) (end 168.529 96.108) (width 0.254) (layer "F.Cu") (net 11))
  (segment (start 158.97772 91.772658) (end 158.97772 92.26168) (width 0.2) (layer "F.Cu") (net 11))
  (segment (start 173.34 62.1) (end 172.97772 61.73772) (width 0.2) (layer "F.Cu") (net 11))
  (segment (start 167.28128 71.34872) (end 167.354897 71.275103) (width 0.254) (layer "F.Cu") (net 11))
  (segment (start 160.15322 91.644059) (end 159.106319 91.644059) (width 0.2) (layer "F.Cu") (net 11))
  (segment (start 168.58 57.66) (end 168.57772 57.66228) (width 0.2) (layer "F.Cu") (net 11))
  (segment (start 174.57772 61.34168) (end 174.57772 61.96122) (width 0.2) (layer "F.Cu") (net 11))
  (segment (start 160.17772 96.07728) (end 160.147 96.108) (width 0.254) (layer "F.Cu") (net 11))
  (segment (start 170.97772 95.34168) (end 170.97772 96.07228) (width 0.2) (layer "F.Cu") (net 11))
  (segment (start 167.37772 96.09972) (end 167.386 96.108) (width 0.254) (layer "F.Cu") (net 11))
  (segment (start 162.97772 57.66278) (end 162.97772 58.26168) (width 0.2) (layer "F.Cu") (net 11))
  (segment (start 175.77772 95.737039) (end 175.77772 95.34168) (width 0.15) (layer "F.Cu") (net 11))
  (segment (start 161.37772 95.34168) (end 161.37772 96.06872) (width 0.2) (layer "F.Cu") (net 11))
  (segment (start 164.97772 96.10328) (end 164.973 96.108) (width 0.2) (layer "F.Cu") (net 11))
  (segment (start 170.97772 91.57172) (end 170.942 91.536) (width 0.254) (layer "F.Cu") (net 11))
  (segment (start 162.57772 96.09028) (end 162.56 96.108) (width 0.254) (layer "F.Cu") (net 11))
  (segment (start 166.74956 71.34872) (end 167.28128 71.34872) (width 0.254) (layer "F.Cu") (net 11))
  (segment (start 170.97772 62.044206) (end 170.997231 62.063717) (width 0.254) (layer "F.Cu") (net 11))
  (segment (start 175.77772 61.95628) (end 175.77772 61.34168) (width 0.2) (layer "F.Cu") (net 11))
  (segment (start 174.2 96.114759) (end 174.57772 95.737039) (width 0.15) (layer "F.Cu") (net 11))
  (segment (start 169.77772 95.34168) (end 169.77772 96.08672) (width 0.2) (layer "F.Cu") (net 11))
  (segment (start 176.97772 61.94372) (end 176.97772 61.34168) (width 0.2) (layer "F.Cu") (net 11))
  (segment (start 82.286421 80.056421) (end 82.29 80.06) (width 0.5) (layer "F.Cu") (net 11))
  (segment (start 164.97772 92.26168) (end 164.97772 91.66772) (width 0.2) (layer "F.Cu") (net 11))
  (segment (start 160.15322 91.644059) (end 160.17772 91.668559) (width 0.2) (layer "F.Cu") (net 11))
  (segment (start 151.4 59.35) (end 150.95 58.9) (width 0.254) (layer "F.Cu") (net 11))
  (segment (start 162.57772 95.34168) (end 162.57772 96.09028) (width 0.2) (layer "F.Cu") (net 11))
  (segment (start 169.1288 72.4606) (end 169.1288 71.1906) (width 0.254) (layer "F.Cu") (net 11))
  (segment (start 166.97772 62.048439) (end 166.992998 62.063717) (width 0.254) (layer "F.Cu") (net 11))
  (segment (start 169.1288 71.1906) (end 169.1288 70.177) (width 0.254) (layer "F.Cu") (net 11))
  (segment (start 161.37772 91.772658) (end 161.37772 92.26168) (width 0.2) (layer "F.Cu") (net 11))
  (segment (start 177.661983 58.090017) (end 177.149383 58.090017) (width 0.2) (layer "F.Cu") (net 11))
  (segment (start 157.77772 96.06428) (end 157.734 96.108) (width 0.254) (layer "F.Cu") (net 11))
  (segment (start 164.719 91.409) (end 163.83 91.409) (width 0.2) (layer "F.Cu") (net 11))
  (segment (start 169.77772 96.08672) (end 169.799 96.108) (width 0.254) (layer "F.Cu") (net 11))
  (segment (start 85.185 84.015) (end 85 84.2) (width 0.254) (layer "F.Cu") (net 11))
  (segment (start 174.57772 92.26168) (end 174.57772 91.58328) (width 0.2) (layer "F.Cu") (net 11))
  (segment (start 166.97772 60.554995) (end 166.992998 60.539717) (width 0.2) (layer "F.Cu") (net 11))
  (segment (start 175.959 83.428285) (end 176.174202 83.213083) (width 0.18) (layer "F.Cu") (net 11))
  (segment (start 173.37772 92.26168) (end 173.37772 91.55872) (width 0.2) (layer "F.Cu") (net 11))
  (segment (start 175.77772 58.80628) (end 175.334 59.25) (width 0.2) (layer "F.Cu") (net 11))
  (segment (start 170.97772 61.34168) (end 170.97772 60.51228) (width 0.254) (layer "F.Cu") (net 11))
  (segment (start 173.37772 91.55872) (end 173.355 91.536) (width 0.254) (layer "F.Cu") (net 11))
  (segment (start 174.57772 57.37228) (end 174.57772 58.26168) (width 0.2) (layer "F.Cu") (net 11))
  (segment (start 80.633579 80.056421) (end 82.286421 80.056421) (width 0.5) (layer "F.Cu") (net 11))
  (segment (start 82.29 80.06) (end 82.293937 80.056063) (width 0.5) (layer "F.Cu") (net 11))
  (segment (start 163.77772 91.46128) (end 163.83 91.409) (width 0.2) (layer "F.Cu") (net 11))
  (segment (start 161.37772 96.06872) (end 161.417 96.108) (width 0.254) (layer "F.Cu") (net 11))
  (segment (start 165.87456 71.34872) (end 165.19956 72.02372) (width 0.254) (layer "F.Cu") (net 11))
  (segment (start 165.37772 61.34168) (end 165.37772 62.037339) (width 0.2) (layer "F.Cu") (net 11))
  (segment (start 166.17772 95.34168) (end 166.17772 96.10622) (width 0.2) (layer "F.Cu") (net 11))
  (segment (start 169.09 69.41) (end 169.09 70.1382) (width 0.254) (layer "F.Cu") (net 11))
  (segment (start 175.77772 58.26168) (end 175.77772 58.80628) (width 0.2) (layer "F.Cu") (net 11))
  (segment (start 177.234 62.15) (end 177.184 62.15) (width 0.2) (layer "F.Cu") (net 11))
  (segment (start 176.175 96.134319) (end 175.77772 95.737039) (width 0.15) (layer "F.Cu") (net 11))
  (segment (start 163.77772 92.26168) (end 163.77772 91.46128) (width 0.2) (layer "F.Cu") (net 11))
  (segment (start 168.97772 61.34168) (end 168.97772 62.004248) (width 0.2) (layer "F.Cu") (net 11))
  (segment (start 165.37772 57.66772) (end 165.37772 58.26168) (width 0.2) (layer "F.Cu") (net 11))
  (segment (start 160.66 73.6) (end 160.075 74.185) (width 0.254) (layer "F.Cu") (net 11))
  (segment (start 157.77772 95.34168) (end 157.77772 96.06428) (width 0.2) (layer "F.Cu") (net 11))
  (segment (start 172.57772 57.79372) (end 172.354 57.57) (width 0.2) (layer "F.Cu") (net 11))
  (segment (start 168.97772 62.004248) (end 168.918251 62.063717) (width 0.254) (layer "F.Cu") (net 11))
  (segment (start 164.17772 62.03321) (end 164.211 62.06649) (width 0.254) (layer "F.Cu") (net 11))
  (segment (start 160.075 74.185) (end 159.99 74.185) (width 0.254) (layer "F.Cu") (net 11))
  (segment (start 164.18 57.66) (end 164.17772 57.66228) (width 0.2) (layer "F.Cu") (net 11))
  (segment (start 157.77772 61.880995) (end 157.77772 61.34168) (width 0.2) (layer "F.Cu") (net 11))
  (segment (start 158.97772 95.34168) (end 158.97772 96.08172) (width 0.2) (layer "F.Cu") (net 11))
  (segment (start 162.9805 57.66) (end 162.97772 57.66278) (width 0.2) (layer "F.Cu") (net 11))
  (segment (start 175.667897 91.337897) (end 175.77772 91.44772) (width 0.2) (layer "F.Cu") (net 11))
  (segment (start 168.57772 95.34168) (end 168.57772 96.05928) (width 0.2) (layer "F.Cu") (net 11))
  (segment (start 172.17772 92.26168) (end 172.17772 91.57028) (width 0.2) (layer "F.Cu") (net 11))
  (segment (start 157.77772 91.428784) (end 157.797504 91.409) (width 0.254) (layer "F.Cu") (net 11))
  (segment (start 164.17772 61.34168) (end 164.17772 62.03321) (width 0.2) (layer "F.Cu") (net 11))
  (segment (start 176.175 96.175) (end 176.175 96.134319) (width 0.15) (layer "F.Cu") (net 11))
  (segment (start 168.57772 57.66228) (end 168.57772 58.26168) (width 0.2) (layer "F.Cu") (net 11))
  (segment (start 169.09 70.1382) (end 169.1264 70.1746) (width 0.254) (layer "F.Cu") (net 11))
  (segment (start 174.41 91.49) (end 174.50328 91.58328) (width 0.254) (layer "F.Cu") (net 11))
  (segment (start 166.1 91.395949) (end 166.17772 91.473669) (width 0.2) (layer "F.Cu") (net 11))
  (segment (start 159.2 78.8) (end 158 78.8) (width 0.254) (layer "F.Cu") (net 11))
  (segment (start 172.17772 95.34168) (end 172.17772 96.07372) (width 0.2) (layer "F.Cu") (net 11))
  (segment (start 177.184 62.15) (end 176.97772 61.94372) (width 0.2) (layer "F.Cu") (net 11))
  (segment (start 85.75 84.015) (end 85.185 84.015) (width 0.254) (layer "F.Cu") (net 11))
  (segment (start 172.354 57.57) (end 170.859398 57.57) (width 0.2) (layer "F.Cu") (net 11))
  (segment (start 160.17772 91.668559) (end 160.17772 92.26168) (width 0.2) (layer "F.Cu") (net 11))
  (segment (start 162.57772 91.64528) (end 162.814 91.409) (width 0.2) (layer "F.Cu") (net 11))
  (segment (start 175.77772 91.44772) (end 175.77772 92.26168) (width 0.2) (layer "F.Cu") (net 11))
  (segment (start 164.17772 57.66228) (end 164.17772 58.26168) (width 0.2) (layer "F.Cu") (net 11))
  (segment (start 164.97772 95.34168) (end 164.97772 96.10328) (width 0.2) (layer "F.Cu") (net 11))
  (segment (start 174.2 96.2) (end 174.2 96.114759) (width 0.15) (layer "F.Cu") (net 11))
  (segment (start 158.97772 96.08172) (end 159.004 96.108) (width 0.254) (layer "F.Cu") (net 11))
  (segment (start 159.106319 91.644059) (end 158.97772 91.772658) (width 0.2) (layer "F.Cu") (net 11))
  (segment (start 152.08 59.35) (end 151.4 59.35) (width 0.254) (layer "F.Cu") (net 11))
  (segment (start 164.7322 70.4032) (end 164.7322 71.55636) (width 0.254) (layer "F.Cu") (net 11))
  (segment (start 160.15322 91.644059) (end 160.157279 91.64) (width 0.2) (layer "F.Cu") (net 11))
  (segment (start 172.17772 91.57028) (end 172.212 91.536) (width 0.254) (layer "F.Cu") (net 11))
  (segment (start 170.97772 61.34168) (end 170.97772 62.044206) (width 0.254) (layer "F.Cu") (net 11))
  (segment (start 81.745 84.811) (end 79.35322 84.811) (width 0.4) (layer "F.Cu") (net 11))
  (segment (start 166.97772 61.34168) (end 166.97772 62.048439) (width 0.2) (layer "F.Cu") (net 11))
  (segment (start 164.97772 91.66772) (end 164.719 91.409) (width 0.2) (layer "F.Cu") (net 11))
  (segment (start 177.149383 58.090017) (end 176.97772 58.26168) (width 0.2) (layer "F.Cu") (net 11))
  (segment (start 152.842 60.455) (end 152.842 61.813) (width 0.254) (layer "F.Cu") (net 11))
  (segment (start 173.37772 96.08528) (end 173.355 96.108) (width 0.2) (layer "F.Cu") (net 11))
  (segment (start 172.97772 61.73772) (end 172.97772 61.34168) (width 0.2) (layer "F.Cu") (net 11))
  (segment (start 166.17772 91.473669) (end 166.17772 92.26168) (width 0.2) (layer "F.Cu") (net 11))
  (segment (start 170.97772 92.26168) (end 170.97772 91.57172) (width 0.2) (layer "F.Cu") (net 11))
  (segment (start 152.842 60.112) (end 152.08 59.35) (width 0.254) (layer "F.Cu") (net 11))
  (segment (start 165.37 57.66) (end 165.37772 57.66772) (width 0.2) (layer "F.Cu") (net 11))
  (segment (start 166.97772 61.34168) (end 166.97772 60.554995) (width 0.2) (layer "F.Cu") (net 11))
  (segment (start 157.77772 62.04178) (end 157.77772 61.891237) (width 0.254) (layer "F.Cu") (net 11))
  (segment (start 172.57772 58.26168) (end 172.57772 57.79372) (width 0.2) (layer "F.Cu") (net 11))
  (segment (start 162.57772 61.34168) (end 162.57772 62.02071) (width 0.2) (layer "F.Cu") (net 11))
  (segment (start 175.584 62.15) (end 175.77772 61.95628) (width 0.2) (layer "F.Cu") (net 11))
  (segment (start 165.6212 70.4032) (end 165.6212 71.60208) (width 0.254) (layer "F.Cu") (net 11))
  (segment (start 82.293937 80.056063) (end 84.601262 80.056063) (width 0.5) (layer "F.Cu") (net 11))
  (segment (start 170.584 57.845398) (end 170.584 58.2554) (width 0.2) (layer "F.Cu") (net 11))
  (segment (start 160.17772 95.34168) (end 160.17772 96.07728) (width 0.2) (layer "F.Cu") (net 11))
  (segment (start 79.3635 79.5) (end 80.077158 79.5) (width 0.5) (layer "F.Cu") (net 11))
  (via (at 80.633579 80.056421) (size 0.5) (drill 0.15) (layers "F.Cu" "B.Cu") (net 11))
  (via (at 82.29 80.06) (size 0.5) (drill 0.15) (layers "F.Cu" "B.Cu") (net 11))
  (via (at 84.601262 80.056063) (size 0.5) (drill 0.15) (layers "F.Cu" "B.Cu") (net 11))
  (via (at 176.835998 87.590717) (size 0.5) (drill 0.15) (layers "F.Cu" "B.Cu") (net 11))
  (via (at 176.174202 83.213083) (size 0.5) (drill 0.15) (layers "F.Cu" "B.Cu") (net 11))
  (via (at 169.977998 88.352717) (size 0.5) (drill 0.15) (layers "F.Cu" "B.Cu") (net 11))
  (via (at 169.101 88.352717) (size 0.5) (drill 0.15) (layers "F.Cu" "B.Cu") (net 11))
  (via (at 170.879 88.352717) (size 0.5) (drill 0.15) (layers "F.Cu" "B.Cu") (net 11))
  (via (at 175.692998 87.590717) (size 0.5) (drill 0.15) (layers "F.Cu" "B.Cu") (net 11))
  (via (at 178.232998 87.590717) (size 0.5) (drill 0.15) (layers "F.Cu" "B.Cu") (net 11))
  (via (at 188.519998 87.209717) (size 0.5) (drill 0.15) (layers "F.Cu" "B.Cu") (net 11))
  (via (at 185.725998 67.6) (size 0.5) (drill 0.15) (layers "F.Cu" "B.Cu") (net 11))
  (via (at 184.455998 66.508717) (size 0.5) (drill 0.15) (layers "F.Cu" "B.Cu") (net 11))
  (via (at 176.835998 65.873717) (size 0.5) (drill 0.15) (layers "F.Cu" "B.Cu") (net 11))
  (via (at 178.486998 65.873717) (size 0.5) (drill 0.15) (layers "F.Cu" "B.Cu") (net 11))
  (via (at 166.992998 62.063717) (size 0.5) (drill 0.15) (layers "F.Cu" "B.Cu") (net 11))
  (via (at 166.992998 60.539717) (size 0.5) (drill 0.15) (layers "F.Cu" "B.Cu") (net 11))
  (via (at 173.355 91.536) (size 0.5) (drill 0.15) (layers "F.Cu" "B.Cu") (net 11))
  (via (at 169.799 91.536) (size 0.5) (drill 0.15) (layers "F.Cu" "B.Cu") (net 11))
  (via (at 174.41 91.49) (size 0.5) (drill 0.15) (layers "F.Cu" "B.Cu") (net 11))
  (via (at 170.942 91.536) (size 0.5) (drill 0.15) (layers "F.Cu" "B.Cu") (net 11))
  (via (at 172.212 91.536) (size 0.5) (drill 0.15) (layers "F.Cu" "B.Cu") (net 11))
  (via (at 170.942 96.108) (size 0.5) (drill 0.15) (layers "F.Cu" "B.Cu") (net 11))
  (via (at 169.799 96.108) (size 0.5) (drill 0.15) (layers "F.Cu" "B.Cu") (net 11))
  (via (at 168.529 96.108) (size 0.5) (drill 0.15) (layers "F.Cu" "B.Cu") (net 11))
  (via (at 167.386 96.108) (size 0.5) (drill 0.15) (layers "F.Cu" "B.Cu") (net 11))
  (via (at 162.56 96.108) (size 0.5) (drill 0.15) (layers "F.Cu" "B.Cu") (net 11))
  (via (at 161.417 96.108) (size 0.5) (drill 0.15) (layers "F.Cu" "B.Cu") (net 11))
  (via (at 160.147 96.108) (size 0.5) (drill 0.15) (layers "F.Cu" "B.Cu") (net 11))
  (via (at 159.004 96.108) (size 0.5) (drill 0.15) (layers "F.Cu" "B.Cu") (net 11))
  (via (at 157.734 96.108) (size 0.5) (drill 0.15) (layers "F.Cu" "B.Cu") (net 11))
  (via (at 165.37 57.66) (size 0.5) (drill 0.15) (layers "F.Cu" "B.Cu") (net 11))
  (via (at 166.57 57.66) (size 0.5) (drill 0.15) (layers "F.Cu" "B.Cu") (net 11))
  (via (at 168.58 57.66) (size 0.5) (drill 0.15) (layers "F.Cu" "B.Cu") (net 11))
  (via (at 172.212 96.108) (size 0.5) (drill 0.15) (layers "F.Cu" "B.Cu") (net 11))
  (via (at 173.355 96.108) (size 0.5) (drill 0.15) (layers "F.Cu" "B.Cu") (net 11))
  (via (at 166.1795 96.108) (size 0.5) (drill 0.15) (layers "F.Cu" "B.Cu") (net 11))
  (via (at 164.973 96.108) (size 0.5) (drill 0.15) (layers "F.Cu" "B.Cu") (net 11))
  (via (at 163.7665 96.108) (size 0.5) (drill 0.15) (layers "F.Cu" "B.Cu") (net 11))
  (via (at 164.7322 70.4032) (size 0.5) (drill 0.15) (layers "F.Cu" "B.Cu") (net 11))
  (via (at 165.6212 70.4032) (size 0.5) (drill 0.15) (layers "F.Cu" "B.Cu") (net 11))
  (via (at 172.577719 57.66098) (size 0.5) (drill 0.15) (layers "F.Cu" "B.Cu") (net 11))
  (via (at 188.53 66.5) (size 0.5) (drill 0.15) (layers "F.Cu" "B.Cu") (net 11))
  (via (at 196.95 79.44) (size 0.5) (drill 0.15) (layers "F.Cu" "B.Cu") (net 11))
  (via (at 192.45 69.67) (size 0.5) (drill 0.15) (layers "F.Cu" "B.Cu") (free) (net 11))
  (via (at 85 84.2) (size 0.5) (drill 0.15) (layers "F.Cu" "B.Cu") (net 11))
  (via (at 163.83 91.409) (size 0.5) (drill 0.15) (layers "F.Cu" "B.Cu") (net 11))
  (via (at 189.92 69.35) (size 0.5) (drill 0.15) (layers "F.Cu" "B.Cu") (free) (net 11))
  (via (at 78.269 87.448) (size 0.5) (drill 0.15) (layers "F.Cu" "B.Cu") (net 11))
  (via (at 164.211 62.06649) (size 0.5) (drill 0.15) (layers "F.Cu" "B.Cu") (net 11))
  (via (at 193.07 70.32) (size 0.5) (drill 0.15) (layers "F.Cu" "B.Cu") (free) (net 11))
  (via (at 105.616 60.602) (size 0.5) (drill 0.15) (layers "F.Cu" "B.Cu") (net 11))
  (via (at 177.58 80.31) (size 0.5) (drill 0.15) (layers "F.Cu" "B.Cu") (net 11))
  (via (at 175.584 62.15) (size 0.5) (drill 0.15) (layers "F.Cu" "B.Cu") (net 11))
  (via (at 196.96 82.44) (size 0.5) (drill 0.15) (layers "F.Cu" "B.Cu") (net 11))
  (via (at 150.95 58.9) (size 0.5) (drill 0.15) (layers "F.Cu" "B.Cu") (net 11))
  (via (at 185.7248 86.2076) (size 0.5) (drill 0.15) (layers "F.Cu" "B.Cu") (net 11))
  (via (at 162.9805 57.66) (size 0.5) (drill 0.15) (layers "F.Cu" "B.Cu") (net 11))
  (via (at 175.334 59.25) (size 0.5) (drill 0.15) (layers "F.Cu" "B.Cu") (net 11))
  (via (at 158.4198 88.95) (size 0.5) (drill 0.15) (layers "F.Cu" "B.Cu") (net 11))
  (via (at 175.667897 91.337897) (size 0.5) (drill 0.15) (layers "F.Cu" "B.Cu") (net 11))
  (via (at 185.7248 74.4252) (size 0.5) (drill 0.15) (layers "F.Cu" "B.Cu") (net 11))
  (via (at 162.7886 88.7476) (size 0.5) (drill 0.15) (layers "F.Cu" "B.Cu") (net 11))
  (via (at 174.76 57.19) (size 0.5) (drill 0.15) (layers "F.Cu" "B.Cu") (net 11))
  (via (at 167.354897 71.275103) (size 0.5) (drill 0.15) (layers "F.Cu" "B.Cu") (net 11))
  (via (at 184.6 87.225) (size 0.5) (drill 0.15) (layers "F.Cu" "B.Cu") (net 11))
  (via (at 160.15 88.95) (size 0.5) (drill 0.15) (layers "F.Cu" "B.Cu") (net 11))
  (via (at 168.918251 62.063717) (size 0.5) (drill 0.15) (layers "F.Cu" "B.Cu") (net 11))
  (via (at 185.7248 83.312) (size 0.5) (drill 0.15) (layers "F.Cu" "B.Cu") (net 11))
  (via (at 190.795 68.525) (size 0.5) (drill 0.15) (layers "F.Cu" "B.Cu") (free) (net 11))
  (via (at 122.25 94.25) (size 0.5) (drill 0.15) (layers "F.Cu" "B.Cu") (free) (net 11))
  (via (at 187.075 92.2) (size 0.5) (drill 0.15) (layers "F.Cu" "B.Cu") (free) (net 11))
  (via (at 174.2 96.2) (size 0.5) (drill 0.15) (layers "F.Cu" "B.Cu") (net 11))
  (via (at 119 85.5) (size 0.5) (drill 0.15) (layers "F.Cu" "B.Cu") (free) (net 11))
  (via (at 194.2 71.49) (size 0.5) (drill 0.15) (layers "F.Cu" "B.Cu") (free) (net 11))
  (via (at 162.6235 62.06649) (size 0.5) (drill 0.15) (layers "F.Cu" "B.Cu") (net 11))
  (via (at 83.674 90.236) (size 0.5) (drill 0.15) (layers "F.Cu" "B.Cu") (net 11))
  (via (at 199.92 76.95) (size 0.5) (drill 0.15) (layers "F.Cu" "B.Cu") (net 11))
  (via (at 165.37772 62.037339) (size 0.5) (drill 0.15) (layers "F.Cu" "B.Cu") (net 11))
  (via (at 176.05 80.33) (size 0.5) (drill 0.15) (layers "F.Cu" "B.Cu") (net 11))
  (via (at 175.32 79.35) (size 0.5) (drill 0.15) (layers "F.Cu" "B.Cu") (free) (net 11))
  (via (at 119 84.75) (size 0.5) (drill 0.15) (layers "F.Cu" "B.Cu") (free) (net 11))
  (via (at 185.7248 75.7652) (size 0.5) (drill 0.15) (layers "F.Cu" "B.Cu") (net 11))
  (via (at 134.5 91) (size 0.5) (drill 0.15) (layers "F.Cu" "B.Cu") (free) (net 11))
  (via (at 164.18 57.66) (size 0.5) (drill 0.15) (layers "F.Cu" "B.Cu") (net 11))
  (via (at 135.25 90.5) (size 0.5) (drill 0.15) (layers "F.Cu" "B.Cu") (free) (net 11))
  (via (at 191.62 69.35) (size 0.5) (drill 0.15) (layers "F.Cu" "B.Cu") (free) (net 11))
  (via (at 185.725998 68.4837) (size 0.5) (drill 0.15) (layers "F.Cu" "B.Cu") (net 11))
  (via (at 177.661983 58.090017) (size 0.5) (drill 0.15) (layers "F.Cu" "B.Cu") (net 11))
  (via (at 123.2458 69.6342) (size 0.5) (drill 0.15) (layers "F.Cu" "B.Cu") (net 11))
  (via (at 135.25 89.5) (size 0.5) (drill 0.15) (layers "F.Cu" "B.Cu") (free) (net 11))
  (via (at 151.9682 72.2122) (size 0.5) (drill 0.15) (layers "F.Cu" "B.Cu") (net 11))
  (via (at 185.59 66.49) (size 0.5) (drill 0.15) (layers "F.Cu" "B.Cu") (net 11))
  (via (at 185.7248 85.1552) (size 0.5) (drill 0.15) (layers "F.Cu" "B.Cu") (net 11))
  (via (at 185.7248 78.1752) (size 0.5) (drill 0.15) (layers "F.Cu" "B.Cu") (net 11))
  (via (at 134.5 89) (size 0.5) (drill 0.15) (layers "F.Cu" "B.Cu") (free) (net 11))
  (via (at 189.675 90.575) (size 0.5) (drill 0.15) (layers "F.Cu" "B.Cu") (free) (net 11))
  (via (at 135.25 91.5) (size 0.5) (drill 0.15) (layers "F.Cu" "B.Cu") (free) (net 11))
  (via (at 93.756857 82.941) (size 0.5) (drill 0.15) (layers "F.Cu" "B.Cu") (net 11))
  (via (at 134.5 90) (size 0.5) (drill 0.15) (layers "F.Cu" "B.Cu") (free) (net 11))
  (via (at 189.92 68.525) (size 0.5) (drill 0.15) (layers "F.Cu" "B.Cu") (free) (net 11))
  (via (at 123 94.25) (size 0.5) (drill 0.15) (layers "F.Cu" "B.Cu") (free) (net 11))
  (via (at 177.234 62.15) (size 0.5) (drill 0.15) (layers "F.Cu" "B.Cu") (net 11))
  (via (at 190.795 67.7) (size 0.5) (drill 0.15) (layers "F.Cu" "B.Cu") (free) (net 11))
  (via (at 193.72 70.96) (size 0.5) (drill 0.15) (layers "F.Cu" "B.Cu") (free) (net 11))
  (via (at 185.7248 69.3674) (size 0.5) (drill 0.15) (layers "F.Cu" "B.Cu") (net 11))
  (via (at 196.95 80.92) (size 0.5) (drill 0.15) (layers "F.Cu" "B.Cu") (net 11))
  (via (at 176.175 96.175) (size 0.5) (drill 0.15) (layers "F.Cu" "B.Cu") (net 11))
  (via (at 195.68 73.24) (size 0.5) (drill 0.15) (layers "F.Cu" "B.Cu") (free) (net 11))
  (via (at 160.66 73.6) (size 0.5) (drill 0.15) (layers "F.Cu" "B.Cu") (net 11))
  (via (at 83.345 87.966) (size 0.5) (drill 0.15) (layers "F.Cu" "B.Cu") (net 11))
  (via (at 185.125 92.125) (size 0.5) (drill 0.15) (layers "F.Cu" "B.Cu") (free) (net 11))
  (via (at 160.15322 91.644059) (size 0.5) (drill 0.15) (layers "F.Cu" "B.Cu") (net 11))
  (via (at 119 88.5) (size 0.5) (drill 0.15) (layers "F.Cu" "B.Cu") (free) (net 11))
  (via (at 166.1 91.395949) (size 0.5) (drill 0.15) (layers "F.Cu" "B.Cu") (net 11))
  (via (at 196.74 74.52) (size 0.5) (drill 0.15) (layers "F.Cu" "B.Cu") (free) (net 11))
  (via (at 110.546 61.437) (size 0.5) (drill 0.15) (layers "F.Cu" "B.Cu") (net 11))
  (via (at 176.84 79.34) (size 0.5) (drill 0.15) (layers "F.Cu" "B.Cu") (free) (net 11))
  (via (at 119 87.75) (size 0.5) (drill 0.15) (layers "F.Cu" "B.Cu") (free) (net 11))
  (via (at 170.97772 60.51228) (size 0.5) (drill 0.15) (layers "F.Cu" "B.Cu") (net 11))
  (via (at 131.975 82.9) (size 0.8) (drill 0.4) (layers "F.Cu" "B.Cu") (net 11))
  (via (at 202.85 76.125) (size 0.5) (drill 0.15) (layers "F.Cu" "B.Cu") (net 11))
  (via (at 119 87) (size 0.5) (drill 0.15) (layers "F.Cu" "B.Cu") (free) (net 11))
  (via (at 157.797504 91.409) (size 0.5) (drill 0.15) (layers "F.Cu" "B.Cu") (net 11))
  (via (at 196.24 73.87) (size 0.5) (drill 0.15) (layers "F.Cu" "B.Cu") (free) (net 11))
  (via (at 185.73 70.58) (size 0.5) (drill 0.15) (layers "F.Cu" "B.Cu") (free) (net 11))
  (via (at 187.44 66.4972) (size 0.5) (drill 0.15) (layers "F.Cu" "B.Cu") (net 11))
  (via (at 119 86.25) (size 0.5) (drill 0.15) (layers "F.Cu" "B.Cu") (free) (net 11))
  (via (at 79.3635 79.5) (size 0.5) (drill 0.15) (layers "F.Cu" "B.Cu") (net 11))
  (via (at 187.535748 87.1982) (size 0.5) (drill 0.15) (layers "F.Cu" "B.Cu") (net 11))
  (via (at 123 95) (size 0.5) (drill 0.15) (layers "F.Cu" "B.Cu") (free) (net 11))
  (via (at 173.47 62.1) (size 0.5) (drill 0.15) (layers "F.Cu" "B.Cu") (net 11))
  (via (at 185.567248 87.2236) (size 0.5) (drill 0.15) (layers "F.Cu" "B.Cu") (net 11))
  (via (at 104.25 62.182083) (size 0.5) (drill 0.15) (layers "F.Cu" "B.Cu") (net 11))
  (via (at 195.23 72.62) (size 0.5) (drill 0.15) (layers "F.Cu" "B.Cu") (free) (net 11))
  (via (at 134 91.75) (size 0.5) (drill 0.15) (layers "F.Cu" "B.Cu") (free) (net 11))
  (via (at 163.957 90.3224) (size 0.5) (drill 0.15) (layers "F.Cu" "B.Cu") (net 11))
  (via (at 158 78.8) (size 0.5) (drill 0.15) (layers "F.Cu" "B.Cu") (net 11))
  (via (at 169.09 69.41) (size 0.5) (drill 0.15) (layers "F.Cu" "B.Cu") (net 11))
  (via (at 133 91.75) (size 0.5) (drill 0.15) (layers "F.Cu" "B.Cu") (free) (net 11))
  (via (at 157.775 62.0445) (size 0.5) (drill 0.15) (layers "F.Cu" "B.Cu") (net 11))
  (via (at 174.6885 62.072) (size 0.5) (drill 0.15) (layers "F.Cu" "B.Cu") (net 11))
  (via (at 190.795 69.35) (size 0.5) (drill 0.15) (layers "F.Cu" "B.Cu") (free) (net 11))
  (via (at 132 91.75) (size 0.5) (drill 0.15) (layers "F.Cu" "B.Cu") (free) (net 11))
  (via (at 185.7248 82.3952) (size 0.5) (drill 0.15) (layers "F.Cu" "B.Cu") (net 11))
  (via (at 185.7248 80.3052) (size 0.5) (drill 0.15) (layers "F.Cu" "B.Cu") (net 11))
  (via (at 187.925 90.55) (size 0.5) (drill 0.15) (layers "F.Cu" "B.Cu") (free) (net 11))
  (via (at 122.25 95) (size 0.5) (drill 0.15) (layers "F.Cu" "B.Cu") (free) (net 11))
  (via (at 186.551498 87.2236) (size 0.5) (drill 0.15) (layers "F.Cu" "B.Cu") (net 11))
  (via (at 194.7 72.02) (size 0.5) (drill 0.15) (layers "F.Cu" "B.Cu") (free) (net 11))
  (via (at 185.74 79.06) (size 0.5) (drill 0.15) (layers "F.Cu" "B.Cu") (net 11))
  (via (at 77.85 90.856) (size 0.5) (drill 0.15) (layers "F.Cu" "B.Cu") (net 11))
  (via (at 199.92 77.94) (size 0.5) (drill 0.15) (layers "F.Cu" "B.Cu") (net 11))
  (via (at 174.52 80.36) (size 0.5) (drill 0.15) (layers "F.Cu" "B.Cu") (net 11))
  (via (at 186.55 66.4972) (size 0.5) (drill 0.15) (layers "F.Cu" "B.Cu") (net 11))
  (via (at 196.97 83.95) (size 0.5) (drill 0.15) (layers "F.Cu" "B.Cu") (net 11))
  (via (at 189.92 67.7) (size 0.5) (drill 0.15) (layers "F.Cu" "B.Cu") (free) (net 11))
  (via (at 170.997231 62.063717) (size 0.5) (drill 0.15) (layers "F.Cu" "B.Cu") (net 11))
  (segment (start 185.7248 80.3052) (end 185.7248 81.1352) (width 0.254) (layer "B.Cu") (net 11))
  (segment (start 185.7248 78.0748) (end 185.7248 78.1752) (width 0.254) (layer "B.Cu") (net 11))
  (segment (start 187.314 73.628) (end 185.7376 73.628) (width 0.254) (layer "B.Cu") (net 11))
  (segment (start 134.8 92.796) (end 132.1 92.796) (width 0.254) (layer "B.Cu") (net 11))
  (segment (start 187.314 76.629) (end 185.789 76.629) (width 0.254) (layer "B.Cu") (net 11))
  (segment (start 151.9352 73.2164) (end 151.9352 72.2452) (width 0.254) (layer "B.Cu") (net 11))
  (segment (start 185.7248 85.7152) (end 185.7248 86.2076) (width 0.254) (layer "B.Cu") (net 11))
  (segment (start 84.15226 91.02978) (end 84.15226 90.71426) (width 0.254) (layer "B.Cu") (net 11))
  (segment (start 185.7248 81.1352) (end 185.7248 82.3952) (width 0.254) (layer "B.Cu") (net 11))
  (segment (start 173.022 80.368) (end 174.512 80.368) (width 0.254) (layer "B.Cu") (net 11))
  (segment (start 104.25 62.182083) (end 104.634917 62.567) (width 1) (layer "B.Cu") (net 11))
  (segment (start 86.775977 80.056063) (end 87.20226 79.62978) (width 0.5) (layer "B.Cu") (net 11))
  (segment (start 200.403 78.449) (end 199.92 77.966) (width 0.127) (layer "B.Cu") (net 11))
  (segment (start 77.82378 90.82978) (end 77.85 90.856) (width 0.5) (layer "B.Cu") (net 11))
  (segment (start 93.756857 82.941) (end 93 82.941) (width 0.254) (layer "B.Cu") (net 11))
  (segment (start 185.7248 82.3952) (end 185.7248 82.6548) (width 0.254) (layer "B.Cu") (net 11))
  (segment (start 185.7248 84.1852) (end 185.7248 85.1552) (width 0.254) (layer "B.Cu") (net 11))
  (segment (start 185.742 79.628) (end 185.7248 79.6452) (width 0.254) (layer "B.Cu") (net 11))
  (segment (start 187.314 84.127) (end 186.467498 84.127) (width 0.254) (layer "B.Cu") (net 11))
  (segment (start 196.969 82.449) (end 196.96 82.44) (width 0.15) (layer "B.Cu") (net 11))
  (segment (start 187.314 85.63) (end 185.81 85.63) (width 0.254) (layer "B.Cu") (net 11))
  (segment (start 185.731 81.129) (end 185.7248 81.1352) (width 0.254) (layer "B.Cu") (net 11))
  (segment (start 198.581 83.949) (end 196.971 83.949) (width 0.254) (layer "B.Cu") (net 11))
  (segment (start 185.7248 75.7652) (end 185.7248 76.5648) (width 0.254) (layer "B.Cu") (net 11))
  (segment (start 185.7248 79.6452) (end 185.7248 80.3052) (width 0.254) (layer "B.Cu") (net 11))
  (segment (start 185.781 84.129) (end 185.7248 84.1852) (width 0.254) (layer "B.Cu") (net 11))
  (segment (start 185.7248 85.1552) (end 185.7248 85.7152) (width 0.254) (layer "B.Cu") (net 11))
  (segment (start 185.7248 83.312) (end 185.7248 84.1852) (width 0.254) (layer "B.Cu") (net 11))
  (segment (start 198.581 77.949) (end 199.911 77.949) (width 0.15) (layer "B.Cu") (net 11))
  (segment (start 198.581 79.449) (end 196.959 79.449) (width 0.254) (layer "B.Cu") (net 11))
  (segment (start 200.008 81.449) (end 199.508 80.949) (width 0.127) (layer "B.Cu") (net 11))
  (segment (start 187.314 72.129) (end 185.871 72.129) (width 0.254) (layer "B.Cu") (net 11))
  (segment (start 185.7376 73.628) (end 185.7248 73.6152) (width 0.254) (layer "B.Cu") (net 11))
  (segment (start 200.131219 82.949) (end 201.245 82.949) (width 0.15) (layer "B.Cu") (net 11))
  (segment (start 201.245 75.45) (end 202.175 75.45) (width 0.127) (layer "B.Cu") (net 11))
  (segment (start 187.314 84.129) (end 185.781 84.129) (width 0.254) (layer "B.Cu") (net 11))
  (segment (start 185.8054 86.127) (end 185.7248 86.2076) (width 0.254) (layer "B.Cu") (net 11))
  (segment (start 199.631219 82.449) (end 200.131219 82.949) (width 0.15) (layer "B.Cu") (net 11))
  (segment (start 185.81 85.63) (end 185.7248 85.7152) (width 0.254) (layer "B.Cu") (net 11))
  (segment (start 187.314 86.127) (end 185.8054 86.127) (width 0.254) (layer "B.Cu") (net 11))
  (segment (start 199.921 76.949) (end 199.92 76.95) (width 0.254) (layer "B.Cu") (net 11))
  (segment (start 84.601262 79.380778) (end 84.80226 79.17978) (width 0.5) (layer "B.Cu") (net 11))
  (segment (start 185.7506 82.629) (end 185.7248 82.6548) (width 0.254) (layer "B.Cu") (net 11))
  (segment (start 105.618 59.13) (end 105.618 60.6) (width 1) (layer "B.Cu") (net 11))
  (segment (start 79.3635 79.5) (end 79.3575 79.506) (width 0.5) (layer "B.Cu") (net 11))
  (segment (start 84.601262 80.056063) (end 86.775977 80.056063) (width 0.5) (layer "B.Cu") (net 11))
  (segment (start 196.979 80.949) (end 196.95 80.92) (width 0.254) (layer "B.Cu") (net 11))
  (segment (start 185.7248 74.4252) (end 185.7248 75.1852) (width 0.254) (layer "B.Cu") (net 11))
  (segment (start 187.314 82.629) (end 185.7506 82.629) (width 0.254) (layer "B.Cu") (net 11))
  (segment (start 84.601262 80.056063) (end 84.601262 79.380778) (width 0.5) (layer "B.Cu") (net 11))
  (segment (start 185.779 78.129) (end 185.7248 78.0748) (width 0.254) (layer "B.Cu") (net 11))
  (segment (start 198.581 80.949) (end 196.979 80.949) (width 0.254) (layer "B.Cu") (net 11))
  (segment (start 187.314 75.128) (end 185.782 75.128) (width 0.254) (layer "B.Cu") (net 11))
  (segment (start 185.789 76.629) (end 185.7248 76.5648) (width 0.254) (layer "B.Cu") (net 11))
  (segment (start 174.512 80.368) (end 174.52 80.36) (width 0.254) (layer "B.Cu") (net 11))
  (segment (start 167.84 69.41) (end 169.09 69.41) (width 0.254) (layer "B.Cu") (net 11))
  (segment (start 185.7248 76.5648) (end 185.7248 78.0748) (width 0.254) (layer "B.Cu") (net 11))
  (segment (start 185.782 75.128) (end 185.7248 75.1852) (width 0.254) (layer "B.Cu") (net 11))
  (segment (start 131.975 83.755) (end 131.975 82.9) (width 0.5) (layer "B.Cu") (net 11))
  (segment (start 198.581 82.449) (end 199.631219 82.449) (width 0.15) (layer "B.Cu") (net 11))
  (segment (start 199.911 77.949) (end 199.92 77.94) (width 0.15) (layer "B.Cu") (net 11))
  (segment (start 199.508 80.949) (end 198.581 80.949) (width 0.127) (layer "B.Cu") (net 11))
  (segment (start 201.245 79.949) (end 200.082062 79.949) (width 0.127) (layer "B.Cu") (net 11))
  (segment (start 201.245 78.449) (end 200.403 78.449) (width 0.127) (layer "B.Cu") (net 11))
  (segment (start 201.245 81.449) (end 200.008 81.449) (width 0.127) (layer "B.Cu") (net 11))
  (segment (start 199.92 77.966) (end 199.92 77.94) (width 0.127) (layer "B.Cu") (net 11))
  (segment (start 105.618 60.6) (end 105.616 60.602) (width 1) (layer "B.Cu") (net 11))
  (segment (start 153.829 74.1196) (end 152.9258 73.2164) (width 0.254) (layer "B.Cu") (net 11))
  (segment (start 202.175 75.45) (end 202.85 76.125) (width 0.127) (layer "B.Cu") (net 11))
  (segment (start 187.314 78.129) (end 185.779 78.129) (width 0.254) (layer "B.Cu") (net 11))
  (segment (start 76.54226 90.82978) (end 77.82378 90.82978) (width 0.5) (layer "B.Cu") (net 11))
  (segment (start 78.250446 87.429446) (end 78.269 87.448) (width 0.5) (layer "B.Cu") (net 11))
  (segment (start 110.551 59.511) (end 110.551 61.432) (width 1) (layer "B.Cu") (net 11))
  (segment (start 201.245 76.949) (end 199.921 76.949) (width 0.254) (layer "B.Cu") (net 11))
  (segment (start 187.314 81.129) (end 185.731 81.129) (width 0.254) (layer "B.Cu") (net 11))
  (segment (start 198.581 74.45) (end 198.343 74.45) (width 0.254) (layer "B.Cu") (net 11))
  (segment (start 200.082062 79.949) (end 199.582062 79.449) (width 0.127) (layer "B.Cu") (net 11))
  (segment (start 110.551 61.432) (end 110.546 61.437) (width 1) (layer "B.Cu") (net 11))
  (segment (start 84.15226 90.71426) (end 83.674 90.236) (width 0.254) (layer "B.Cu") (net 11))
  (segment (start 185.7248 78.1752) (end 185.7248 79.6452) (width 0.254) (layer "B.Cu") (net 11))
  (segment (start 91.707 82.942) (end 92.955 82.942) (width 0.254) (layer "B.Cu") (net 11))
  (segment (start 198.581 82.449) (end 196.969 82.449) (width 0.15) (layer "B.Cu") (net 11))
  (segment (start 131.985 83.765) (end 131.975 83.755) (width 0.5) (layer "B.Cu") (net 11))
  (segment (start 199.582062 79.449) (end 198.581 79.449) (width 0.127) (layer "B.Cu") (net 11))
  (segment (start 185.7248 82.6548) (end 185.7248 83.312) (width 0.254) (layer "B.Cu") (net 11))
  (segment (start 185.7248 73.6152) (end 185.7248 74.4252) (width 0.254) (layer "B.Cu") (net 11))
  (segment (start 167.354897 69.895103) (end 167.84 69.41) (width 0.254) (layer "B.Cu") (net 11))
  (segment (start 79.3575 79.506) (end 76.56848 79.506) (width 0.5) (layer "B.Cu") (net 11))
  (segment (start 187.314 79.628) (end 185.742 79.628) (width 0.254) (layer "B.Cu") (net 11))
  (segment (start 104.634917 62.567) (end 106.306 62.567) (width 1) (layer "B.Cu") (net 11))
  (segment (start 185.871 72.129) (end 185.7248 72.2752) (width 0.254) (layer "B.Cu") (net 11))
  (segment (start 152.9258 73.2164) (end 151.9352 73.2164) (width 0.254) (layer "B.Cu") (net 11))
  (segment (start 151.9352 72.2452) (end 151.9682 72.2122) (width 0.254) (layer "B.Cu") (net 11))
  (segment (start 185.7248 75.1852) (end 185.7248 75.7652) (width 0.254) (layer "B.Cu") (net 11))
  (segment (start 76.418042 87.429446) (end 78.250446 87.429446) (width 0.5) (layer "B.Cu") (net 11))
  (segment (start 154.4828 74.1196) (end 153.829 74.1196) (width 0.254) (layer "B.Cu") (net 11))
  (segment (start 185.7248 72.2752) (end 185.7248 73.6152) (width 0.254) (layer "B.Cu") (net 11))
  (segment (start 196.959 79.449) (end 196.95 79.44) (width 0.254) (layer "B.Cu") (net 11))
  (segment (start 196.971 83.949) (end 196.97 83.95) (width 0.254) (layer "B.Cu") (net 11))
  (segment (start 167.354897 71.275103) (end 167.354897 69.895103) (width 0.254) (layer "B.Cu") (net 11))
  (segment (start 136.2258 71.2742) (end 135.9658 71.5342) (width 0.15) (layer "F.Cu") (net 12))
  (segment (start 135.7208 68.8842) (end 136.2258 69.3892) (width 0.15) (layer "F.Cu") (net 12))
  (segment (start 134.1258 71.5342) (end 134.1 71.56) (width 0.15) (layer "F.Cu") (net 12))
  (segment (start 135.9658 71.5342) (end 134.1258 71.5342) (width 0.15) (layer "F.Cu") (net 12))
  (segment (start 136.2258 69.3892) (end 136.2258 71.2742) (width 0.15) (layer "F.Cu") (net 12))
  (segment (start 133.2 68.8842) (end 135.7208 68.8842) (width 0.15) (layer "F.Cu") (net 12))
  (via (at 159.98 57.67) (size 0.5) (drill 0.15) (layers "F.Cu" "B.Cu") (net 12))
  (via (at 161.09 57.659989) (size 0.5) (drill 0.15) (layers "F.Cu" "B.Cu") (net 12))
  (via (at 161.63 57.659989) (size 0.5) (drill 0.15) (layers "F.Cu" "B.Cu") (net 12))
  (via (at 159.89 58.882) (size 0.5) (drill 0.15) (layers "F.Cu" "B.Cu") (net 12))
  (via (at 161.03 58.88) (size 0.5) (drill 0.15) (layers "F.Cu" "B.Cu") (net 12))
  (via (at 160.51 57.659989) (size 0.5) (drill 0.15) (layers "F.Cu" "B.Cu") (net 12))
  (via (at 160.47 58.882) (size 0.5) (drill 0.15) (layers "F.Cu" "B.Cu") (net 12))
  (via (at 133.5 70.96) (size 0.5) (drill 0.15) (layers "F.Cu" "B.Cu") (free) (net 12))
  (via (at 134.1 71.56) (size 0.5) (drill 0.15) (layers "F.Cu" "B.Cu") (free) (net 12))
  (via (at 124 90.8) (size 0.5) (drill 0.15) (layers "F.Cu" "B.Cu") (free) (net 12))
  (via (at 132.9 62.8) (size 0.5) (drill 0.15) (layers "F.Cu" "B.Cu") (free) (net 12))
  (via (at 197.29 67.96) (size 0.5) (drill 0.15) (layers "F.Cu" "B.Cu") (net 12))
  (via (at 131.7 70.96) (size 0.5) (drill 0.15) (layers "F.Cu" "B.Cu") (free) (net 12))
  (via (at 123.4 92.6) (size 0.5) (drill 0.15) (layers "F.Cu" "B.Cu") (free) (net 12))
  (via (at 199.75 68.72) (size 0.5) (drill 0.15) (layers "F.Cu" "B.Cu") (net 12))
  (via (at 198.8185 68.7) (size 0.5) (drill 0.15) (layers "F.Cu" "B.Cu") (net 12))
  (via (at 122.8 91.4) (size 0.5) (drill 0.15) (layers "F.Cu" "B.Cu") (free) (net 12))
  (via (at 132.9 61.6) (size 0.5) (drill 0.15) (layers "F.Cu" "B.Cu") (free) (net 12))
  (via (at 134.1 70.96) (size 0.5) (drill 0.15) (layers "F.Cu" "B.Cu") (free) (net 12))
  (via (at 133.5 61.6) (size 0.5) (drill 0.15) (layers "F.Cu" "B.Cu") (free) (net 12))
  (via (at 197.96 67.32) (size 0.5) (drill 0.15) (layers "F.Cu" "B.Cu") (net 12))
  (via (at 122.8 92) (size 0.5) (drill 0.15) (layers "F.Cu" "B.Cu") (free) (net 12))
  (via (at 132.9 71.56) (size 0.5) (drill 0.15) (layers "F.Cu" "B.Cu") (free) (net 12))
  (via (at 134.1 61.6) (size 0.5) (drill 0.15) (layers "F.Cu" "B.Cu") (free) (net 12))
  (via (at 132.3 61.6) (size 0.5) (drill 0.15) (layers "F.Cu" "B.Cu") (free) (net 12))
  (via (at 124 92.6) (size 0.5) (drill 0.15) (layers "F.Cu" "B.Cu") (free) (net 12))
  (via (at 133.5 62.8) (size 0.5) (drill 0.15) (layers "F.Cu" "B.Cu") (free) (net 12))
  (via (at 132.3 70.96) (size 0.5) (drill 0.15) (layers "F.Cu" "B.Cu") (free) (net 12))
  (via (at 124 92) (size 0.5) (drill 0.15) (layers "F.Cu" "B.Cu") (free) (net 12))
  (via (at 132.9 70.96) (size 0.5) (drill 0.15) (layers "F.Cu" "B.Cu") (free) (net 12))
  (via (at 161.6 58.88) (size 0.5) (drill 0.15) (layers "F.Cu" "B.Cu") (net 12))
  (via (at 123.4 92) (size 0.5) (drill 0.15) (layers "F.Cu" "B.Cu") (free) (net 12))
  (via (at 131.7 71.56) (size 0.5) (drill 0.15) (layers "F.Cu" "B.Cu") (free) (net 12))
  (via (at 122.8 92.6) (size 0.5) (drill 0.15) (layers "F.Cu" "B.Cu") (free) (net 12))
  (via (at 133.5 62.2) (size 0.5) (drill 0.15) (layers "F.Cu" "B.Cu") (free) (net 12))
  (via (at 131.1 71.56) (size 0.5) (drill 0.15) (layers "F.Cu" "B.Cu") (free) (net 12))
  (via (at 122.8 90.8) (size 0.5) (drill 0.15) (layers "F.Cu" "B.Cu") (free) (net 12))
  (via (at 198.06 68.02) (size 0.5) (drill 0.15) (layers "F.Cu" "B.Cu") (net 12))
  (via (at 134.1 62.8) (size 0.5) (drill 0.15) (layers "F.Cu" "B.Cu") (free) (net 12))
  (via (at 132.3 62.2) (size 0.5) (drill 0.15) (layers "F.Cu" "B.Cu") (free) (net 12))
  (via (at 123.4 90.8) (size 0.5) (drill 0.15) (layers "F.Cu" "B.Cu") (free) (net 12))
  (via (at 134.1 62.2) (size 0.5) (drill 0.15) (layers "F.Cu" "B.Cu") (free) (net 12))
  (via (at 132.3 71.56) (size 0.5) (drill 0.15) (layers "F.Cu" "B.Cu") (free) (net 12))
  (via (at 124 91.4) (size 0.5) (drill 0.15) (layers "F.Cu" "B.Cu") (free) (net 12))
  (via (at 132.3 62.8) (size 0.5) (drill 0.15) (layers "F.Cu" "B.Cu") (free) (net 12))
  (via (at 123.4 91.4) (size 0.5) (drill 0.15) (layers "F.Cu" "B.Cu") (free) (net 12))
  (via (at 197.28 67.33) (size 0.5) (drill 0.15) (layers "F.Cu" "B.Cu") (net 12))
  (via (at 196.61 67.31) (size 0.5) (drill 0.15) (layers "F.Cu" "B.Cu") (net 12))
  (via (at 132.9 62.2) (size 0.5) (drill 0.15) (layers "F.Cu" "B.Cu") (free) (net 12))
  (via (at 131.1 70.96) (size 0.5) (drill 0.15) (layers "F.Cu" "B.Cu") (free) (net 12))
  (via (at 133.5 71.56) (size 0.5) (drill 0.15) (layers "F.Cu" "B.Cu") (free) (net 12))
  (segment (start 134.8 94.196) (end 132.53 94.196) (width 0.254) (layer "B.Cu") (net 13))
  (segment (start 132.53 94.196) (end 132 93.666) (width 0.254) (layer "B.Cu") (net 13))
  (segment (start 134.8 94.196) (end 136.58 94.196) (width 0.254) (layer "B.Cu") (net 13))
  (segment (start 136.58 94.196) (end 137.41 93.366) (width 0.254) (layer "B.Cu") (net 13))
  (segment (start 129 94.796) (end 129 92.096) (width 0.254) (layer "B.Cu") (net 13))
  (segment (start 130.87 94.796) (end 129 94.796) (width 0.254) (layer "B.Cu") (net 13))
  (segment (start 132 93.666) (end 130.87 94.796) (width 0.254) (layer "B.Cu") (net 13))
  (segment (start 102.956 65.099) (end 103.271 64.784) (width 0.25) (layer "B.Cu") (net 14))
  (segment (start 102.654232 65.099) (end 102.956 65.099) (width 0.25) (layer "B.Cu") (net 14))
  (segment (start 103.271 64.784) (end 103.271 64.464) (width 0.25) (layer "B.Cu") (net 14))
  (segment (start 102.301 65.452232) (end 102.654232 65.099) (width 0.25) (layer "B.Cu") (net 14))
  (segment (start 102.301 65.734) (end 102.301 65.452232) (width 0.25) (layer "B.Cu") (net 14))
  (segment (start 188.45 91.087598) (end 188.45 90.925) (width 0.18) (layer "F.Cu") (net 15))
  (segment (start 183.473097 91.123097) (end 183.623097 91.123097) (width 0.18) (layer "F.Cu") (net 15))
  (segment (start 172.57772 95.34168) (end 172.57772 94.816679) (width 0.18) (layer "F.Cu") (net 15))
  (segment (start 172.712256 94.187256) (end 173.664512 93.235) (width 0.18) (layer "F.Cu") (net 15))
  (segment (start 181.558201 91.123097) (end 182.423097 91.123097) (width 0.18) (layer "F.Cu") (net 15))
  (segment (start 172.58772 94.293578) (end 172.670949 94.210349) (width 0.18) (layer "F.Cu") (net 15))
  (segment (start 188.414501 91.123097) (end 188.45 91.087598) (width 0.18) (layer "F.Cu") (net 15))
  (segment (start 172.57772 94.816679) (end 172.58772 94.806679) (width 0.18) (layer "F.Cu") (net 15))
  (segment (start 179.446298 93.235) (end 181.558201 91.123097) (width 0.18) (layer "F.Cu") (net 15))
  (segment (start 172.58772 94.806679) (end 172.58772 94.293578) (width 0.18) (layer "F.Cu") (net 15))
  (segment (start 182.873097 90.673097) (end 183.023097 90.673097) (width 0.18) (layer "F.Cu") (net 15))
  (segment (start 183.623097 91.123097) (end 188.414501 91.123097) (width 0.18) (layer "F.Cu") (net 15))
  (segment (start 173.664512 93.235) (end 179.446298 93.235) (width 0.18) (layer "F.Cu") (net 15))
  (via (at 188.45 90.925) (size 0.5) (drill 0.15) (layers "F.Cu" "B.Cu") (net 15))
  (arc (start 183.023097 90.673097) (mid 183.182196 90.738998) (end 183.248097 90.898097) (width 0.18) (layer "F.Cu") (net 15))
  (arc (start 183.248097 90.898097) (mid 183.313998 91.057196) (end 183.473097 91.123097) (width 0.18) (layer "F.Cu") (net 15))
  (arc (start 182.423097 91.123097) (mid 182.582196 91.057196) (end 182.648097 90.898097) (width 0.18) (layer "F.Cu") (net 15))
  (arc (start 182.648097 90.898097) (mid 182.713998 90.738998) (end 182.873097 90.673097) (width 0.18) (layer "F.Cu") (net 15))
  (segment (start 189.665628 75.971851) (end 189.665629 75.971851) (width 0.18) (layer "B.Cu") (net 15))
  (segment (start 189.622623 75.547587) (end 189.622624 75.547586) (width 0.18) (layer "B.Cu") (net 15))
  (segment (start 189.023298 74.567) (end 187.999 74.567) (width 0.18) (layer "B.Cu") (net 15))
  (segment (start 189.622624 75.547586) (end 189.622623 75.547584) (width 0.18) (layer "B.Cu") (net 15))
  (segment (start 188.61 89.971298) (end 190.691 87.890298) (width 0.18) (layer "B.Cu") (net 15))
  (segment (start 189.665629 75.971851) (end 189.622624 75.928846) (width 0.18) (layer "B.Cu") (net 15))
  (segment (start 190.04689 75.97185) (end 190.046889 75.971851) (width 0.18) (layer "B.Cu") (net 15))
  (segment (start 190.691 76.234702) (end 190.428149 75.971851) (width 0.18) (layer "B.Cu") (net 15))
  (segment (start 190.691 87.890298) (end 190.691 76.234702) (width 0.18) (layer "B.Cu") (net 15))
  (segment (start 188.45 90.925) (end 188.61 90.765) (width 0.18) (layer "B.Cu") (net 15))
  (segment (start 190.046889 75.971851) (end 190.046887 75.97185) (width 0.18) (layer "B.Cu") (net 15))
  (segment (start 189.622624 75.166325) (end 189.622624 75.166326) (width 0.18) (layer "B.Cu") (net 15))
  (segment (start 188.61 90.765) (end 188.61 89.971298) (width 0.18) (layer "B.Cu") (net 15))
  (segment (start 189.622624 75.166326) (end 189.023298 74.567) (width 0.18) (layer "B.Cu") (net 15))
  (arc (start 190.428149 75.971851) (mid 190.237519 75.892888) (end 190.04689 75.97185) (width 0.18) (layer "B.Cu") (net 15))
  (arc (start 189.622623 75.547584) (mid 189.701586 75.356956) (end 189.622624 75.166325) (width 0.18) (layer "B.Cu") (net 15))
  (arc (start 190.046887 75.97185) (mid 189.856259 76.050813) (end 189.665628 75.971851) (width 0.18) (layer "B.Cu") (net 15))
  (arc (start 189.622624 75.928846) (mid 189.543661 75.738216) (end 189.622623 75.547587) (width 0.18) (layer "B.Cu") (net 15))
  (segment (start 174.196298 94.21) (end 184.396298 94.21) (width 0.18) (layer "F.Cu") (net 16))
  (segment (start 173.78772 94.618578) (end 174.196298 94.21) (width 0.18) (layer "F.Cu") (net 16))
  (segment (start 173.78772 94.806679) (end 173.78772 94.618578) (width 0.18) (layer "F.Cu") (net 16))
  (segment (start 185.91 92.696298) (end 185.91 92.5645) (width 0.18) (layer "F.Cu") (net 16))
  (segment (start 184.396298 94.21) (end 185.91 92.696298) (width 0.18) (layer "F.Cu") (net 16))
  (segment (start 173.77772 94.816679) (end 173.78772 94.806679) (width 0.18) (layer "F.Cu") (net 16))
  (segment (start 173.77772 95.34168) (end 173.77772 94.816679) (width 0.18) (layer "F.Cu") (net 16))
  (segment (start 185.91 92.5645) (end 185.75 92.4045) (width 0.18) (layer "F.Cu") (net 16))
  (via (at 185.75 92.4045) (size 0.5) (drill 0.15) (layers "F.Cu" "B.Cu") (net 16))
  (segment (start 189.4078 87.823498) (end 189.4078 77.042309) (width 0.18) (layer "B.Cu") (net 16))
  (segment (start 187.078149 89.748173) (end 187.07815 89.748171) (width 0.18) (layer "B.Cu") (net 16))
  (segment (start 185.91 91.321298) (end 187.078149 90.153149) (width 0.18) (layer "B.Cu") (net 16))
  (segment (start 185.75 92.4045) (end 185.91 92.2445) (width 0.18) (layer "B.Cu") (net 16))
  (segment (start 187.907391 89.323909) (end 187.907392 89.323908) (width 0.18) (layer "B.Cu") (net 16))
  (segment (start 187.999 76.067) (end 187.939 76.127) (width 0.18) (layer "B.Cu") (net 16))
  (segment (start 187.939 76.127) (end 187.314 76.127) (width 0.18) (layer "B.Cu") (net 16))
  (segment (start 188.432491 76.067) (end 187.999 76.067) (width 0.18) (layer "B.Cu") (net 16))
  (segment (start 187.502415 89.323908) (end 187.502414 89.323908) (width 0.18) (layer "B.Cu") (net 16))
  (segment (start 187.907392 89.323908) (end 189.4078 87.823498) (width 0.18) (layer "B.Cu") (net 16))
  (segment (start 187.078149 89.343195) (end 187.097438 89.323907) (width 0.18) (layer "B.Cu") (net 16))
  (segment (start 187.078151 89.343194) (end 187.078149 89.343195) (width 0.18) (layer "B.Cu") (net 16))
  (segment (start 189.4078 77.042309) (end 188.432491 76.067) (width 0.18) (layer "B.Cu") (net 16))
  (segment (start 185.91 92.2445) (end 185.91 91.321298) (width 0.18) (layer "B.Cu") (net 16))
  (arc (start 187.07815 89.748171) (mid 186.994277 89.545682) (end 187.078151 89.343194) (width 0.18) (layer "B.Cu") (net 16))
  (arc (start 187.097438 89.323907) (mid 187.299927 89.240034) (end 187.502415 89.323908) (width 0.18) (layer "B.Cu") (net 16))
  (arc (start 187.078149 90.153149) (mid 187.162023 89.95066) (end 187.078149 89.748173) (width 0.18) (layer "B.Cu") (net 16))
  (arc (start 187.502414 89.323908) (mid 187.704902 89.407782) (end 187.907391 89.323909) (width 0.18) (layer "B.Cu") (net 16))
  (segment (start 189.15 90.925) (end 188.571903 91.503097) (width 0.18) (layer "F.Cu") (net 17))
  (segment (start 179.603702 93.615) (end 173.821916 93.615) (width 0.18) (layer "F.Cu") (net 17))
  (segment (start 172.96772 94.806679) (end 172.96772 94.450982) (width 0.18) (layer "F.Cu") (net 17))
  (segment (start 172.97772 94.816679) (end 172.96772 94.806679) (width 0.18) (layer "F.Cu") (net 17))
  (segment (start 181.715605 91.503097) (end 179.603702 93.615) (width 0.18) (layer "F.Cu") (net 17))
  (segment (start 173.821916 93.615) (end 172.980958 94.455958) (width 0.18) (layer "F.Cu") (net 17))
  (segment (start 188.571903 91.503097) (end 181.715605 91.503097) (width 0.18) (layer "F.Cu") (net 17))
  (segment (start 172.97772 95.34168) (end 172.97772 94.816679) (width 0.18) (layer "F.Cu") (net 17))
  (via (at 189.15 90.925) (size 0.5) (drill 0.15) (layers "F.Cu" "B.Cu") (net 17))
  (segment (start 191.071 76.077298) (end 191.071 88.047702) (width 0.18) (layer "B.Cu") (net 17))
  (segment (start 188.99 90.765) (end 189.15 90.925) (width 0.18) (layer "B.Cu") (net 17))
  (segment (start 188.99 90.128702) (end 188.99 90.765) (width 0.18) (layer "B.Cu") (net 17))
  (segment (start 187.999 74.187) (end 189.180702 74.187) (width 0.18) (layer "B.Cu") (net 17))
  (segment (start 191.071 88.047702) (end 188.99 90.128702) (width 0.18) (layer "B.Cu") (net 17))
  (segment (start 189.180702 74.187) (end 191.071 76.077298) (width 0.18) (layer "B.Cu") (net 17))
  (segment (start 184.553702 94.59) (end 174.353702 94.59) (width 0.18) (layer "F.Cu") (net 18))
  (segment (start 174.353702 94.59) (end 174.16772 94.775982) (width 0.18) (layer "F.Cu") (net 18))
  (segment (start 186.45 92.4045) (end 186.29 92.5645) (width 0.18) (layer "F.Cu") (net 18))
  (segment (start 174.16772 94.806679) (end 174.17772 94.816679) (width 0.18) (layer "F.Cu") (net 18))
  (segment (start 174.17772 94.816679) (end 174.17772 95.34168) (width 0.18) (layer "F.Cu") (net 18))
  (segment (start 186.29 92.853702) (end 184.553702 94.59) (width 0.18) (layer "F.Cu") (net 18))
  (segment (start 174.16772 94.775982) (end 174.16772 94.806679) (width 0.18) (layer "F.Cu") (net 18))
  (segment (start 186.29 92.5645) (end 186.29 92.853702) (width 0.18) (layer "F.Cu") (net 18))
  (via (at 186.45 92.4045) (size 0.5) (drill 0.15) (layers "F.Cu" "B.Cu") (net 18))
  (segment (start 188.589893 75.687) (end 189.7888 76.885907) (width 0.18) (layer "B.Cu") (net 18))
  (segment (start 186.29 91.478702) (end 186.29 92.2445) (width 0.18) (layer "B.Cu") (net 18))
  (segment (start 187.939 75.627) (end 187.999 75.687) (width 0.18) (layer "B.Cu") (net 18))
  (segment (start 187.999 75.687) (end 188.589893 75.687) (width 0.18) (layer "B.Cu") (net 18))
  (segment (start 187.314 75.627) (end 187.939 75.627) (width 0.18) (layer "B.Cu") (net 18))
  (segment (start 189.7888 76.885907) (end 189.7888 87.979902) (width 0.18) (layer "B.Cu") (net 18))
  (segment (start 186.29 92.2445) (end 186.45 92.4045) (width 0.18) (layer "B.Cu") (net 18))
  (segment (start 189.7888 87.979902) (end 186.29 91.478702) (width 0.18) (layer "B.Cu") (net 18))
  (segment (start 100.881 64.025315) (end 99.228685 62.373) (width 0.4) (layer "F.Cu") (net 20))
  (segment (start 99.228685 62.373) (end 97.887 62.373) (width 0.4) (layer "F.Cu") (net 20))
  (segment (start 100.881 64.025315) (end 100.881 64.591) (width 0.4) (layer "F.Cu") (net 20))
  (via (at 100.881 64.591) (size 0.5) (drill 0.15) (layers "F.Cu" "B.Cu") (net 20))
  (segment (start 100.119 64.591) (end 99.693 64.165) (width 0.4) (layer "B.Cu") (net 20))
  (segment (start 99.693 64.165) (end 99.693 62.884) (width 0.4) (layer "B.Cu") (net 20))
  (segment (start 100.881 64.591) (end 100.119 64.591) (width 0.4) (layer "B.Cu") (net 20))
  (segment (start 101.135 64.591) (end 102.174 64.591) (width 0.4) (layer "B.Cu") (net 20))
  (segment (start 102.174 64.591) (end 102.301 64.464) (width 0.4) (layer "B.Cu") (net 20))
  (segment (start 101.135 64.591) (end 100.881 64.591) (width 0.4) (layer "B.Cu") (net 20))
  (segment (start 98.15 90.85) (end 98.15 92.3) (width 0.254) (layer "F.Cu") (net 21))
  (segment (start 166.74956 72.69872) (end 166.74956 72.24872) (width 0.2) (layer "F.Cu") (net 23))
  (segment (start 163.64956 71.79872) (end 162.77492 71.79872) (width 0.2) (layer "F.Cu") (net 23))
  (segment (start 168.1588 72.9202) (end 167.7802 73.2988) (width 0.2) (layer "F.Cu") (net 23))
  (segment (start 167.46672 72.24872) (end 166.74956 72.24872) (width 0.2) (layer "F.Cu") (net 23))
  (segment (start 168.1588 72.4606) (end 167.6786 72.4606) (width 0.2) (layer "F.Cu") (net 23))
  (segment (start 167.6786 72.4606) (end 167.46672 72.24872) (width 0.2) (layer "F.Cu") (net 23))
  (segment (start 168.1588 72.4606) (end 168.1588 72.9202) (width 0.2) (layer "F.Cu") (net 23))
  (segment (start 162.77492 71.79872) (end 162.5224 71.5462) (width 0.2) (layer "F.Cu") (net 23))
  (via (at 167.7802 73.2988) (size 0.5) (drill 0.15) (layers "F.Cu" "B.Cu") (net 23))
  (via (at 162.5224 71.5462) (size 0.5) (drill 0.15) (layers "F.Cu" "B.Cu") (net 23))
  (segment (start 162.7764 71.8002) (end 165.8498 71.8002) (width 0.2) (layer "B.Cu") (net 23))
  (segment (start 162.5224 71.5462) (end 162.7764 71.8002) (width 0.2) (layer "B.Cu") (net 23))
  (segment (start 167.7802 73.2988) (end 167.3484 73.2988) (width 0.2) (layer "B.Cu") (net 23))
  (segment (start 167.3484 73.2988) (end 165.8498 71.8002) (width 0.2) (layer "B.Cu") (net 23))
  (segment (start 161.75 78.3) (end 163.6 78.3) (width 0.18) (layer "F.Cu") (net 24))
  (segment (start 172.214981 86.185019) (end 172.858962 86.829) (width 0.18) (layer "F.Cu") (net 24))
  (segment (start 172.858962 86.829) (end 174.349 86.829) (width 0.18) (layer "F.Cu") (net 24))
  (segment (start 161.7 78.35) (end 161.75 78.3) (width 0.18) (layer "F.Cu") (net 24))
  (via (at 161.7 78.35) (size 0.5) (drill 0.15) (layers "F.Cu" "B.Cu") (net 24))
  (via (at 172.214981 86.185019) (size 0.5) (drill 0.15) (layers "F.Cu" "B.Cu") (net 24))
  (segment (start 172.054981 85.836279) (end 172.054981 86.025019) (width 0.18) (layer "B.Cu") (net 24))
  (segment (start 161.828702 79.41) (end 165.628702 79.41) (width 0.18) (layer "B.Cu") (net 24))
  (segment (start 172.054981 86.025019) (end 172.214981 86.185019) (width 0.18) (layer "B.Cu") (net 24))
  (segment (start 161.54 79.121298) (end 161.828702 79.41) (width 0.18) (layer "B.Cu") (net 24))
  (segment (start 165.628702 79.41) (end 172.054981 85.836279) (width 0.18) (layer "B.Cu") (net 24))
  (segment (start 161.7 78.35) (end 161.54 78.51) (width 0.18) (layer "B.Cu") (net 24))
  (segment (start 161.54 78.51) (end 161.54 79.121298) (width 0.18) (layer "B.Cu") (net 24))
  (segment (start 171.514981 86.185019) (end 171.371 86.329) (width 0.18) (layer "F.Cu") (net 25))
  (segment (start 171.371 86.329) (end 169.949 86.329) (width 0.18) (layer "F.Cu") (net 25))
  (segment (start 160.45 77.8) (end 159.2 77.8) (width 0.18) (layer "F.Cu") (net 25))
  (segment (start 161 78.35) (end 160.45 77.8) (width 0.18) (layer "F.Cu") (net 25))
  (via (at 171.514981 86.185019) (size 0.5) (drill 0.15) (layers "F.Cu" "B.Cu") (net 25))
  (via (at 161 78.35) (size 0.5) (drill 0.15) (layers "F.Cu" "B.Cu") (net 25))
  (segment (start 163.2352 79.79) (end 165.471298 79.79) (width 0.18) (layer "B.Cu") (net 25))
  (segment (start 161.16 78.51) (end 161.16 79.278702) (width 0.18) (layer "B.Cu") (net 25))
  (segment (start 171.674981 86.025019) (end 171.514981 86.185019) (width 0.18) (layer "B.Cu") (net 25))
  (segment (start 162.330971 80.085771) (end 162.330971 80.085772) (width 0.18) (layer "B.Cu") (net 25))
  (segment (start 161 78.35) (end 161.16 78.51) (width 0.18) (layer "B.Cu") (net 25))
  (segment (start 162.930971 80.085772) (end 162.930971 80.085771) (width 0.18) (layer "B.Cu") (net 25))
  (segment (start 161.16 79.278702) (end 161.671298 79.79) (width 0.18) (layer "B.Cu") (net 25))
  (segment (start 161.671298 79.79) (end 162.0352 79.79) (width 0.18) (layer "B.Cu") (net 25))
  (segment (start 163.226742 79.79) (end 163.2352 79.79) (width 0.18) (layer "B.Cu") (net 25))
  (segment (start 171.674981 85.993683) (end 171.674981 86.025019) (width 0.18) (layer "B.Cu") (net 25))
  (segment (start 162.626742 80.381543) (end 162.6352 80.381543) (width 0.18) (layer "B.Cu") (net 25))
  (segment (start 165.471298 79.79) (end 171.674981 85.993683) (width 0.18) (layer "B.Cu") (net 25))
  (arc (start 162.0352 79.79) (mid 162.244342 79.876629) (end 162.330971 80.085771) (width 0.18) (layer "B.Cu") (net 25))
  (arc (start 162.330971 80.085772) (mid 162.4176 80.294914) (end 162.626742 80.381543) (width 0.18) (layer "B.Cu") (net 25))
  (arc (start 162.6352 80.381543) (mid 162.844342 80.294914) (end 162.930971 80.085772) (width 0.18) (layer "B.Cu") (net 25))
  (arc (start 162.930971 80.085771) (mid 163.0176 79.876629) (end 163.226742 79.79) (width 0.18) (layer "B.Cu") (net 25))
  (segment (start 77.169583 80.500583) (end 76.1 79.431) (width 0.15) (layer "F.Cu") (net 26))
  (segment (start 103.83 75.93) (end 90.35 75.93) (width 0.15) (layer "F.Cu") (net 26))
  (segment (start 83.85 82.43) (end 79.5 82.43) (width 0.15) (layer "F.Cu") (net 26))
  (segment (start 104.59452 75.16548) (end 103.83 75.93) (width 0.15) (layer "F.Cu") (net 26))
  (segment (start 78.700583 80.500583) (end 77.169583 80.500583) (width 0.15) (layer "F.Cu") (net 26))
  (segment (start 90.35 75.93) (end 83.85 82.43) (width 0.15) (layer "F.Cu") (net 26))
  (segment (start 119.09 76.77) (end 117.48548 75.16548) (width 0.15) (layer "F.Cu") (net 26))
  (segment (start 79.5 82.43) (end 79.37 82.3) (width 0.15) (layer "F.Cu") (net 26))
  (segment (start 177.4 66.9) (end 175.73 68.57) (width 0.15) (layer "F.Cu") (net 26))
  (segment (start 175.73 68.57) (end 150.93 68.57) (width 0.15) (layer "F.Cu") (net 26))
  (segment (start 79.37 82.3) (end 79.37 81.17) (width 0.15) (layer "F.Cu") (net 26))
  (segment (start 79.37 81.17) (end 78.700583 80.500583) (width 0.15) (layer "F.Cu") (net 26))
  (segment (start 182.723 83.877) (end 183.08 83.52) (width 0.2) (layer "F.Cu") (net 26))
  (segment (start 183.08 83.52) (end 184.38 83.52) (width 0.2) (layer "F.Cu") (net 26))
  (segment (start 150.93 68.57) (end 150.67 68.83) (width 0.15) (layer "F.Cu") (net 26))
  (segment (start 180.1 66.9) (end 177.4 66.9) (width 0.15) (layer "F.Cu") (net 26))
  (segment (start 117.48548 75.16548) (end 104.59452 75.16548) (width 0.15) (layer "F.Cu") (net 26))
  (via (at 182.723 83.877) (size 0.5) (drill 0.15) (layers "F.Cu" "B.Cu") (net 26))
  (via (at 184.38 83.52) (size 0.5) (drill 0.15) (layers "F.Cu" "B.Cu") (net 26))
  (via (at 180.1 66.9) (size 0.5) (drill 0.15) (layers "F.Cu" "B.Cu") (net 26))
  (via (at 119.09 76.77) (size 0.5) (drill 0.15) (layers "F.Cu" "B.Cu") (net 26))
  (via (at 150.67 68.83) (size 0.5) (drill 0.15) (layers "F.Cu" "B.Cu") (net 26))
  (segment (start 121.69 79.37) (end 144.2 79.37) (width 0.15) (layer "B.Cu") (net 26))
  (segment (start 182.723 83.877) (end 179.764 83.877) (width 0.2) (layer "B.Cu") (net 26))
  (segment (start 180.39 66.9) (end 180.1 66.9) (width 0.2) (layer "B.Cu") (net 26))
  (segment (start 184.5035 83.3965) (end 184.5035 71.0135) (width 0.2) (layer "B.Cu") (net 26))
  (segment (start 119.09 76.77) (end 121.69 79.37) (width 0.15) (layer "B.Cu") (net 26))
  (segment (start 184.38 83.52) (end 184.5035 83.3965) (width 0.2) (layer "B.Cu") (net 26))
  (segment (start 150.175 73.395) (end 150.175 69.325) (width 0.15) (layer "B.Cu") (net 26))
  (segment (start 184.5035 71.0135) (end 180.39 66.9) (width 0.2) (layer "B.Cu") (net 26))
  (segment (start 144.2 79.37) (end 150.175 73.395) (width 0.15) (layer "B.Cu") (net 26))
  (segment (start 150.175 69.325) (end 150.67 68.83) (width 0.15) (layer "B.Cu") (net 26))
  (segment (start 81.745 85.781) (end 82.171 85.781) (width 0.2) (layer "F.Cu") (net 27))
  (segment (start 165.75084 69) (end 167.94144 71.1906) (width 0.2) (layer "F.Cu") (net 27))
  (segment (start 168.1564 70.1746) (end 168.1564 71.1882) (width 0.254) (layer "F.Cu") (net 27))
  (segment (start 151.171045 69) (end 165.75084 69) (width 0.2) (layer "F.Cu") (net 27))
  (segment (start 142.583392 68.177892) (end 149.297892 68.177892) (width 0.2) (layer "F.Cu") (net 27))
  (segment (start 82.4 86.608) (end 82.59 86.798) (width 0.2) (layer "F.Cu") (net 27))
  (segment (start 79.61372 86.07404) (end 80.89696 86.07404) (width 0.4) (layer "F.Cu") (net 27))
  (segment (start 82.4 84.35) (end 90.52 76.23) (width 0.2) (layer "F.Cu") (net 27))
  (segment (start 102.311627 76.23) (end 103.758628 77.677001) (width 0.2) (layer "F.Cu") (net 27))
  (segment (start 80.89696 86.07404) (end 81.215 85.756) (width 0.4) (layer "F.Cu") (net 27))
  (segment (start 82.4 85.89) (end 82.291 85.781) (width 0.2) (layer "F.Cu") (net 27))
  (segment (start 81.215 85.756) (end 81.72 85.756) (width 0.4) (layer "F.Cu") (net 27))
  (segment (start 82.171 85.781) (end 82.291 85.781) (width 0.2) (layer "F.Cu") (net 27))
  (segment (start 82.171 85.781) (end 82.299 85.781) (width 0.2) (layer "F.Cu") (net 27))
  (segment (start 142.5 68.0945) (end 142.583392 68.177892) (width 0.2) (layer "F.Cu") (net 27))
  (segment (start 82.4 85.68) (end 82.4 84.35) (width 0.2) (layer "F.Cu") (net 27))
  (segment (start 149.297892 68.177892) (end 150.620361 69.500361) (width 0.2) (layer "F.Cu") (net 27))
  (segment (start 150.670684 69.500361) (end 151.171045 69) (width 0.2) (layer "F.Cu") (net 27))
  (segment (start 121.53 59.35) (end 122.35 58.53) (width 0.2) (layer "F.Cu") (net 27))
  (segment (start 82.299 85.781) (end 82.4 85.68) (width 0.2) (layer "F.Cu") (net 27))
  (segment (start 90.52 76.23) (end 102.311627 76.23) (width 0.2) (layer "F.Cu") (net 27))
  (segment (start 166.74956 71.79872) (end 167.55068 71.79872) (width 0.254) (layer "F.Cu") (net 27))
  (segment (start 167.94144 71.1906) (end 168.1588 71.1906) (width 0.2) (layer "F.Cu") (net 27))
  (segment (start 117.442999 77.677001) (end 118.329477 76.790523) (width 0.2) (layer "F.Cu") (net 27))
  (segment (start 103.758628 77.677001) (end 117.442999 77.677001) (width 0.2) (layer "F.Cu") (net 27))
  (segment (start 82.4 85.89) (end 82.4 85.68) (width 0.2) (layer "F.Cu") (net 27))
  (segment (start 82.4 85.89) (end 82.4 86.608) (width 0.2) (layer "F.Cu") (net 27))
  (segment (start 167.55068 71.79872) (end 168.1588 71.1906) (width 0.254) (layer "F.Cu") (net 27))
  (segment (start 150.620361 69.500361) (end 150.670684 69.500361) (width 0.2) (layer "F.Cu") (net 27))
  (via (at 118.329477 76.790523) (size 0.5) (drill 0.15) (layers "F.Cu" "B.Cu") (net 27))
  (via (at 150.670684 69.500361) (size 0.5) (drill 0.15) (layers "F.Cu" "B.Cu") (net 27))
  (via (at 142.5 68.0945) (size 0.5) (drill 0.15) (layers "F.Cu" "B.Cu") (net 27))
  (via (at 121.53 59.35) (size 0.5) (drill 0.15) (layers "F.Cu" "B.Cu") (net 27))
  (segment (start 150.58 73.57) (end 144.43 79.72) (width 0.2) (layer "B.Cu") (net 27))
  (segment (start 142.5 68.0945) (end 142.5 65.43) (width 0.2) (layer "B.Cu") (net 27))
  (segment (start 142.5 65.43) (end 135.5 58.43) (width 0.2) (layer "B.Cu") (net 27))
  (segment (start 121.258954 79.72) (end 118.329477 76.790523) (width 0.2) (layer "B.Cu") (net 27))
  (segment (start 150.58 69.591045) (end 150.58 73.57) (width 0.2) (layer "B.Cu") (net 27))
  (segment (start 122.45 58.43) (end 121.53 59.35) (width 0.2) (layer "B.Cu") (net 27))
  (segment (start 150.670684 69.500361) (end 150.58 69.591045) (width 0.2) (layer "B.Cu") (net 27))
  (segment (start 144.43 79.72) (end 121.258954 79.72) (width 0.2) (layer "B.Cu") (net 27))
  (segment (start 135.5 58.43) (end 122.45 58.43) (width 0.2) (layer "B.Cu") (net 27))
  (segment (start 162.79 59.83) (end 155.37 59.83) (width 0.18) (layer "F.Cu") (net 28))
  (segment (start 163.77772 58.26168) (end 163.77772 58.84228) (width 0.18) (layer "F.Cu") (net 28))
  (segment (start 95.46 86.04) (end 94.38 84.96) (width 0.18) (layer "F.Cu") (net 28))
  (segment (start 163.77772 58.84228) (end 162.79 59.83) (width 0.18) (layer "F.Cu") (net 28))
  (segment (start 102.817261 83.256756) (end 102.817261 84.352739) (width 0.18) (layer "F.Cu") (net 28))
  (segment (start 102.817261 84.352739) (end 101.13 86.04) (width 0.18) (layer "F.Cu") (net 28))
  (segment (start 101.13 86.04) (end 95.46 86.04) (width 0.18) (layer "F.Cu") (net 28))
  (segment (start 154.6225 60.5775) (end 154.6225 62.707) (width 0.18) (layer "F.Cu") (net 28))
  (segment (start 155.37 59.83) (end 154.6225 60.5775) (width 0.18) (layer "F.Cu") (net 28))
  (via (at 94.38 84.96) (size 0.5) (drill 0.15) (layers "F.Cu" "B.Cu") (net 28))
  (via (at 102.817261 83.256756) (size 0.5) (drill 0.15) (layers "F.Cu" "B.Cu") (net 28))
  (via (at 154.6225 62.707) (size 0.5) (drill 0.15) (layers "F.Cu" "B.Cu") (net 28))
  (segment (start 76.418042 89.629446) (end 85.485094 89.629446) (width 0.18) (layer "B.Cu") (net 28))
  (segment (start 102.817261 83.256756) (end 102.817261 82.567689) (width 0.16) (layer "B.Cu") (net 28))
  (segment (start 103.48495 81.9) (end 104.36 81.9) (width 0.16) (layer "B.Cu") (net 28))
  (segment (start 114.695 71.44195) (end 115.28695 70.85) (width 0.16) (layer "B.Cu") (net 28))
  (segment (start 149.175 65.825) (end 150.998695 65.825) (width 0.16) (layer "B.Cu") (net 28))
  (segment (start 154.116695 62.707) (end 154.6225 62.707) (width 0.18) (layer "B.Cu") (net 28))
  (segment (start 150.998695 65.825) (end 154.116695 62.707) (width 0.16) (layer "B.Cu") (net 28))
  (segment (start 85.485094 89.629446) (end 90.17454 84.94) (width 0.18) (layer "B.Cu") (net 28))
  (segment (start 94.38 84.96) (end 93.02 84.96) (width 0.18) (layer "B.Cu") (net 28))
  (segment (start 93 84.94) (end 91.9885 84.94) (width 0.18) (layer "B.Cu") (net 28))
  (segment (start 94.38 84.96) (end 94.38 85.882) (width 0.18) (layer "B.Cu") (net 28))
  (segment (start 104.36 81.9) (end 114.695 71.565) (width 0.16) (layer "B.Cu") (net 28))
  (segment (start 126.05 78.09) (end 136.91 78.09) (width 0.16) (layer "B.Cu") (net 28))
  (segment (start 90.17454 84.94) (end 91.66 84.94) (width 0.18) (layer "B.Cu") (net 28))
  (segment (start 114.695 71.565) (end 114.695 71.44195) (width 0.16) (layer "B.Cu") (net 28))
  (segment (start 102.817261 82.567689) (end 103.48495 81.9) (width 0.16) (layer "B.Cu") (net 28))
  (segment (start 136.91 78.09) (end 149.175 65.825) (width 0.16) (layer "B.Cu") (net 28))
  (segment (start 118.81 70.85) (end 126.05 78.09) (width 0.16) (layer "B.Cu") (net 28))
  (segment (start 115.28695 70.85) (end 118.81 70.85) (width 0.16) (layer "B.Cu") (net 28))
  (segment (start 102.35 82.66) (end 102.35 84.15) (width 0.18) (layer "F.Cu") (net 29))
  (segment (start 164.57772 58.644502) (end 164.57772 58.26168) (width 0.18) (layer "F.Cu") (net 29))
  (segment (start 102.35 84.15) (end 100.85 85.65) (width 0.18) (layer "F.Cu") (net 29))
  (segment (start 163.55 59.672222) (end 164.57772 58.644502) (width 0.18) (layer "F.Cu") (net 29))
  (segment (start 96.06 85.65) (end 95.38 84.97) (width 0.18) (layer "F.Cu") (net 29))
  (segment (start 100.85 85.65) (end 96.06 85.65) (width 0.18) (layer "F.Cu") (net 29))
  (segment (start 163.55 60.31318) (end 163.55 59.672222) (width 0.18) (layer "F.Cu") (net 29))
  (via (at 163.55 60.31318) (size 0.5) (drill 0.15) (layers "F.Cu" "B.Cu") (net 29))
  (via (at 95.38 84.97) (size 0.5) (drill 0.15) (layers "F.Cu" "B.Cu") (net 29))
  (via (at 102.35 82.66) (size 0.5) (drill 0.15) (layers "F.Cu" "B.Cu") (net 29))
  (segment (start 136.78 77.72) (end 126.18 77.72) (width 0.16) (layer "B.Cu") (net 29))
  (segment (start 94.85 84.44) (end 93 84.44) (width 0.18) (layer "B.Cu") (net 29))
  (segment (start 154.499431 61.9) (end 150.874431 65.525) (width 0.16) (layer "B.Cu") (net 29))
  (segment (start 126.18 77.72) (end 118.99 70.53) (width 0.16) (layer "B.Cu") (net 29))
  (segment (start 150.874431 65.525) (end 148.975 65.525) (width 0.16) (layer "B.Cu") (net 29))
  (segment (start 115.18 70.53) (end 104.26 81.45) (width 0.16) (layer "B.Cu") (net 29))
  (segment (start 103.18 81.45) (end 102.35 82.28) (width 0.16) (layer "B.Cu") (net 29))
  (segment (start 76.981 88.506) (end 77.53978 89.06478) (width 0.18) (layer "B.Cu") (net 29))
  (segment (start 93 84.44) (end 91.66 84.44) (width 0.18) (layer "B.Cu") (net 29))
  (segment (start 77.53978 89.06478) (end 85.35126 89.06478) (width 0.18) (layer "B.Cu") (net 29))
  (segment (start 102.35 82.28) (end 102.35 82.66) (width 0.16) (layer "B.Cu") (net 29))
  (segment (start 89.97604 84.44) (end 91.66 84.44) (width 0.18) (layer "B.Cu") (net 29))
  (segment (start 162.828013 61.035167) (end 163.55 60.31318) (width 0.18) (layer "B.Cu") (net 29))
  (segment (start 104.26 81.45) (end 103.18 81.45) (width 0.16) (layer "B.Cu") (net 29))
  (segment (start 95.38 84.97) (end 95.388 84.978) (width 0.18) (layer "B.Cu") (net 29))
  (segment (start 155.26 61.9) (end 156.124833 61.035167) (width 0.18) (layer "B.Cu") (net 29))
  (segment (start 156.124833 61.035167) (end 162.828013 61.035167) (width 0.18) (layer "B.Cu") (net 29))
  (segment (start 118.99 70.53) (end 115.18 70.53) (width 0.16) (layer "B.Cu") (net 29))
  (segment (start 95.388 84.978) (end 95.388 85.89) (width 0.18) (layer "B.Cu") (net 29))
  (segment (start 148.975 65.525) (end 136.78 77.72) (width 0.16) (layer "B.Cu") (net 29))
  (segment (start 155.26 61.9) (end 154.499431 61.9) (width 0.16) (layer "B.Cu") (net 29))
  (segment (start 85.35126 89.06478) (end 89.97604 84.44) (width 0.18) (layer "B.Cu") (net 29))
  (segment (start 95.38 84.97) (end 94.85 84.44) (width 0.18) (layer "B.Cu") (net 29))
  (segment (start 155.602513 60.77768) (end 163.784542 60.77768) (width 0.18) (layer "F.Cu") (net 30))
  (segment (start 165.77772 58.79228) (end 165.77772 58.26168) (width 0.18) (layer "F.Cu") (net 30))
  (segment (start 97.61 85.26) (end 96.375 84.025) (width 0.18) (layer "F.Cu") (net 30))
  (segment (start 164.730084 59.839916) (end 165.77772 58.79228) (width 0.18) (layer "F.Cu") (net 30))
  (segment (start 163.784542 60.77768) (end 164.722306 59.839916) (width 0.18) (layer "F.Cu") (net 30))
  (segment (start 164.722306 59.839916) (end 164.730084 59.839916) (width 0.18) (layer "F.Cu") (net 30))
  (segment (start 101.85 83.96) (end 100.55 85.26) (width 0.18) (layer "F.Cu") (net 30))
  (segment (start 100.55 85.26) (end 97.61 85.26) (width 0.18) (layer "F.Cu") (net 30))
  (segment (start 101.85 83.25) (end 101.85 83.96) (width 0.18) (layer "F.Cu") (net 30))
  (segment (start 155.4 60.575167) (end 155.602513 60.77768) (width 0.18) (layer "F.Cu") (net 30))
  (via (at 101.85 83.25) (size 0.5) (drill 0.15) (layers "F.Cu" "B.Cu") (net 30))
  (via (at 155.4 60.575167) (size 0.5) (drill 0.15) (layers "F.Cu" "B.Cu") (net 30))
  (via (at 96.375 84.025) (size 0.5) (drill 0.15) (layers "F.Cu" "B.Cu") (net 30))
  (segment (start 78.623446 86.329446) (end 76.418042 86.329446) (width 0.18) (layer "B.Cu") (net 30))
  (segment (start 80.85078 88.55678) (end 78.623446 86.329446) (width 0.18) (layer "B.Cu") (net 30))
  (segment (start 102.85 81.06) (end 104.1 81.06) (width 0.16) (layer "B.Cu") (net 30))
  (segment (start 96.404 84.054) (end 96.404 85.89) (width 0.18) (layer "B.Cu") (net 30))
  (segment (start 126.34 77.4) (end 136.6 77.4) (width 0.16) (layer "B.Cu") (net 30))
  (segment (start 136.6 77.4) (end 148.775 65.225) (width 0.16) (layer "B.Cu") (net 30))
  (segment (start 93 83.94) (end 91.66 83.94) (width 0.18) (layer "B.Cu") (net 30))
  (segment (start 101.85 83.25) (end 101.85 82.06) (width 0.16) (layer "B.Cu") (net 30))
  (segment (start 101.85 82.06) (end 102.85 81.06) (width 0.16) (layer "B.Cu") (net 30))
  (segment (start 85.16076 88.55678) (end 80.85078 88.55678) (width 0.18) (layer "B.Cu") (net 30))
  (segment (start 91.66 83.94) (end 89.77754 83.94) (width 0.18) (layer "B.Cu") (net 30))
  (segment (start 96.375 84.025) (end 96.29 83.94) (width 0.18) (layer "B.Cu") (net 30))
  (segment (start 96.375 84.025) (end 96.404 84.054) (width 0.18) (layer "B.Cu") (net 30))
  (segment (start 148.775 65.225) (end 150.750167 65.225) (width 0.16) (layer "B.Cu") (net 30))
  (segment (start 89.77754 83.94) (end 85.16076 88.55678) (width 0.18) (layer "B.Cu") (net 30))
  (segment (start 150.750167 65.225) (end 155.4 60.575167) (width 0.16) (layer "B.Cu") (net 30))
  (segment (start 114.94 70.22) (end 119.16 70.22) (width 0.16) (layer "B.Cu") (net 30))
  (segment (start 119.16 70.22) (end 126.34 77.4) (width 0.16) (layer "B.Cu") (net 30))
  (segment (start 96.29 83.94) (end 93 83.94) (width 0.18) (layer "B.Cu") (net 30))
  (segment (start 104.1 81.06) (end 114.94 70.22) (width 0.16) (layer "B.Cu") (net 30))
  (segment (start 164.973 60.363) (end 164.973 61.33696) (width 0.18) (layer "F.Cu") (net 31))
  (segment (start 100.21 84.86) (end 98.235 84.86) (width 0.18) (layer "F.Cu") (net 31))
  (segment (start 101.294666 82.665334) (end 101.294666 83.775334) (width 0.18) (layer "F.Cu") (net 31))
  (segment (start 101.294666 83.775334) (end 100.21 84.86) (width 0.18) (layer "F.Cu") (net 31))
  (segment (start 164.914916 60.304916) (end 164.973 60.363) (width 0.18) (layer "F.Cu") (net 31))
  (segment (start 98.235 84.86) (end 97.4 84.025) (width 0.18) (layer "F.Cu") (net 31))
  (via (at 164.914916 60.304916) (size 0.5) (drill 0.15) (layers "F.Cu" "B.Cu") (net 31))
  (via (at 101.294666 82.665334) (size 0.5) (drill 0.15) (layers "F.Cu" "B.Cu") (net 31))
  (via (at 97.4 84.025) (size 0.5) (drill 0.15) (layers "F.Cu" "B.Cu") (net 31))
  (segment (start 97.4 84.025) (end 97.42 84.045) (width 0.18) (layer "B.Cu") (net 31))
  (segment (start 77.67 83.44) (end 76.980554 84.129446) (width 0.18) (layer "B.Cu") (net 31))
  (segment (start 91.66 83.44) (end 93 83.44) (width 0.18) (layer "B.Cu") (net 31))
  (segment (start 102.76 80.37) (end 101.294666 81.835334) (width 0.16) (layer "B.Cu") (net 31))
  (segment (start 114.76 69.9) (end 104.29 80.37) (width 0.16) (layer "B.Cu") (net 31))
  (segment (start 97.4 84.025) (end 96.815 83.44) (width 0.18) (layer "B.Cu") (net 31))
  (segment (start 148.575 64.925) (end 136.45096 77.04904) (width 0.16) (layer "B.Cu") (net 31))
  (segment (start 164.914916 60.304916) (end 164.42 59.81) (width 0.16) (layer "B.Cu") (net 31))
  (segment (start 96.815 83.44) (end 93 83.44) (width 0.18) (layer "B.Cu") (net 31))
  (segment (start 126.435454 77.04904) (end 119.286414 69.9) (width 0.16) (layer "B.Cu") (net 31))
  (segment (start 163.28 59.81) (end 163.14 59.95) (width 0.16) (layer "B.Cu") (net 31))
  (segment (start 119.286414 69.9) (end 114.76 69.9) (width 0.16) (layer "B.Cu") (net 31))
  (segment (start 136.45096 77.04904) (end 126.435454 77.04904) (width 0.16) (layer "B.Cu") (net 31))
  (segment (start 163.14 59.95) (end 155.17 59.95) (width 0.16) (layer "B.Cu") (net 31))
  (segment (start 164.42 59.81) (end 163.28 59.81) (width 0.16) (layer "B.Cu") (net 31))
  (segment (start 97.42 84.045) (end 97.42 85.89) (width 0.18) (layer "B.Cu") (net 31))
  (segment (start 91.66 83.44) (end 77.67 83.44) (width 0.18) (layer "B.Cu") (net 31))
  (segment (start 104.29 80.37) (end 102.76 80.37) (width 0.16) (layer "B.Cu") (net 31))
  (segment (start 155.17 59.95) (end 150.195 64.925) (width 0.16) (layer "B.Cu") (net 31))
  (segment (start 101.294666 81.835334) (end 101.294666 82.665334) (width 0.16) (layer "B.Cu") (net 31))
  (segment (start 150.195 64.925) (end 148.575 64.925) (width 0.16) (layer "B.Cu") (net 31))
  (segment (start 164.751548 59.128284) (end 164.973 58.906832) (width 0.18) (layer "F.Cu") (net 32))
  (segment (start 164.751548 59.161548) (end 164.751548 59.128284) (width 0.18) (layer "F.Cu") (net 32))
  (segment (start 100.8 83.25) (end 100.8 83.306039) (width 0.18) (layer "F.Cu") (net 32))
  (segment (start 98.915 84.49) (end 98.45 84.025) (width 0.16) (layer "F.Cu") (net 32))
  (segment (start 100.8 83.306039) (end 99.616039 84.49) (width 0.16) (layer "F.Cu") (net 32))
  (segment (start 164.973 58.906832) (end 164.973 58.2664) (width 0.18) (layer "F.Cu") (net 32))
  (segment (start 99.616039 84.49) (end 98.915 84.49) (width 0.16) (layer "F.Cu") (net 32))
  (via (at 164.751548 59.161548) (size 0.5) (drill 0.15) (layers "F.Cu" "B.Cu") (net 32))
  (via (at 100.8 83.25) (size 0.5) (drill 0.15) (layers "F.Cu" "B.Cu") (net 32))
  (via (at 98.45 84.025) (size 0.5) (drill 0.15) (layers "F.Cu" "B.Cu") (net 32))
  (segment (start 113.56 69.59) (end 119.4 69.59) (width 0.16) (layer "B.Cu") (net 32))
  (segment (start 77.502553 82.44) (end 91.66 82.44) (width 0.18) (layer "B.Cu") (net 32))
  (segment (start 103.6 74.48) (end 108.67 74.48) (width 0.16) (layer "B.Cu") (net 32))
  (segment (start 108.67 74.48) (end 113.56 69.59) (width 0.16) (layer "B.Cu") (net 32))
  (segment (start 76.913107 83.029446) (end 77.502553 82.44) (width 0.18) (layer "B.Cu") (net 32))
  (segment (start 136.31 76.69) (end 148.375 64.625) (width 0.16) (layer "B.Cu") (net 32))
  (segment (start 119.4 69.59) (end 126.5 76.69) (width 0.16) (layer "B.Cu") (net 32))
  (segment (start 100.81 77.99) (end 101.79 77.01) (width 0.16) (layer "B.Cu") (net 32))
  (segment (start 101.79 76.29) (end 103.6 74.48) (width 0.16) (layer "B.Cu") (net 32))
  (segment (start 98.45 84.025) (end 96.865 82.44) (width 0.18) (layer "B.Cu") (net 32))
  (segment (start 100.81 83.24) (end 100.81 77.99) (width 0.16) (layer "B.Cu") (net 32))
  (segment (start 148.375 64.625) (end 149.769314 64.625) (width 0.16) (layer "B.Cu") (net 32))
  (segment (start 100.8 83.25) (end 100.81 83.24) (width 0.18) (layer "B.Cu") (net 32))
  (segment (start 93 82.44) (end 91.66 82.44) (width 0.18) (layer "B.Cu") (net 32))
  (segment (start 164.453096 59.46) (end 164.751548 59.161548) (width 0.18) (layer "B.Cu") (net 32))
  (segment (start 98.45 84.025) (end 98.45 85.876) (width 0.18) (layer "B.Cu") (net 32))
  (segment (start 154.934314 59.46) (end 164.453096 59.46) (width 0.16) (layer "B.Cu") (net 32))
  (segment (start 96.865 82.44) (end 93 82.44) (width 0.18) (layer "B.Cu") (net 32))
  (segment (start 126.5 76.69) (end 136.31 76.69) (width 0.16) (layer "B.Cu") (net 32))
  (segment (start 101.79 77.01) (end 101.79 76.29) (width 0.16) (layer "B.Cu") (net 32))
  (segment (start 149.769314 64.625) (end 154.934314 59.46) (width 0.16) (layer "B.Cu") (net 32))
  (segment (start 159.5 59.4) (end 158.982 58.882) (width 0.18) (layer "F.Cu") (net 33))
  (segment (start 163.37772 58.65228) (end 162.63 59.4) (width 0.18) (layer "F.Cu") (net 33))
  (segment (start 100.3455 82.66) (end 99.425 83.5805) (width 0.18) (layer "F.Cu") (net 33))
  (segment (start 99.425 83.5805) (end 99.425 84.0305) (width 0.18) (layer "F.Cu") (net 33))
  (segment (start 158.982 58.882) (end 156.09 58.882) (width 0.18) (layer "F.Cu") (net 33))
  (segment (start 163.37772 58.26168) (end 163.37772 58.65228) (width 0.18) (layer "F.Cu") (net 33))
  (segment (start 162.63 59.4) (end 159.5 59.4) (width 0.18) (layer "F.Cu") (net 33))
  (via (at 99.425 84.0305) (size 0.5) (drill 0.15) (layers "F.Cu" "B.Cu") (net 33))
  (via (at 100.3455 82.66) (size 0.5) (drill 0.15) (layers "F.Cu" "B.Cu") (net 33))
  (via (at 156.09 58.882) (size 0.5) (drill 0.15) (layers "F.Cu" "B.Cu") (net 33))
  (segment (start 91.66 81.94) (end 93 81.94) (width 0.18) (layer "B.Cu") (net 33))
  (segment (start 100.3455 82.66) (end 100.35 82.6555) (width 0.18) (layer "B.Cu") (net 33))
  (segment (start 126.64 76.35) (end 136.15 76.35) (width 0.16) (layer "B.Cu") (net 33))
  (segment (start 100.35 82.6555) (end 100.35 77.96) (width 0.16) (layer "B.Cu") (net 33))
  (segment (start 119.48 69.19) (end 126.64 76.35) (width 0.16) (layer "B.Cu") (net 33))
  (segment (start 103.569 74.031) (end 108.459 74.031) (width 0.16) (layer "B.Cu") (net 33))
  (segment (start 100.35 77.96) (end 101.415 76.895) (width 0.16) (layer "B.Cu") (net 33))
  (segment (start 99.425 84.025) (end 97.34 81.94) (width 0.18) (layer "B.Cu") (net 33))
  (segment (start 154.85105 58.882) (end 156.09 58.882) (width 0.18) (layer "B.Cu") (net 33))
  (segment (start 149.408051 64.325) (end 154.85105 58.882) (width 0.16) (layer "B.Cu") (net 33))
  (segment (start 101.415 76.895) (end 101.415 76.185) (width 0.16) (layer "B.Cu") (net 33))
  (segment (start 148.175 64.325) (end 149.408051 64.325) (width 0.16) (layer "B.Cu") (net 33))
  (segment (start 97.34 81.94) (end 93 81.94) (width 0.18) (layer "B.Cu") (net 33))
  (segment (start 99.425 84.0305) (end 99.425 85.863) (width 0.18) (layer "B.Cu") (net 33))
  (segment (start 101.415 76.185) (end 103.569 74.031) (width 0.16) (layer "B.Cu") (net 33))
  (segment (start 136.15 76.35) (end 148.175 64.325) (width 0.16) (layer "B.Cu") (net 33))
  (segment (start 91.65 81.93) (end 76.418596 81.93) (width 0.18) (layer "B.Cu") (net 33))
  (segment (start 113.3 69.19) (end 119.48 69.19) (width 0.16) (layer "B.Cu") (net 33))
  (segment (start 108.459 74.031) (end 113.3 69.19) (width 0.16) (layer "B.Cu") (net 33))
  (segment (start 99.425 84.0305) (end 99.425 84.025) (width 0.18) (layer "B.Cu") (net 33))
  (segment (start 103.841209 86.008791) (end 103.289092 86.560908) (width 0.2) (layer "F.Cu") (net 34))
  (segment (start 100.205 89.305) (end 100.517 89.305) (width 0.254) (layer "F.Cu") (net 34))
  (segment (start 96.4 91.4) (end 97.1 90.7) (width 0.254) (layer "F.Cu") (net 34))
  (segment (start 103.841209 83.281821) (end 103.841209 86.008791) (width 0.2) (layer "F.Cu") (net 34))
  (segment (start 94.725 91.4) (end 96.4 91.4) (width 0.254) (layer "F.Cu") (net 34))
  (segment (start 97.1 89.7) (end 98.3 88.5) (width 0.254) (layer "F.Cu") (net 34))
  (segment (start 98.3 88.5) (end 99.4 88.5) (width 0.254) (layer "F.Cu") (net 34))
  (segment (start 97.1 90.7) (end 97.1 89.7) (width 0.254) (layer "F.Cu") (net 34))
  (segment (start 99.4 88.5) (end 100.205 89.305) (width 0.254) (layer "F.Cu") (net 34))
  (segment (start 103.289092 86.560908) (end 103.280908 86.560908) (width 0.2) (layer "F.Cu") (net 34))
  (via (at 103.841209 83.281821) (size 0.5) (drill 0.15) (layers "F.Cu" "B.Cu") (net 34))
  (via (at 103.280908 86.560908) (size 0.5) (drill 0.15) (layers "F.Cu" "B.Cu") (net 34))
  (via (at 100.517 89.305) (size 0.5) (drill 0.15) (layers "F.Cu" "B.Cu") (net 34))
  (segment (start 103.280908 86.560908) (end 103.280908 86.689092) (width 0.2) (layer "B.Cu") (net 34))
  (segment (start 100.517 89.896522) (end 101.491478 90.871) (width 0.2) (layer "B.Cu") (net 34))
  (segment (start 117.09 73.05) (end 114.34 73.05) (width 0.16) (layer "B.Cu") (net 34))
  (segment (start 117.09 73.05) (end 117.09 73.046) (width 0.2) (layer "B.Cu") (net 34))
  (segment (start 100.517 89.305) (end 100.517 89.896522) (width 0.2) (layer "B.Cu") (net 34))
  (segment (start 114.34 73.05) (end 104.108179 83.281821) (width 0.16) (layer "B.Cu") (net 34))
  (segment (start 104.108179 83.281821) (end 103.841209 83.281821) (width 0.16) (layer "B.Cu") (net 34))
  (segment (start 100.665 89.305) (end 100.517 89.305) (width 0.2) (layer "B.Cu") (net 34))
  (segment (start 103.280908 86.689092) (end 100.665 89.305) (width 0.2) (layer "B.Cu") (net 34))
  (segment (start 167.571804 84.172424) (end 167.941325 84.541946) (width 0.15) (layer "F.Cu") (net 36))
  (segment (start 170.39851 82.084757) (end 170.39851 82.084756) (width 0.15) (layer "F.Cu") (net 36))
  (segment (start 164.211347 88.271921) (end 164.211347 88.27192) (width 0.15) (layer "F.Cu") (net 36))
  (segment (start 172.166275 81.006424) (end 172.166275 81.006425) (width 0.15) (layer "F.Cu") (net 36))
  (segment (start 172.166275 81.006425) (end 172.166271 81.006422) (width 0.15) (layer "F.Cu") (net 36))
  (segment (start 166.862988 85.620278) (end 166.493468 85.250757) (width 0.15) (layer "F.Cu") (net 36))
  (segment (start 180.80244 75.237488) (end 180.837488 75.237488) (width 0.15) (layer "F.Cu") (net 36))
  (segment (start 179.20244 75.237488) (end 179.237488 75.237488) (width 0.15) (layer "F.Cu") (net 36))
  (segment (start 165.095227 87.38804) (end 165.095227 87.388039) (width 0.15) (layer "F.Cu") (net 36))
  (segment (start 168.455684 83.288543) (end 168.825205 83.658065) (width 0.15) (layer "F.Cu") (net 36))
  (segment (start 165.979111 87.193588) (end 165.979108 87.193586) (width 0.15) (layer "F.Cu") (net 36))
  (segment (start 180.00244 75.237488) (end 180.037488 75.237488) (width 0.15) (layer "F.Cu") (net 36))
  (segment (start 167.746872 85.425826) (end 167.746872 85.425827) (width 0.15) (layer "F.Cu") (net 36))
  (segment (start 179.819964 75.419965) (end 179.819964 75.419964) (width 0.15) (layer "F.Cu") (net 36))
  (segment (start 170.398514 82.774186) (end 170.39851 82.774183) (width 0.15) (layer "F.Cu") (net 36))
  (segment (start 166.687923 85.056304) (end 167.057444 85.425826) (width 0.15) (layer "F.Cu") (net 36))
  (segment (start 165.804044 85.940184) (end 165.804043 85.940185) (width 0.15) (layer "F.Cu") (net 36))
  (segment (start 168.455685 83.288542) (end 168.455684 83.288543) (width 0.15) (layer "F.Cu") (net 36))
  (segment (start 164.920162 86.824065) (end 165.289683 87.193587) (width 0.15) (layer "F.Cu") (net 36))
  (segment (start 171.107326 80.636902) (end 171.476847 81.006424) (width 0.15) (layer "F.Cu") (net 36))
  (segment (start 163.52772 89.85) (end 163.52772 89.644975) (width 0.15) (layer "F.Cu") (net 36))
  (segment (start 165.095227 87.388039) (end 164.725707 87.018518) (width 0.15) (layer "F.Cu") (net 36))
  (segment (start 171.107327 80.636901) (end 171.107326 80.636902) (width 0.15) (layer "F.Cu") (net 36))
  (segment (start 171.282391 81.200876) (end 170.912871 80.831355) (width 0.15) (layer "F.Cu") (net 36))
  (segment (start 164.920163 86.824064) (end 164.920162 86.824065) (width 0.15) (layer "F.Cu") (net 36))
  (segment (start 170.223446 81.520781) (end 170.223445 81.520782) (width 0.15) (layer "F.Cu") (net 36))
  (segment (start 167.746869 84.736398) (end 167.377349 84.366877) (width 0.15) (layer "F.Cu") (net 36))
  (segment (start 169.339566 82.404662) (end 169.339565 82.404663) (width 0.15) (layer "F.Cu") (net 36))
  (segment (start 165.979111 87.193587) (end 165.979111 87.193588) (width 0.15) (layer "F.Cu") (net 36))
  (segment (start 165.095231 88.077468) (end 165.095231 88.077469) (width 0.15) (layer "F.Cu") (net 36))
  (segment (start 165.979108 86.50416) (end 165.979108 86.504159) (width 0.15) (layer "F.Cu") (net 36))
  (segment (start 180.219964 75.419964) (end 180.219964 75.419965) (width 0.15) (layer "F.Cu") (net 36))
  (segment (start 169.51463 82.968637) (end 169.14511 82.599116) (width 0.15) (layer "F.Cu") (net 36))
  (segment (start 179.60244 75.602441) (end 179.637488 75.602441) (width 0.15) (layer "F.Cu") (net 36))
  (segment (start 178.80244 75.602441) (end 178.837488 75.602441) (width 0.15) (layer "F.Cu") (net 36))
  (segment (start 165.979108 86.504159) (end 165.609588 86.134638) (width 0.15) (layer "F.Cu") (net 36))
  (segment (start 167.571805 84.172423) (end 167.571804 84.172424) (width 0.15) (layer "F.Cu") (net 36))
  (segment (start 164.211347 88.27192) (end 163.841827 87.902399) (width 0.15) (layer "F.Cu") (net 36))
  (segment (start 180.619964 75.419965) (end 180.619964 75.419964) (width 0.15) (layer "F.Cu") (net 36))
  (segment (start 166.862992 86.309707) (end 166.862992 86.309708) (width 0.15) (layer "F.Cu") (net 36))
  (segment (start 177.935208 75.237488) (end 178.437488 75.237488) (width 0.15) (layer "F.Cu") (net 36))
  (segment (start 168.630753 84.541947) (end 168.630749 84.541944) (width 0.15) (layer "F.Cu") (net 36))
  (segment (start 166.687924 85.056303) (end 166.687923 85.056304) (width 0.15) (layer "F.Cu") (net 36))
  (segment (start 168.630749 83.852518) (end 168.630749 83.852517) (width 0.15) (layer "F.Cu") (net 36))
  (segment (start 170.223445 81.520782) (end 170.592966 81.890304) (width 0.15) (layer "F.Cu") (net 36))
  (segment (start 180.837488 75.237488) (end 196.577488 75.237488) (width 0.15) (layer "F.Cu") (net 36))
  (segment (start 169.514633 83.658066) (end 169.51463 83.658064) (width 0.15) (layer "F.Cu") (net 36))
  (segment (start 169.339565 82.404663) (end 169.709086 82.774185) (width 0.15) (layer "F.Cu") (net 36))
  (segment (start 168.630753 84.541946) (end 168.630753 84.541947) (width 0.15) (layer "F.Cu") (net 36))
  (segment (start 178.619964 75.419964) (end 178.619964 75.419965) (width 0.15) (layer "F.Cu") (net 36))
  (segment (start 170.398514 82.774185) (end 170.398514 82.774186) (width 0.15) (layer "F.Cu") (net 36))
  (segment (start 171.282394 81.890304) (end 171.282394 81.890305) (width 0.15) (layer "F.Cu") (net 36))
  (segment (start 166.862992 86.309708) (end 166.862988 86.309705) (width 0.15) (layer "F.Cu") (net 36))
  (segment (start 163.37772 93.591) (end 163.52772 93.441) (width 0.15) (layer "F.Cu") (net 36))
  (segment (start 171.282394 81.890305) (end 171.282391 81.890303) (width 0.15) (layer "F.Cu") (net 36))
  (segment (start 179.419964 75.419964) (end 179.419964 75.419965) (width 0.15) (layer "F.Cu") (net 36))
  (segment (start 165.804043 85.940185) (end 166.173564 86.309707) (width 0.15) (layer "F.Cu") (net 36))
  (segment (start 167.746872 85.425827) (end 167.746869 85.425825) (width 0.15) (layer "F.Cu") (net 36))
  (segment (start 179.019964 75.419965) (end 179.019964 75.419964) (width 0.15) (layer "F.Cu") (net 36))
  (segment (start 163.37772 95.34168) (end 163.37772 93.591) (width 0.15) (layer "F.Cu") (net 36))
  (segment (start 165.095231 88.077469) (end 165.095227 88.077466) (width 0.15) (layer "F.Cu") (net 36))
  (segment (start 167.746869 84.736399) (end 167.746869 84.736398) (width 0.15) (layer "F.Cu") (net 36))
  (segment (start 166.862988 85.620279) (end 166.862988 85.620278) (width 0.15) (layer "F.Cu") (net 36))
  (segment (start 164.036282 87.707946) (end 164.405803 88.077468) (width 0.15) (layer "F.Cu") (net 36))
  (segment (start 164.036283 87.707945) (end 164.036282 87.707946) (width 0.15) (layer "F.Cu") (net 36))
  (segment (start 170.39851 82.084756) (end 170.02899 81.715235) (width 0.15) (layer "F.Cu") (net 36))
  (segment (start 172.166271 81.006422) (end 177.935208 75.237488) (width 0.15) (layer "F.Cu") (net 36))
  (segment (start 169.514633 83.658065) (end 169.514633 83.658066) (width 0.15) (layer "F.Cu") (net 36))
  (segment (start 163.52772 89.644975) (end 164.211347 88.961347) (width 0.15) (layer "F.Cu") (net 36))
  (segment (start 168.630749 83.852517) (end 168.261229 83.482996) (width 0.15) (layer "F.Cu") (net 36))
  (segment (start 169.51463 82.968638) (end 169.51463 82.968637) (width 0.15) (layer "F.Cu") (net 36))
  (segment (start 180.40244 75.602441) (end 180.437488 75.602441) (width 0.15) (layer "F.Cu") (net 36))
  (segment (start 171.282391 81.200877) (end 171.282391 81.200876) (width 0.15) (layer "F.Cu") (net 36))
  (via (at 196.577488 75.237488) (size 0.5) (drill 0.15) (layers "F.Cu" "B.Cu") (net 36))
  (via (at 163.52772 89.85) (size 0.5) (drill 0.15) (layers "F.Cu" "B.Cu") (net 36))
  (via (at 163.52772 93.441) (size 0.5) (drill 0.15) (layers "F.Cu" "B.Cu") (net 36))
  (arc (start 164.725707 86.824064) (mid 164.822934 86.783792) (end 164.920163 86.824064) (width 0.15) (layer "F.Cu") (net 36))
  (arc (start 165.095227 88.077466) (mid 165.238012 87.732753) (end 165.095227 87.38804) (width 0.15) (layer "F.Cu") (net 36))
  (arc (start 166.173564 86.309707) (mid 166.518279 86.452493) (end 166.862992 86.309707) (width 0.15) (layer "F.Cu") (net 36))
  (arc (start 169.51463 83.658064) (mid 169.657415 83.313351) (end 169.51463 82.968638) (width 0.15) (layer "F.Cu") (net 36))
  (arc (start 167.377349 84.172423) (mid 167.474576 84.132151) (end 167.571805 84.172423) (width 0.15) (layer "F.Cu") (net 36))
  (arc (start 170.02899 81.520781) (mid 170.126217 81.480509) (end 170.223446 81.520781) (width 0.15) (layer "F.Cu") (net 36))
  (arc (start 170.912871 80.831355) (mid 170.872598 80.734128) (end 170.912871 80.636901) (width 0.15) (layer "F.Cu") (net 36))
  (arc (start 180.619964 75.419964) (mid 180.67341 75.290934) (end 180.80244 75.237488) (width 0.15) (layer "F.Cu") (net 36))
  (arc (start 169.709086 82.774185) (mid 170.053801 82.916971) (end 170.398514 82.774185) (width 0.15) (layer "F.Cu") (net 36))
  (arc (start 170.39851 82.774183) (mid 170.541295 82.42947) (end 170.39851 82.084757) (width 0.15) (layer "F.Cu") (net 36))
  (arc (start 167.941325 84.541946) (mid 168.28604 84.684732) (end 168.630753 84.541946) (width 0.15) (layer "F.Cu") (net 36))
  (arc (start 180.437488 75.602441) (mid 180.566518 75.548995) (end 180.619964 75.419965) (width 0.15) (layer "F.Cu") (net 36))
  (arc (start 164.725707 87.018518) (mid 164.685434 86.921291) (end 164.725707 86.824064) (width 0.15) (layer "F.Cu") (net 36))
  (arc (start 178.837488 75.602441) (mid 178.966518 75.548995) (end 179.019964 75.419965) (width 0.15) (layer "F.Cu") (net 36))
  (arc (start 168.630749 84.541944) (mid 168.773534 84.197231) (end 168.630749 83.852518) (width 0.15) (layer "F.Cu") (net 36))
  (arc (start 163.841827 87.707945) (mid 163.939054 87.667673) (end 164.036283 87.707945) (width 0.15) (layer "F.Cu") (net 36))
  (arc (start 168.261229 83.482996) (mid 168.220956 83.385769) (end 168.261229 83.288542) (width 0.15) (layer "F.Cu") (net 36))
  (arc (start 166.493468 85.250757) (mid 166.453195 85.15353) (end 166.493468 85.056303) (width 0.15) (layer "F.Cu") (net 36))
  (arc (start 171.282391 81.890303) (mid 171.425176 81.54559) (end 171.282391 81.200877) (width 0.15) (layer "F.Cu") (net 36))
  (arc (start 170.02899 81.715235) (mid 169.988717 81.618008) (end 170.02899 81.520781) (width 0.15) (layer "F.Cu") (net 36))
  (arc (start 179.237488 75.237488) (mid 179.366518 75.290934) (end 179.419964 75.419964) (width 0.15) (layer "F.Cu") (net 36))
  (arc (start 165.609588 86.134638) (mid 165.569315 86.037411) (end 165.609588 85.940184) (width 0.15) (layer "F.Cu") (net 36))
  (arc (start 169.14511 82.599116) (mid 169.104837 82.501889) (end 169.14511 82.404662) (width 0.15) (layer "F.Cu") (net 36))
  (arc (start 179.819964 75.419964) (mid 179.87341 75.290934) (end 180.00244 75.237488) (width 0.15) (layer "F.Cu") (net 36))
  (arc (start 167.746869 85.425825) (mid 167.889654 85.081112) (end 167.746869 84.736399) (width 0.15) (layer "F.Cu") (net 36))
  (arc (start 180.219964 75.419965) (mid 180.27341 75.548995) (end 180.40244 75.602441) (width 0.15) (layer "F.Cu") (net 36))
  (arc (start 165.289683 87.193587) (mid 165.634398 87.336373) (end 165.979111 87.193587) (width 0.15) (layer "F.Cu") (net 36))
  (arc (start 163.841827 87.902399) (mid 163.801554 87.805172) (end 163.841827 87.707945) (width 0.15) (layer "F.Cu") (net 36))
  (arc (start 164.405803 88.077468) (mid 164.750518 88.220254) (end 165.095231 88.077468) (width 0.15) (layer "F.Cu") (net 36))
  (arc (start 170.912871 80.636901) (mid 171.010098 80.596629) (end 171.107327 80.636901) (width 0.15) (layer "F.Cu") (net 36))
  (arc (start 165.979108 87.193586) (mid 166.121893 86.848873) (end 165.979108 86.50416) (width 0.15) (layer "F.Cu") (net 36))
  (arc (start 171.476847 81.006424) (mid 171.821562 81.14921) (end 172.166275 81.006424) (width 0.15) (layer "F.Cu") (net 36))
  (arc (start 178.619964 75.419965) (mid 178.67341 75.548995) (end 178.80244 75.602441) (width 0.15) (layer "F.Cu") (net 36))
  (arc (start 179.019964 75.419964) (mid 179.07341 75.290934) (end 179.20244 75.237488) (width 0.15) (layer "F.Cu") (net 36))
  (arc (start 168.261229 83.288542) (mid 168.358456 83.24827) (end 168.455685 83.288542) (width 0.15) (layer "F.Cu") (net 36))
  (arc (start 169.14511 82.404662) (mid 169.242337 82.36439) (end 169.339566 82.404662) (width 0.15) (layer "F.Cu") (net 36))
  (arc (start 170.592966 81.890304) (mid 170.937681 82.03309) (end 171.282394 81.890304) (width 0.15) (layer "F.Cu") (net 36))
  (arc (start 166.862988 86.309705) (mid 167.005773 85.964992) (end 166.862988 85.620279) (width 0.15) (layer "F.Cu") (net 36))
  (arc (start 179.637488 75.602441) (mid 179.766518 75.548995) (end 179.819964 75.419965) (width 0.15) (layer "F.Cu") (net 36))
  (arc (start 167.377349 84.366877) (mid 167.337076 84.26965) (end 167.377349 84.172423) (width 0.15) (layer "F.Cu") (net 36))
  (arc (start 180.037488 75.237488) (mid 180.166518 75.290934) (end 180.219964 75.419964) (width 0.15) (layer "F.Cu") (net 36))
  (arc (start 178.437488 75.237488) (mid 178.566518 75.290934) (end 178.619964 75.419964) (width 0.15) (layer "F.Cu") (net 36))
  (arc (start 166.493468 85.056303) (mid 166.590695 85.016031) (end 166.687924 85.056303) (width 0.15) (layer "F.Cu") (net 36))
  (arc (start 167.057444 85.425826) (mid 167.402159 85.568612) (end 167.746872 85.425826) (width 0.15) (layer "F.Cu") (net 36))
  (arc (start 164.211347 88.961347) (mid 164.354132 88.616634) (end 164.211347 88.271921) (width 0.15) (layer "F.Cu") (net 36))
  (arc (start 168.825205 83.658065) (mid 169.16992 83.800851) (end 169.514633 83.658065) (width 0.15) (layer "F.Cu") (net 36))
  (arc (start 165.609588 85.940184) (mid 165.706815 85.899912) (end 165.804044 85.940184) (width 0.15) (layer "F.Cu") (net 36))
  (arc (start 179.419964 75.419965) (mid 179.47341 75.548995) (end 179.60244 75.602441) (width 0.15) (layer "F.Cu") (net 36))
  (segment (start 163.35272 93.266) (end 163.35272 90.025) (width 0.15) (layer "B.Cu") (net 36))
  (segment (start 198.581 78.45) (end 197.831 78.45) (width 0.15) (layer "B.Cu") (net 36))
  (segment (start 198.581 78.449) (end 197.230999 78.449) (width 0.15) (layer "B.Cu") (net 36))
  (segment (start 196.604112 78.524) (end 196.125 78.044888) (width 0.15) (layer "B.Cu") (net 36))
  (segment (start 197.155999 78.524) (end 196.604112 78.524) (width 0.15) (layer "B.Cu") (net 36))
  (segment (start 196.125 75.442488) (end 196.33 75.237488) (width 0.15) (layer "B.Cu") (net 36))
  (segment (start 196.33 75.237488) (end 196.577488 75.237488) (width 0.15) (layer "B.Cu") (net 36))
  (segment (start 163.35272 90.025) (end 163.52772 89.85) (width 0.15) (layer "B.Cu") (net 36))
  (segment (start 197.831 78.45) (end 197.756 78.525) (width 0.15) (layer "B.Cu") (net 36))
  (segment (start 196.125 78.044888) (end 196.125 75.442488) (width 0.15) (layer "B.Cu") (net 36))
  (segment (start 197.230999 78.449) (end 197.155999 78.524) (width 0.15) (layer "B.Cu") (net 36))
  (segment (start 163.35272 93.266) (end 163.52772 93.441) (width 0.15) (layer "B.Cu") (net 36))
  (segment (start 171.034906 81.448362) (end 171.034905 81.448364) (width 0.15) (layer "F.Cu") (net 37))
  (segment (start 164.283769 87.460459) (end 164.283768 87.46046) (width 0.15) (layer "F.Cu") (net 37))
  (segment (start 169.267147 83.41058) (end 169.267145 83.410579) (width 0.15) (layer "F.Cu") (net 37))
  (segment (start 166.935409 84.808818) (end 167.30493 85.17834) (width 0.15) (layer "F.Cu") (net 37))
  (segment (start 170.151028 82.526699) (end 170.151028 82.5267) (width 0.15) (layer "F.Cu") (net 37))
  (segment (start 166.615503 85.867764) (end 166.615502 85.867766) (width 0.15) (layer "F.Cu") (net 37))
  (segment (start 168.383267 84.29446) (end 168.383267 84.294461) (width 0.15) (layer "F.Cu") (net 37))
  (segment (start 168.70317 83.041057) (end 169.072691 83.410579) (width 0.15) (layer "F.Cu") (net 37))
  (segment (start 166.05153 85.692698) (end 166.051529 85.692699) (width 0.15) (layer "F.Cu") (net 37))
  (segment (start 168.383264 84.100003) (end 168.383263 84.100005) (width 0.15) (layer "F.Cu") (net 37))
  (segment (start 168.383267 84.294461) (end 168.383264 84.294459) (width 0.15) (layer "F.Cu") (net 37))
  (segment (start 169.587051 82.157177) (end 169.956572 82.526699) (width 0.15) (layer "F.Cu") (net 37))
  (segment (start 164.847742 87.635525) (end 164.847741 87.635527) (width 0.15) (layer "F.Cu") (net 37))
  (segment (start 167.499386 85.178341) (end 167.499384 85.17834) (width 0.15) (layer "F.Cu") (net 37))
  (segment (start 165.731625 86.946102) (end 165.731623 86.946101) (width 0.15) (layer "F.Cu") (net 37))
  (segment (start 168.383263 84.100005) (end 168.013743 83.730482) (width 0.15) (layer "F.Cu") (net 37))
  (segment (start 166.615506 86.062222) (end 166.615503 86.06222) (width 0.15) (layer "F.Cu") (net 37))
  (segment (start 170.470932 81.273295) (end 170.470931 81.273296) (width 0.15) (layer "F.Cu") (net 37))
  (segment (start 167.81929 83.924938) (end 168.188811 84.29446) (width 0.15) (layer "F.Cu") (net 37))
  (segment (start 165.731625 86.946101) (end 165.731625 86.946102) (width 0.15) (layer "F.Cu") (net 37))
  (segment (start 195.937536 74.887488) (end 196.082512 74.742512) (width 0.15) (layer "F.Cu") (net 37))
  (segment (start 164.847745 87.829982) (end 164.847745 87.829983) (width 0.15) (layer "F.Cu") (net 37))
  (segment (start 165.167648 86.576579) (end 165.537169 86.946101) (width 0.15) (layer "F.Cu") (net 37))
  (segment (start 170.151024 82.332244) (end 169.781504 81.962721) (width 0.15) (layer "F.Cu") (net 37))
  (segment (start 164.847745 87.829983) (end 164.847742 87.829981) (width 0.15) (layer "F.Cu") (net 37))
  (segment (start 162.97772 93.591) (end 162.97772 95.34168) (width 0.15) (layer "F.Cu") (net 37))
  (segment (start 166.615506 86.062221) (end 166.615506 86.062222) (width 0.15) (layer "F.Cu") (net 37))
  (segment (start 163.963862 88.519406) (end 163.963861 88.519408) (width 0.15) (layer "F.Cu") (net 37))
  (segment (start 169.587052 82.157176) (end 169.587051 82.157177) (width 0.15) (layer "F.Cu") (net 37))
  (segment (start 171.034905 81.448364) (end 170.665385 81.078841) (width 0.15) (layer "F.Cu") (net 37))
  (segment (start 171.034908 81.642818) (end 171.034908 81.642819) (width 0.15) (layer "F.Cu") (net 37))
  (segment (start 167.499383 84.983886) (end 167.129863 84.614363) (width 0.15) (layer "F.Cu") (net 37))
  (segment (start 171.034908 81.642819) (end 171.034906 81.642818) (width 0.15) (layer "F.Cu") (net 37))
  (segment (start 165.731623 86.751645) (end 165.731622 86.751647) (width 0.15) (layer "F.Cu") (net 37))
  (segment (start 171.918789 80.758939) (end 171.918785 80.758936) (width 0.15) (layer "F.Cu") (net 37))
  (segment (start 164.283768 87.46046) (end 164.653289 87.829982) (width 0.15) (layer "F.Cu") (net 37))
  (segment (start 165.167649 86.576578) (end 165.167648 86.576579) (width 0.15) (layer "F.Cu") (net 37))
  (segment (start 169.267145 83.216123) (end 169.267144 83.216125) (width 0.15) (layer "F.Cu") (net 37))
  (segment (start 167.499386 85.17834) (end 167.499386 85.178341) (width 0.15) (layer "F.Cu") (net 37))
  (segment (start 171.918789 80.758938) (end 171.918789 80.758939) (width 0.15) (layer "F.Cu") (net 37))
  (segment (start 169.267144 83.216125) (end 168.897624 82.846602) (width 0.15) (layer "F.Cu") (net 37))
  (segment (start 163.96386 88.71386) (end 163.963862 88.713862) (width 0.15) (layer "F.Cu") (net 37))
  (segment (start 163.963861 88.519408) (end 163.594341 88.149885) (width 0.15) (layer "F.Cu") (net 37))
  (segment (start 167.499384 84.983884) (end 167.499383 84.983886) (width 0.15) (layer "F.Cu") (net 37))
  (segment (start 171.354812 80.389416) (end 171.724333 80.758938) (width 0.15) (layer "F.Cu") (net 37))
  (segment (start 169.267147 83.410579) (end 169.267147 83.41058) (width 0.15) (layer "F.Cu") (net 37))
  (segment (start 171.918785 80.758936) (end 177.790234 74.887488) (width 0.15) (layer "F.Cu") (net 37))
  (segment (start 170.470931 81.273296) (end 170.840452 81.642818) (width 0.15) (layer "F.Cu") (net 37))
  (segment (start 166.051529 85.692699) (end 166.42105 86.062221) (width 0.15) (layer "F.Cu") (net 37))
  (segment (start 166.615502 85.867766) (end 166.245982 85.498243) (width 0.15) (layer "F.Cu") (net 37))
  (segment (start 164.847741 87.635527) (end 164.478221 87.266004) (width 0.15) (layer "F.Cu") (net 37))
  (segment (start 177.790234 74.887488) (end 195.937536 74.887488) (width 0.15) (layer "F.Cu") (net 37))
  (segment (start 165.731622 86.751647) (end 165.362102 86.382124) (width 0.15) (layer "F.Cu") (net 37))
  (segment (start 170.151025 82.332242) (end 170.151024 82.332244) (width 0.15) (layer "F.Cu") (net 37))
  (segment (start 162.82772 89.85) (end 163.96386 88.71386) (width 0.15) (layer "F.Cu") (net 37))
  (segment (start 170.151028 82.5267) (end 170.151025 82.526698) (width 0.15) (layer "F.Cu") (net 37))
  (segment (start 167.819291 83.924937) (end 167.81929 83.924938) (width 0.15) (layer "F.Cu") (net 37))
  (segment (start 166.93541 84.808817) (end 166.935409 84.808818) (width 0.15) (layer "F.Cu") (net 37))
  (segment (start 168.703171 83.041056) (end 168.70317 83.041057) (width 0.15) (layer "F.Cu") (net 37))
  (segment (start 162.82772 93.441) (end 162.97772 93.591) (width 0.15) (layer "F.Cu") (net 37))
  (segment (start 171.354813 80.389415) (end 171.354812 80.389416) (width 0.15) (layer "F.Cu") (net 37))
  (via (at 162.82772 89.85) (size 0.5) (drill 0.15) (layers "F.Cu" "B.Cu") (net 37))
  (via (at 162.82772 93.441) (size 0.5) (drill 0.15) (layers "F.Cu" "B.Cu") (net 37))
  (via (at 196.082512 74.742512) (size 0.5) (drill 0.15) (layers "F.Cu" "B.Cu") (net 37))
  (arc (start 164.478221 86.576578) (mid 164.822934 86.433794) (end 165.167649 86.576578) (width 0.15) (layer "F.Cu") (net 37))
  (arc (start 164.478221 87.266004) (mid 164.335436 86.921291) (end 164.478221 86.576578) (width 0.15) (layer "F.Cu") (net 37))
  (arc (start 169.072691 83.410579) (mid 169.16992 83.450853) (end 169.267147 83.410579) (width 0.15) (layer "F.Cu") (net 37))
  (arc (start 169.267145 83.410579) (mid 169.307417 83.313352) (end 169.267145 83.216123) (width 0.15) (layer "F.Cu") (net 37))
  (arc (start 163.963862 88.713862) (mid 164.004134 88.616635) (end 163.963862 88.519406) (width 0.15) (layer "F.Cu") (net 37))
  (arc (start 168.013743 83.730482) (mid 167.870958 83.385769) (end 168.013743 83.041056) (width 0.15) (layer "F.Cu") (net 37))
  (arc (start 170.840452 81.642818) (mid 170.937681 81.683092) (end 171.034908 81.642818) (width 0.15) (layer "F.Cu") (net 37))
  (arc (start 165.731623 86.946101) (mid 165.771895 86.848874) (end 165.731623 86.751645) (width 0.15) (layer "F.Cu") (net 37))
  (arc (start 171.034906 81.642818) (mid 171.075178 81.545591) (end 171.034906 81.448362) (width 0.15) (layer "F.Cu") (net 37))
  (arc (start 170.665385 81.078841) (mid 170.5226 80.734128) (end 170.665385 80.389415) (width 0.15) (layer "F.Cu") (net 37))
  (arc (start 168.013743 83.041056) (mid 168.358456 82.898272) (end 168.703171 83.041056) (width 0.15) (layer "F.Cu") (net 37))
  (arc (start 163.594341 87.460459) (mid 163.939054 87.317675) (end 164.283769 87.460459) (width 0.15) (layer "F.Cu") (net 37))
  (arc (start 165.362102 86.382124) (mid 165.219317 86.037411) (end 165.362102 85.692698) (width 0.15) (layer "F.Cu") (net 37))
  (arc (start 166.42105 86.062221) (mid 166.518279 86.102495) (end 166.615506 86.062221) (width 0.15) (layer "F.Cu") (net 37))
  (arc (start 168.383264 84.294459) (mid 168.423536 84.197232) (end 168.383264 84.100003) (width 0.15) (layer "F.Cu") (net 37))
  (arc (start 170.151025 82.526698) (mid 170.191297 82.429471) (end 170.151025 82.332242) (width 0.15) (layer "F.Cu") (net 37))
  (arc (start 165.537169 86.946101) (mid 165.634398 86.986375) (end 165.731625 86.946101) (width 0.15) (layer "F.Cu") (net 37))
  (arc (start 169.956572 82.526699) (mid 170.053801 82.566973) (end 170.151028 82.526699) (width 0.15) (layer "F.Cu") (net 37))
  (arc (start 164.653289 87.829982) (mid 164.750518 87.870256) (end 164.847745 87.829982) (width 0.15) (layer "F.Cu") (net 37))
  (arc (start 165.362102 85.692698) (mid 165.706815 85.549914) (end 166.05153 85.692698) (width 0.15) (layer "F.Cu") (net 37))
  (arc (start 171.724333 80.758938) (mid 171.821562 80.799212) (end 171.918789 80.758938) (width 0.15) (layer "F.Cu") (net 37))
  (arc (start 166.245982 85.498243) (mid 166.103197 85.15353) (end 166.245982 84.808817) (width 0.15) (layer "F.Cu") (net 37))
  (arc (start 169.781504 81.273295) (mid 170.126217 81.130511) (end 170.470932 81.273295) (width 0.15) (layer "F.Cu") (net 37))
  (arc (start 167.129863 84.614363) (mid 166.987078 84.26965) (end 167.129863 83.924937) (width 0.15) (layer "F.Cu") (net 37))
  (arc (start 168.897624 82.157176) (mid 169.242337 82.014392) (end 169.587052 82.157176) (width 0.15) (layer "F.Cu") (net 37))
  (arc (start 166.615503 86.06222) (mid 166.655775 85.964993) (end 166.615503 85.867764) (width 0.15) (layer "F.Cu") (net 37))
  (arc (start 169.781504 81.962721) (mid 169.638719 81.618008) (end 169.781504 81.273295) (width 0.15) (layer "F.Cu") (net 37))
  (arc (start 166.245982 84.808817) (mid 166.590695 84.666033) (end 166.93541 84.808817) (width 0.15) (layer "F.Cu") (net 37))
  (arc (start 163.594341 88.149885) (mid 163.451556 87.805172) (end 163.594341 87.460459) (width 0.15) (layer "F.Cu") (net 37))
  (arc (start 168.188811 84.29446) (mid 168.28604 84.334734) (end 168.383267 84.29446) (width 0.15) (layer "F.Cu") (net 37))
  (arc (start 167.129863 83.924937) (mid 167.474576 83.782153) (end 167.819291 83.924937) (width 0.15) (layer "F.Cu") (net 37))
  (arc (start 167.30493 85.17834) (mid 167.402159 85.218614) (end 167.499386 85.17834) (width 0.15) (layer "F.Cu") (net 37))
  (arc (start 170.665385 80.389415) (mid 171.010098 80.246631) (end 171.354813 80.389415) (width 0.15) (layer "F.Cu") (net 37))
  (arc (start 167.499384 85.17834) (mid 167.539656 85.081113) (end 167.499384 84.983884) (width 0.15) (layer "F.Cu") (net 37))
  (arc (start 168.897624 82.846602) (mid 168.754839 82.501889) (end 168.897624 82.157176) (width 0.15) (layer "F.Cu") (net 37))
  (arc (start 164.847742 87.829981) (mid 164.888014 87.732754) (end 164.847742 87.635525) (width 0.15) (layer "F.Cu") (net 37))
  (segment (start 198.581 78.949) (end 197.230999 78.949) (width 0.15) (layer "B.Cu") (net 37))
  (segment (start 196.459136 78.874) (end 195.775 78.189864) (width 0.15) (layer "B.Cu") (net 37))
  (segment (start 196.082512 74.99) (end 196.082512 74.742512) (width 0.15) (layer "B.Cu") (net 37))
  (segment (start 197.230999 78.949) (end 197.155999 78.874) (width 0.15) (layer "B.Cu") (net 37))
  (segment (start 197.831 78.95) (end 197.756 78.875) (width 0.15) (layer "B.Cu") (net 37))
  (segment (start 195.775 78.189864) (end 195.775 75.297512) (width 0.15) (layer "B.Cu") (net 37))
  (segment (start 163.00272 93.266) (end 163.00272 90.025) (width 0.15) (layer "B.Cu") (net 37))
  (segment (start 162.82772 93.441) (end 163.00272 93.266) (width 0.15) (layer "B.Cu") (net 37))
  (segment (start 195.775 75.297512) (end 196.082512 74.99) (width 0.15) (layer "B.Cu") (net 37))
  (segment (start 163.00272 90.025) (end 162.82772 89.85) (width 0.15) (layer "B.Cu") (net 37))
  (segment (start 197.155999 78.874) (end 196.459136 78.874) (width 0.15) (layer "B.Cu") (net 37))
  (segment (start 198.581 78.95) (end 197.831 78.95) (width 0.15) (layer "B.Cu") (net 37))
  (segment (start 168.051678 82.262687) (end 168.051678 82.262688) (width 0.15) (layer "F.Cu") (net 38))
  (segment (start 162.17772 95.34168) (end 162.17772 94.35) (width 0.15) (layer "F.Cu") (net 38))
  (segment (start 166.782956 81.630363) (end 166.782956 81.630364) (width 0.15) (layer "F.Cu") (net 38))
  (segment (start 169.435966 78.977351) (end 169.435966 78.977352) (width 0.15) (layer "F.Cu") (net 38))
  (segment (start 167.668196 80.745121) (end 167.668196 80.745122) (width 0.15) (layer "F.Cu") (net 38))
  (segment (start 178.057488 73.947488) (end 195.507488 73.947488) (width 0.15) (layer "F.Cu") (net 38))
  (segment (start 175.347 73.947488) (end 175.657488 73.947488) (width 0.15) (layer "F.Cu") (net 38))
  (segment (start 169.752808 79.294191) (end 170.06965 79.611033) (width 0.15) (layer "F.Cu") (net 38))
  (segment (start 167.473743 80.800866) (end 167.473741 80.800867) (width 0.15) (layer "F.Cu") (net 38))
  (segment (start 168.935563 81.378802) (end 168.935563 81.378803) (width 0.15) (layer "F.Cu") (net 38))
  (segment (start 176.617159 74.107159) (end 176.617159 74.10716) (width 0.15) (layer "F.Cu") (net 38))
  (segment (start 168.357626 79.916982) (end 168.413373 79.861236) (width 0.15) (layer "F.Cu") (net 38))
  (segment (start 169.435966 78.977352) (end 169.752808 79.294194) (width 0.15) (layer "F.Cu") (net 38))
  (segment (start 177.17683 73.947488) (end 177.257488 73.947488) (width 0.15) (layer "F.Cu") (net 38))
  (segment (start 162.15272 87.141768) (end 166.712244 82.582244) (width 0.15) (layer "F.Cu") (net 38))
  (segment (start 169.241511 79.033097) (end 169.297258 78.977351) (width 0.15) (layer "F.Cu") (net 38))
  (segment (start 166.782956 81.630364) (end 167.099798 81.947206) (width 0.15) (layer "F.Cu") (net 38))
  (segment (start 168.357627 80.05569) (end 168.991308 80.689373) (width 0.15) (layer "F.Cu") (net 38))
  (segment (start 177.97683 73.947488) (end 178.057488 73.947488) (width 0.15) (layer "F.Cu") (net 38))
  (segment (start 169.241513 79.033096) (end 169.241511 79.033097) (width 0.15) (layer "F.Cu") (net 38))
  (segment (start 169.819448 80.494917) (end 169.819448 80.494918) (width 0.15) (layer "F.Cu") (net 38))
  (segment (start 168.868923 80.178076) (end 169.185765 80.494918) (width 0.15) (layer "F.Cu") (net 38))
  (segment (start 168.357628 79.916981) (end 168.357626 79.916982) (width 0.15) (layer "F.Cu") (net 38))
  (segment (start 166.712245 81.94856) (end 166.588502 81.824817) (width 0.15) (layer "F.Cu") (net 38))
  (segment (start 167.101153 81.945846) (end 167.417995 82.262688) (width 0.15) (layer "F.Cu") (net 38))
  (segment (start 167.099798 81.947206) (end 167.101153 81.945846) (width 0.15) (layer "F.Cu") (net 38))
  (segment (start 170.319851 78.093466) (end 170.319851 78.093467) (width 0.15) (layer "F.Cu") (net 38))
  (segment (start 167.668196 80.745122) (end 167.985038 81.061964) (width 0.15) (layer "F.Cu") (net 38))
  (segment (start 170.125396 78.149212) (end 170.181143 78.093466) (width 0.15) (layer "F.Cu") (net 38))
  (segment (start 168.935563 81.378803) (end 168.991308 81.323057) (width 0.15) (layer "F.Cu") (net 38))
  (segment (start 168.552081 79.861236) (end 168.552081 79.861237) (width 0.15) (layer "F.Cu") (net 38))
  (segment (start 177.57683 74.266831) (end 177.657488 74.266831) (width 0.15) (layer "F.Cu") (net 38))
  (segment (start 177.417159 74.107159) (end 177.417159 74.10716) (width 0.15) (layer "F.Cu") (net 38))
  (segment (start 162.17772 94.35) (end 162.32772 94.2) (width 0.15) (layer "F.Cu") (net 38))
  (segment (start 169.752808 79.294194) (end 169.752808 79.294191) (width 0.15) (layer "F.Cu") (net 38))
  (segment (start 167.473741 80.800867) (end 167.529488 80.745121) (width 0.15) (layer "F.Cu") (net 38))
  (segment (start 166.712244 81.94856) (end 166.712245 81.94856) (width 0.15) (layer "F.Cu") (net 38))
  (segment (start 168.051678 82.262688) (end 168.107423 82.206942) (width 0.15) (layer "F.Cu") (net 38))
  (segment (start 170.703333 79.611033) (end 170.759078 79.555287) (width 0.15) (layer "F.Cu") (net 38))
  (segment (start 169.241512 79.171805) (end 169.875193 79.805488) (width 0.15) (layer "F.Cu") (net 38))
  (segment (start 176.77683 74.266831) (end 176.857488 74.266831) (width 0.15) (layer "F.Cu") (net 38))
  (segment (start 175.817159 74.107159) (end 175.817159 74.10716) (width 0.15) (layer "F.Cu") (net 38))
  (segment (start 167.473742 80.939575) (end 168.107423 81.573258) (width 0.15) (layer "F.Cu") (net 38))
  (segment (start 168.868923 80.178079) (end 168.868923 80.178076) (width 0.15) (layer "F.Cu") (net 38))
  (segment (start 168.552081 79.861237) (end 168.868923 80.178079) (width 0.15) (layer "F.Cu") (net 38))
  (segment (start 176.37683 73.947488) (end 176.457488 73.947488) (width 0.15) (layer "F.Cu") (net 38))
  (segment (start 177.817159 74.10716) (end 177.817159 74.107159) (width 0.15) (layer "F.Cu") (net 38))
  (segment (start 170.125398 78.149211) (end 170.125396 78.149212) (width 0.15) (layer "F.Cu") (net 38))
  (segment (start 162.15272 89.112482) (end 162.15272 87.141768) (width 0.15) (layer "F.Cu") (net 38))
  (segment (start 162.32772 89.287482) (end 162.15272 89.112482) (width 0.15) (layer "F.Cu") (net 38))
  (segment (start 169.819448 80.494918) (end 169.875193 80.439172) (width 0.15) (layer "F.Cu") (net 38))
  (segment (start 170.703333 79.611032) (end 170.703333 79.611033) (width 0.15) (layer "F.Cu") (net 38))
  (segment (start 175.97683 74.266831) (end 176.057488 74.266831) (width 0.15) (layer "F.Cu") (net 38))
  (segment (start 177.017159 74.10716) (end 177.017159 74.107159) (width 0.15) (layer "F.Cu") (net 38))
  (segment (start 176.217159 74.10716) (end 176.217159 74.107159) (width 0.15) (layer "F.Cu") (net 38))
  (segment (start 166.588501 81.686109) (end 166.644248 81.630363) (width 0.15) (layer "F.Cu") (net 38))
  (segment (start 171.077279 78.217211) (end 175.347 73.947488) (width 0.15) (layer "F.Cu") (net 38))
  (segment (start 167.985038 81.061961) (end 168.30188 81.378803) (width 0.15) (layer "F.Cu") (net 38))
  (segment (start 166.588501 81.686108) (end 166.588501 81.686109) (width 0.15) (layer "F.Cu") (net 38))
  (segment (start 170.319851 78.093467) (end 170.443595 78.217211) (width 0.15) (layer "F.Cu") (net 38))
  (segment (start 167.985038 81.061964) (end 167.985038 81.061961) (width 0.15) (layer "F.Cu") (net 38))
  (segment (start 170.125397 78.28792) (end 170.759078 78.921603) (width 0.15) (layer "F.Cu") (net 38))
  (via (at 162.32772 94.2) (size 0.5) (drill 0.15) (layers "F.Cu" "B.Cu") (net 38))
  (via (at 195.507488 73.947488) (size 0.5) (drill 0.15) (layers "F.Cu" "B.Cu") (net 38))
  (via (at 162.32772 89.287482) (size 0.5) (drill 0.15) (layers "F.Cu" "B.Cu") (net 38))
  (arc (start 176.057488 74.266831) (mid 176.170392 74.220064) (end 176.217159 74.10716) (width 0.15) (layer "F.Cu") (net 38))
  (arc (start 166.644248 81.630363) (mid 166.713601 81.601637) (end 166.782956 81.630363) (width 0.15) (layer "F.Cu") (net 38))
  (arc (start 177.017159 74.107159) (mid 177.063926 73.994255) (end 177.17683 73.947488) (width 0.15) (layer "F.Cu") (net 38))
  (arc (start 168.357627 80.05569) (mid 168.3289 79.986335) (end 168.357628 79.916981) (width 0.15) (layer "F.Cu") (net 38))
  (arc (start 168.107423 82.206942) (mid 168.238663 81.8901) (end 168.107423 81.573258) (width 0.15) (layer "F.Cu") (net 38))
  (arc (start 176.857488 74.266831) (mid 176.970392 74.220064) (end 177.017159 74.10716) (width 0.15) (layer "F.Cu") (net 38))
  (arc (start 168.413373 79.861236) (mid 168.482726 79.83251) (end 168.552081 79.861236) (width 0.15) (layer "F.Cu") (net 38))
  (arc (start 170.759078 79.555287) (mid 170.890318 79.238445) (end 170.759078 78.921603) (width 0.15) (layer "F.Cu") (net 38))
  (arc (start 176.617159 74.10716) (mid 176.663926 74.220064) (end 176.77683 74.266831) (width 0.15) (layer "F.Cu") (net 38))
  (arc (start 177.657488 74.266831) (mid 177.770392 74.220064) (end 177.817159 74.10716) (width 0.15) (layer "F.Cu") (net 38))
  (arc (start 176.217159 74.107159) (mid 176.263926 73.994255) (end 176.37683 73.947488) (width 0.15) (layer "F.Cu") (net 38))
  (arc (start 169.297258 78.977351) (mid 169.366611 78.948625) (end 169.435966 78.977351) (width 0.15) (layer "F.Cu") (net 38))
  (arc (start 177.817159 74.107159) (mid 177.863926 73.994255) (end 177.97683 73.947488) (width 0.15) (layer "F.Cu") (net 38))
  (arc (start 167.473742 80.939575) (mid 167.445015 80.87022) (end 167.473743 80.800866) (width 0.15) (layer "F.Cu") (net 38))
  (arc (start 170.443595 78.217211) (mid 170.760437 78.348451) (end 171.077279 78.217211) (width 0.15) (layer "F.Cu") (net 38))
  (arc (start 168.30188 81.378803) (mid 168.618722 81.510043) (end 168.935563 81.378802) (width 0.15) (layer "F.Cu") (net 38))
  (arc (start 167.417995 82.262688) (mid 167.734837 82.393928) (end 168.051678 82.262687) (width 0.15) (layer "F.Cu") (net 38))
  (arc (start 176.457488 73.947488) (mid 176.570392 73.994255) (end 176.617159 74.107159) (width 0.15) (layer "F.Cu") (net 38))
  (arc (start 169.241512 79.171805) (mid 169.212785 79.10245) (end 169.241513 79.033096) (width 0.15) (layer "F.Cu") (net 38))
  (arc (start 169.185765 80.494918) (mid 169.502607 80.626158) (end 169.819448 80.494917) (width 0.15) (layer "F.Cu") (net 38))
  (arc (start 177.257488 73.947488) (mid 177.370392 73.994255) (end 177.417159 74.107159) (width 0.15) (layer "F.Cu") (net 38))
  (arc (start 170.06965 79.611033) (mid 170.386492 79.742273) (end 170.703333 79.611032) (width 0.15) (layer "F.Cu") (net 38))
  (arc (start 167.529488 80.745121) (mid 167.598841 80.716395) (end 167.668196 80.745121) (width 0.15) (layer "F.Cu") (net 38))
  (arc (start 175.657488 73.947488) (mid 175.770392 73.994255) (end 175.817159 74.107159) (width 0.15) (layer "F.Cu") (net 38))
  (arc (start 168.991308 81.323057) (mid 169.122548 81.006215) (end 168.991308 80.689373) (width 0.15) (layer "F.Cu") (net 38))
  (arc (start 166.588502 81.824817) (mid 166.559774 81.755463) (end 166.588501 81.686108) (width 0.15) (layer "F.Cu") (net 38))
  (arc (start 169.875193 80.439172) (mid 170.006433 80.12233) (end 169.875193 79.805488) (width 0.15) (layer "F.Cu") (net 38))
  (arc (start 175.817159 74.10716) (mid 175.863926 74.220064) (end 175.97683 74.266831) (width 0.15) (layer "F.Cu") (net 38))
  (arc (start 170.181143 78.093466) (mid 170.250496 78.06474) (end 170.319851 78.093466) (width 0.15) (layer "F.Cu") (net 38))
  (arc (start 170.125397 78.28792) (mid 170.09667 78.218565) (end 170.125398 78.149211) (width 0.15) (layer "F.Cu") (net 38))
  (arc (start 177.417159 74.10716) (mid 177.463926 74.220064) (end 177.57683 74.266831) (width 0.15) (layer "F.Cu") (net 38))
  (arc (start 166.712244 82.582244) (mid 166.843484 82.265402) (end 166.712244 81.94856) (width 0.15) (layer "F.Cu") (net 38))
  (segment (start 162.32772 94.2) (end 162.15272 94.025) (width 0.15) (layer "B.Cu") (net 38))
  (segment (start 198.581 79.949) (end 197.230999 79.949) (width 0.15) (layer "B.Cu") (net 38))
  (segment (start 197.230999 79.949) (end 197.155999 80.024) (width 0.15) (layer "B.Cu") (net 38))
  (segment (start 195.205 74.002488) (end 195.26 73.947488) (width 0.15) (layer "B.Cu") (net 38))
  (segment (start 195.26 73.947488) (end 195.507488 73.947488) (width 0.15) (layer "B.Cu") (net 38))
  (segment (start 162.15272 94.025) (end 162.15272 89.462482) (width 0.15) (layer "B.Cu") (net 38))
  (segment (start 195.205 79.847512) (end 195.205 74.002488) (width 0.15) (layer "B.Cu") (net 38))
  (segment (start 195.381488 80.024) (end 195.205 79.847512) (width 0.15) (layer "B.Cu") (net 38))
  (segment (start 197.155999 80.024) (end 195.381488 80.024) (width 0.15) (layer "B.Cu") (net 38))
  (segment (start 162.15272 89.462482) (end 162.32772 89.287482) (width 0.15) (layer "B.Cu") (net 38))
  (segment (start 161.80272 89.112482) (end 161.80272 86.996792) (width 0.15) (layer "F.Cu") (net 39))
  (segment (start 169.571961 80.247431) (end 169.627706 80.191685) (width 0.15) (layer "F.Cu") (net 39))
  (segment (start 169.877911 77.901724) (end 169.877909 77.901725) (width 0.15) (layer "F.Cu") (net 39))
  (segment (start 168.110141 79.669494) (end 168.110139 79.669495) (width 0.15) (layer "F.Cu") (net 39))
  (segment (start 166.464757 82.196047) (end 166.464758 82.196047) (width 0.15) (layer "F.Cu") (net 39))
  (segment (start 170.829793 77.969724) (end 170.829792 77.969724) (width 0.15) (layer "F.Cu") (net 39))
  (segment (start 167.804191 82.015201) (end 167.859936 81.959455) (width 0.15) (layer "F.Cu") (net 39))
  (segment (start 175.202024 73.597488) (end 194.867536 73.597488) (width 0.15) (layer "F.Cu") (net 39))
  (segment (start 169.877909 77.901725) (end 169.933656 77.845979) (width 0.15) (layer "F.Cu") (net 39))
  (segment (start 167.226254 80.55338) (end 167.282001 80.497634) (width 0.15) (layer "F.Cu") (net 39))
  (segment (start 166.341015 81.43862) (end 166.39676 81.382876) (width 0.15) (layer "F.Cu") (net 39))
  (segment (start 167.030444 81.382876) (end 167.347286 81.699718) (width 0.15) (layer "F.Cu") (net 39))
  (segment (start 168.994024 78.78561) (end 169.049771 78.729864) (width 0.15) (layer "F.Cu") (net 39))
  (segment (start 168.743821 80.936861) (end 168.110138 80.303179) (width 0.15) (layer "F.Cu") (net 39))
  (segment (start 169.627706 80.052976) (end 168.994023 79.419294) (width 0.15) (layer "F.Cu") (net 39))
  (segment (start 168.688076 81.131315) (end 168.688076 81.131316) (width 0.15) (layer "F.Cu") (net 39))
  (segment (start 170.56734 77.845979) (end 170.691084 77.969723) (width 0.15) (layer "F.Cu") (net 39))
  (segment (start 168.79957 79.613749) (end 169.433252 80.247431) (width 0.15) (layer "F.Cu") (net 39))
  (segment (start 169.627706 80.052977) (end 169.627706 80.052976) (width 0.15) (layer "F.Cu") (net 39))
  (segment (start 161.62772 89.287482) (end 161.80272 89.112482) (width 0.15) (layer "F.Cu") (net 39))
  (segment (start 167.859936 81.820746) (end 167.226253 81.187064) (width 0.15) (layer "F.Cu") (net 39))
  (segment (start 167.859936 81.820747) (end 167.859936 81.820746) (width 0.15) (layer "F.Cu") (net 39))
  (segment (start 161.77772 95.34168) (end 161.77772 94.35) (width 0.15) (layer "F.Cu") (net 39))
  (segment (start 170.511591 79.169092) (end 170.511591 79.169091) (width 0.15) (layer "F.Cu") (net 39))
  (segment (start 168.110139 79.669495) (end 168.165886 79.613749) (width 0.15) (layer "F.Cu") (net 39))
  (segment (start 168.994026 78.785609) (end 168.994024 78.78561) (width 0.15) (layer "F.Cu") (net 39))
  (segment (start 168.688076 81.131316) (end 168.743821 81.07557) (width 0.15) (layer "F.Cu") (net 39))
  (segment (start 161.80272 86.996792) (end 166.464757 82.334757) (width 0.15) (layer "F.Cu") (net 39))
  (segment (start 169.683455 78.729864) (end 170.317137 79.363546) (width 0.15) (layer "F.Cu") (net 39))
  (segment (start 170.455846 79.363546) (end 170.511591 79.3078) (width 0.15) (layer "F.Cu") (net 39))
  (segment (start 167.347286 81.699718) (end 167.34864 81.698359) (width 0.15) (layer "F.Cu") (net 39))
  (segment (start 166.464758 82.196047) (end 166.341015 82.072304) (width 0.15) (layer "F.Cu") (net 39))
  (segment (start 167.915685 80.497634) (end 168.549367 81.131316) (width 0.15) (layer "F.Cu") (net 39))
  (segment (start 168.743821 80.936862) (end 168.743821 80.936861) (width 0.15) (layer "F.Cu") (net 39))
  (segment (start 167.226256 80.553379) (end 167.226254 80.55338) (width 0.15) (layer "F.Cu") (net 39))
  (segment (start 170.455846 79.363545) (end 170.455846 79.363546) (width 0.15) (layer "F.Cu") (net 39))
  (segment (start 167.34864 81.698359) (end 167.665482 82.015201) (width 0.15) (layer "F.Cu") (net 39))
  (segment (start 194.867536 73.597488) (end 195.012512 73.452512) (width 0.15) (layer "F.Cu") (net 39))
  (segment (start 167.804191 82.0152) (end 167.804191 82.015201) (width 0.15) (layer "F.Cu") (net 39))
  (segment (start 170.829792 77.969724) (end 171.245067 77.554445) (width 0.15) (layer "F.Cu") (net 39))
  (segment (start 171.245067 77.554445) (end 175.202024 73.597488) (width 0.15) (layer "F.Cu") (net 39))
  (segment (start 169.571961 80.24743) (end 169.571961 80.247431) (width 0.15) (layer "F.Cu") (net 39))
  (segment (start 161.77772 94.35) (end 161.62772 94.2) (width 0.15) (layer "F.Cu") (net 39))
  (segment (start 170.511591 79.169091) (end 169.877908 78.535409) (width 0.15) (layer "F.Cu") (net 39))
  (via (at 161.62772 94.2) (size 0.5) (drill 0.15) (layers "F.Cu" "B.Cu") (net 39))
  (via (at 161.62772 89.287482) (size 0.5) (drill 0.15) (layers "F.Cu" "B.Cu") (net 39))
  (via (at 195.012512 73.452512) (size 0.5) (drill 0.15) (layers "F.Cu" "B.Cu") (net 39))
  (arc (start 170.511591 79.3078) (mid 170.540318 79.238446) (end 170.511591 79.169092) (width 0.15) (layer "F.Cu") (net 39))
  (arc (start 167.282001 80.497634) (mid 167.598843 80.366394) (end 167.915685 80.497634) (width 0.15) (layer "F.Cu") (net 39))
  (arc (start 168.994023 79.419294) (mid 168.862783 79.102452) (end 168.994026 78.785609) (width 0.15) (layer "F.Cu") (net 39))
  (arc (start 168.549367 81.131316) (mid 168.618722 81.160043) (end 168.688076 81.131315) (width 0.15) (layer "F.Cu") (net 39))
  (arc (start 170.691084 77.969723) (mid 170.760438 77.998451) (end 170.829793 77.969724) (width 0.15) (layer "F.Cu") (net 39))
  (arc (start 168.743821 81.07557) (mid 168.772548 81.006216) (end 168.743821 80.936862) (width 0.15) (layer "F.Cu") (net 39))
  (arc (start 169.877908 78.535409) (mid 169.746668 78.218567) (end 169.877911 77.901724) (width 0.15) (layer "F.Cu") (net 39))
  (arc (start 170.317137 79.363546) (mid 170.386492 79.392273) (end 170.455846 79.363545) (width 0.15) (layer "F.Cu") (net 39))
  (arc (start 166.464757 82.334757) (mid 166.493486 82.265401) (end 166.464757 82.196047) (width 0.15) (layer "F.Cu") (net 39))
  (arc (start 168.165886 79.613749) (mid 168.482728 79.482509) (end 168.79957 79.613749) (width 0.15) (layer "F.Cu") (net 39))
  (arc (start 169.627706 80.191685) (mid 169.656433 80.122331) (end 169.627706 80.052977) (width 0.15) (layer "F.Cu") (net 39))
  (arc (start 166.39676 81.382876) (mid 166.713602 81.251636) (end 167.030444 81.382876) (width 0.15) (layer "F.Cu") (net 39))
  (arc (start 169.933656 77.845979) (mid 170.250498 77.714739) (end 170.56734 77.845979) (width 0.15) (layer "F.Cu") (net 39))
  (arc (start 167.226253 81.187064) (mid 167.095013 80.870222) (end 167.226256 80.553379) (width 0.15) (layer "F.Cu") (net 39))
  (arc (start 169.049771 78.729864) (mid 169.366613 78.598624) (end 169.683455 78.729864) (width 0.15) (layer "F.Cu") (net 39))
  (arc (start 167.665482 82.015201) (mid 167.734837 82.043928) (end 167.804191 82.0152) (width 0.15) (layer "F.Cu") (net 39))
  (arc (start 168.110138 80.303179) (mid 167.978898 79.986337) (end 168.110141 79.669494) (width 0.15) (layer "F.Cu") (net 39))
  (arc (start 166.341015 82.072304) (mid 166.209775 81.755462) (end 166.341015 81.43862) (width 0.15) (layer "F.Cu") (net 39))
  (arc (start 169.433252 80.247431) (mid 169.502607 80.276158) (end 169.571961 80.24743) (width 0.15) (layer "F.Cu") (net 39))
  (arc (start 167.859936 81.959455) (mid 167.888663 81.890101) (end 167.859936 81.820747) (width 0.15) (layer "F.Cu") (net 39))
  (segment (start 161.80272 94.025) (end 161.80272 89.462482) (width 0.15) (layer "B.Cu") (net 39))
  (segment (start 195.236512 80.374) (end 194.855 79.992488) (width 0.15) (layer "B.Cu") (net 39))
  (segment (start 161.62772 94.2) (end 161.80272 94.025) (width 0.15) (layer "B.Cu") (net 39))
  (segment (start 197.230999 80.449) (end 197.155999 80.374) (width 0.15) (layer "B.Cu") (net 39))
  (segment (start 194.855 79.992488) (end 194.855 73.857512) (width 0.15) (layer "B.Cu") (net 39))
  (segment (start 194.855 73.857512) (end 195.012512 73.7) (width 0.15) (layer "B.Cu") (net 39))
  (segment (start 195.012512 73.7) (end 195.012512 73.452512) (width 0.15) (layer "B.Cu") (net 39))
  (segment (start 198.581 80.449) (end 197.230999 80.449) (width 0.15) (layer "B.Cu") (net 39))
  (segment (start 197.155999 80.374) (end 195.236512 80.374) (width 0.15) (layer "B.Cu") (net 39))
  (segment (start 161.80272 89.462482) (end 161.62772 89.287482) (width 0.15) (layer "B.Cu") (net 39))
  (segment (start 159.77772 95.34168) (end 159.77772 94.816679) (width 0.15) (layer "F.Cu") (net 40))
  (segment (start 159.75272 94.791679) (end 159.75272 94.3145) (width 0.15) (layer "F.Cu") (net 40))
  (segment (start 159.475 84.993488) (end 159.475 89.15) (width 0.15) (layer "F.Cu") (net 40))
  (segment (start 159.475 89.15) (end 159.65 89.325) (width 0.15) (layer "F.Cu") (net 40))
  (segment (start 159.77772 94.816679) (end 159.75272 94.791679) (width 0.15) (layer "F.Cu") (net 40))
  (segment (start 159.75272 94.3145) (end 159.92772 94.1395) (width 0.15) (layer "F.Cu") (net 40))
  (segment (start 193.497488 71.637488) (end 172.831 71.637488) (width 0.15) (layer "F.Cu") (net 40))
  (segment (start 172.831 71.637488) (end 159.475 84.993488) (width 0.15) (layer "F.Cu") (net 40))
  (via (at 193.497488 71.637488) (size 0.5) (drill 0.15) (layers "F.Cu" "B.Cu") (net 40))
  (via (at 159.65 89.325) (size 0.5) (drill 0.15) (layers "F.Cu" "B.Cu") (net 40))
  (via (at 159.92772 94.1395) (size 0.5) (drill 0.15) (layers "F.Cu" "B.Cu") (net 40))
  (segment (start 159.75272 92.230232) (end 159.475 91.952512) (width 0.15) (layer "B.Cu") (net 40))
  (segment (start 194.957152 82.577152) (end 194.904 82.577152) (width 0.15) (layer "B.Cu") (net 40))
  (segment (start 159.75272 93.9645) (end 159.75272 92.230232) (width 0.15) (layer "B.Cu") (net 40))
  (segment (start 194.404 83.024) (end 194.281488 83.024) (width 0.15) (layer "B.Cu") (net 40))
  (segment (start 193.245 81.987512) (end 193.245 71.642488) (width 0.15) (layer "B.Cu") (net 40))
  (segment (start 198.581 82.949) (end 197.230999 82.949) (width 0.15) (layer "B.Cu") (net 40))
  (segment (start 194.281488 83.024) (end 193.245 81.987512) (width 0.15) (layer "B.Cu") (net 40))
  (segment (start 197.230999 82.949) (end 197.155999 83.024) (width 0.15) (layer "B.Cu") (net 40))
  (segment (start 159.92772 94.1395) (end 159.75272 93.9645) (width 0.15) (layer "B.Cu") (net 40))
  (segment (start 197.155999 83.024) (end 196.404 83.024) (width 0.15) (layer "B.Cu") (net 40))
  (segment (start 159.475 89.5) (end 159.65 89.325) (width 0.15) (layer "B.Cu") (net 40))
  (segment (start 193.25 71.637488) (end 193.497488 71.637488) (width 0.15) (layer "B.Cu") (net 40))
  (segment (start 159.475 91.952512) (end 159.475 89.5) (width 0.15) (layer "B.Cu") (net 40))
  (segment (start 195.957152 82.577152) (end 195.904 82.577152) (width 0.15) (layer "B.Cu") (net 40))
  (segment (start 195.457152 83.024) (end 195.404 83.024) (width 0.15) (layer "B.Cu") (net 40))
  (segment (start 193.245 71.642488) (end 193.25 71.637488) (width 0.15) (layer "B.Cu") (net 40))
  (segment (start 194.457152 83.024) (end 194.404 83.024) (width 0.15) (layer "B.Cu") (net 40))
  (arc (start 194.680576 82.800576) (mid 194.615137 82.958561) (end 194.457152 83.024) (width 0.15) (layer "B.Cu") (net 40))
  (arc (start 195.180576 82.800576) (mid 195.115137 82.642591) (end 194.957152 82.577152) (width 0.15) (layer "B.Cu") (net 40))
  (arc (start 195.904 82.577152) (mid 195.746015 82.642591) (end 195.680576 82.800576) (width 0.15) (layer "B.Cu") (net 40))
  (arc (start 195.680576 82.800576) (mid 195.615137 82.958561) (end 195.457152 83.024) (width 0.15) (layer "B.Cu") (net 40))
  (arc (start 196.404 83.024) (mid 196.246015 82.958561) (end 196.180576 82.800576) (width 0.15) (layer "B.Cu") (net 40))
  (arc (start 195.404 83.024) (mid 195.246015 82.958561) (end 195.180576 82.800576) (width 0.15) (layer "B.Cu") (net 40))
  (arc (start 196.180576 82.800576) (mid 196.115137 82.642591) (end 195.957152 82.577152) (width 0.15) (layer "B.Cu") (net 40))
  (arc (start 194.904 82.577152) (mid 194.746015 82.642591) (end 194.680576 82.800576) (width 0.15) (layer "B.Cu") (net 40))
  (segment (start 159.40272 94.3145) (end 159.22772 94.1395) (width 0.15) (layer "F.Cu") (net 41))
  (segment (start 159.40272 94.791679) (end 159.40272 94.3145) (width 0.15) (layer "F.Cu") (net 41))
  (segment (start 159.125 84.848512) (end 159.125 89.15) (width 0.15) (layer "F.Cu") (net 41))
  (segment (start 172.686024 71.287488) (end 159.125 84.848512) (width 0.15) (layer "F.Cu") (net 41))
  (segment (start 159.37772 94.816679) (end 159.40272 94.791679) (width 0.15) (layer "F.Cu") (net 41))
  (segment (start 192.857536 71.287488) (end 172.686024 71.287488) (width 0.15) (layer "F.Cu") (net 41))
  (segment (start 159.125 89.15) (end 158.95 89.325) (width 0.15) (layer "F.Cu") (net 41))
  (segment (start 193.002512 71.142512) (end 192.857536 71.287488) (width 0.15) (layer "F.Cu") (net 41))
  (segment (start 159.37772 95.34168) (end 159.37772 94.816679) (width 0.15) (layer "F.Cu") (net 41))
  (via (at 159.22772 94.1395) (size 0.5) (drill 0.15) (layers "F.Cu" "B.Cu") (net 41))
  (via (at 193.002512 71.142512) (size 0.5) (drill 0.15) (layers "F.Cu" "B.Cu") (net 41))
  (via (at 158.95 89.325) (size 0.5) (drill 0.15) (layers "F.Cu" "B.Cu") (net 41))
  (segment (start 159.22772 94.1395) (end 159.40272 93.9645) (width 0.15) (layer "B.Cu") (net 41))
  (segment (start 192.895 82.132488) (end 192.895 71.497512) (width 0.15) (layer "B.Cu") (net 41))
  (segment (start 194.136512 83.374) (end 192.895 82.132488) (width 0.15) (layer "B.Cu") (net 41))
  (segment (start 192.895 71.497512) (end 193.002512 71.39) (width 0.15) (layer "B.Cu") (net 41))
  (segment (start 159.40272 92.375208) (end 159.125 92.097488) (width 0.15) (layer "B.Cu") (net 41))
  (segment (start 193.002512 71.39) (end 193.002512 71.142512) (width 0.15) (layer "B.Cu") (net 41))
  (segment (start 197.155999 83.374) (end 194.136512 83.374) (width 0.15) (layer "B.Cu") (net 41))
  (segment (start 198.581 83.449) (end 197.230999 83.449) (width 0.15) (layer "B.Cu") (net 41))
  (segment (start 159.125 92.097488) (end 159.125 89.5) (width 0.15) (layer "B.Cu") (net 41))
  (segment (start 159.125 89.5) (end 158.95 89.325) (width 0.15) (layer "B.Cu") (net 41))
  (segment (start 159.40272 93.9645) (end 159.40272 92.375208) (width 0.15) (layer "B.Cu") (net 41))
  (segment (start 197.230999 83.449) (end 197.155999 83.374) (width 0.15) (layer "B.Cu") (net 41))
  (segment (start 159.37772 61.34168) (end 159.77772 61.34168) (width 0.2) (layer "F.Cu") (net 50))
  (segment (start 160.997231 61.361191) (end 160.97772 61.34168) (width 0.2) (layer "F.Cu") (net 52))
  (segment (start 160.997231 63.527766) (end 160.997231 61.361191) (width 0.18) (layer "F.Cu") (net 52))
  (segment (start 171.464124 67.335876) (end 171.517557 67.389309) (width 0.2) (layer "F.Cu") (net 52))
  (segment (start 200.22 79.43) (end 200.17 79.43) (width 0.2) (layer "F.Cu") (net 52))
  (segment (start 176.100691 67.389309) (end 178.39 65.1) (width 0.2) (layer "F.Cu") (net 52))
  (segment (start 160.75 63.66) (end 160.864997 63.66) (width 0.2) (layer "F.Cu") (net 52))
  (segment (start 171.517557 67.389309) (end 176.100691 67.389309) (width 0.2) (layer "F.Cu") (net 52))
  (segment (start 200.17 79.43) (end 200.88 78.72) (width 0.17) (layer "F.Cu") (net 52))
  (segment (start 200.88 78.72) (end 200.88 73.62) (width 0.17) (layer "F.Cu") (net 52))
  (segment (start 178.39 65.1) (end 185.6 65.1) (width 0.2) (layer "F.Cu") (net 52))
  (segment (start 185.6 65.1) (end 186.3 64.4) (width 0.2) (layer "F.Cu") (net 52))
  (segment (start 170.7 68.1) (end 171.464124 67.335876) (width 0.2) (layer "F.Cu") (net 52))
  (segment (start 186.3 64.4) (end 186.3 63.7) (width 0.2) (layer "F.Cu") (net 52))
  (segment (start 194.63 67.37) (end 194.63 66.35) (width 0.17) (layer "F.Cu") (net 52))
  (segment (start 200.88 73.62) (end 194.63 67.37) (width 0.17) (layer "F.Cu") (net 52))
  (segment (start 160.864997 63.66) (end 160.997231 63.527766) (width 0.2) (layer "F.Cu") (net 52))
  (via (at 170.7 68.1) (size 0.5) (drill 0.15) (layers "F.Cu" "B.Cu") (net 52))
  (via (at 200.22 79.43) (size 0.5) (drill 0.15) (layers "F.Cu" "B.Cu") (net 52))
  (via (at 160.75 63.66) (size 0.5) (drill 0.15) (layers "F.Cu" "B.Cu") (net 52))
  (via (at 186.3 63.7) (size 0.5) (drill 0.15) (layers "F.Cu" "B.Cu") (net 52))
  (via (at 194.63 66.35) (size 0.5) (drill 0.15) (layers "F.Cu" "B.Cu") (net 52))
  (segment (start 160.75 63.66) (end 160.75 65.85) (width 0.2) (layer "B.Cu") (net 52))
  (segment (start 201.226 79.43) (end 201.245 79.449) (width 0.2) (layer "B.Cu") (net 52))
  (segment (start 163 68.1) (end 170.7 68.1) (width 0.2) (layer "B.Cu") (net 52))
  (segment (start 160.75 65.85) (end 163 68.1) (width 0.2) (layer "B.Cu") (net 52))
  (segment (start 200.22 79.43) (end 201.226 79.43) (width 0.2) (layer "B.Cu") (net 52))
  (segment (start 187.32 64.72) (end 193 64.72) (width 0.2) (layer "B.Cu") (net 52))
  (segment (start 193 64.72) (end 194.63 66.35) (width 0.2) (layer "B.Cu") (net 52))
  (segment (start 186.3 63.7) (end 187.32 64.72) (width 0.2) (layer "B.Cu") (net 52))
  (segment (start 177.7 64.3) (end 185.7 64.3) (width 0.2) (layer "F.Cu") (net 53))
  (segment (start 193.964227 67.094227) (end 193.964227 66.883914) (width 0.2) (layer "F.Cu") (net 53))
  (segment (start 172.4 66.9) (end 175.1 66.9) (width 0.2) (layer "F.Cu") (net 53))
  (segment (start 200.585 78.055) (end 200.585 74.105) (width 0.17) (layer "F.Cu") (net 53))
  (segment (start 161.66 63.66) (end 161.5155 63.66) (width 0.2) (layer "F.Cu") (net 53))
  (segment (start 171.714309 66.914309) (end 172.385691 66.914309) (width 0.2) (layer "F.Cu") (net 53))
  (segment (start 175.1 66.9) (end 177.7 64.3) (width 0.2) (layer "F.Cu") (net 53))
  (segment (start 161.5155 63.66) (end 161.358209 63.502709) (width 0.2) (layer "F.Cu") (net 53))
  (segment (start 200.585 74.105) (end 193.964227 67.484227) (width 0.17) (layer "F.Cu") (net 53))
  (segment (start 161.358209 63.502709) (end 161.358209 61.361191) (width 0.18) (layer "F.Cu") (net 53))
  (segment (start 199.97 78.67) (end 200.585 78.055) (width 0.17) (layer "F.Cu") (net 53))
  (segment (start 199.97 78.766811) (end 199.97 78.67) (width 0.17) (layer "F.Cu") (net 53))
  (segment (start 172.385691 66.914309) (end 172.4 66.9) (width 0.2) (layer "F.Cu") (net 53))
  (segment (start 193.964227 67.484227) (end 193.964227 67.094227) (width 0.17) (layer "F.Cu") (net 53))
  (segment (start 161.358209 61.361191) (end 161.37772 61.34168) (width 0.2) (layer "F.Cu") (net 53))
  (via (at 171.714309 66.914309) (size 0.5) (drill 0.15) (layers "F.Cu" "B.Cu") (net 53))
  (via (at 185.7 64.3) (size 0.5) (drill 0.15) (layers "F.Cu" "B.Cu") (net 53))
  (via (at 199.97 78.766811) (size 0.5) (drill 0.15) (layers "F.Cu" "B.Cu") (net 53))
  (via (at 193.964227 66.883914) (size 0.5) (drill 0.15) (layers "F.Cu" "B.Cu") (net 53))
  (via (at 161.66 63.66) (size 0.5) (drill 0.15) (layers "F.Cu" "B.Cu") (net 53))
  (segment (start 162.556857 66.914309) (end 171.714309 66.914309) (width 0.2) (layer "B.Cu") (net 53))
  (segment (start 199.97 78.766811) (end 200.152189 78.949) (width 0.2) (layer "B.Cu") (net 53))
  (segment (start 193.964227 66.883914) (end 193.964227 66.674227) (width 0.2) (layer "B.Cu") (net 53))
  (segment (start 192.51 65.22) (end 186.62 65.22) (width 0.2) (layer "B.Cu") (net 53))
  (segment (start 161.66 66.017452) (end 162.556857 66.914309) (width 0.2) (layer "B.Cu") (net 53))
  (segment (start 186.62 65.22) (end 185.7 64.3) (width 0.2) (layer "B.Cu") (net 53))
  (segment (start 200.152189 78.949) (end 201.245 78.949) (width 0.2) (layer "B.Cu") (net 53))
  (segment (start 193.964227 66.674227) (end 192.51 65.22) (width 0.2) (layer "B.Cu") (net 53))
  (segment (start 161.66 63.66) (end 161.66 66.017452) (width 0.2) (layer "B.Cu") (net 53))
  (segment (start 102.633931 86.466069) (end 102.633931 86.543911) (width 0.2) (layer "F.Cu") (net 57))
  (segment (start 165.093996 62.66) (end 165.655 62.66) (width 0.2) (layer "F.Cu") (net 57))
  (segment (start 103.366709 82.661709) (end 103.366709 85.733291) (width 0.2) (layer "F.Cu") (net 57))
  (segment (start 166.17772 62.13728) (end 166.17772 61.34168) (width 0.2) (layer "F.Cu") (net 57))
  (segment (start 165.655 62.66) (end 166.17772 62.13728) (width 0.2) (layer "F.Cu") (net 57))
  (segment (start 103.366709 85.733291) (end 102.633931 86.466069) (width 0.2) (layer "F.Cu") (net 57))
  (segment (start 164.783996 62.35) (end 165.093996 62.66) (width 0.2) (layer "F.Cu") (net 57))
  (via (at 102.633931 86.543911) (size 0.5) (drill 0.15) (layers "F.Cu" "B.Cu") (net 57))
  (via (at 103.366709 82.661709) (size 0.5) (drill 0.15) (layers "F.Cu" "B.Cu") (net 57))
  (via (at 164.783996 62.35) (size 0.5) (drill 0.15) (layers "F.Cu" "B.Cu") (net 57))
  (segment (start 103.371709 82.656709) (end 103.688418 82.34) (width 0.16) (layer "B.Cu") (net 57))
  (segment (start 137.07 78.43) (end 149.365 66.135) (width 0.16) (layer "B.Cu") (net 57))
  (segment (start 114.98 71.56) (end 115.31 71.23) (width 0.16) (layer "B.Cu") (net 57))
  (segment (start 125.89 78.43) (end 137.07 78.43) (width 0.16) (layer "B.Cu") (net 57))
  (segment (start 114.98 71.85) (end 114.98 71.56) (width 0.16) (layer "B.Cu") (net 57))
  (segment (start 156.524181 61.47) (end 164.36 61.47) (width 0.2) (layer "B.Cu") (net 57))
  (segment (start 100.89448 88.27552) (end 88.82048 88.27552) (width 0.2) (layer "B.Cu") (net 57))
  (segment (start 104.49 82.34) (end 114.98 71.85) (width 0.16) (layer "B.Cu") (net 57))
  (segment (start 164.36 61.47) (end 164.783996 61.893996) (width 0.2) (layer "B.Cu") (net 57))
  (segment (start 164.783996 61.893996) (end 164.783996 62.35) (width 0.2) (layer "B.Cu") (net 57))
  (segment (start 151.859181 66.135) (end 156.524181 61.47) (width 0.16) (layer "B.Cu") (net 57))
  (segment (start 102.626089 86.543911) (end 100.89448 88.27552) (width 0.2) (layer "B.Cu") (net 57))
  (segment (start 88.82048 88.27552) (end 88.425 88.671) (width 0.2) (layer "B.Cu") (net 57))
  (segment (start 118.69 71.23) (end 125.89 78.43) (width 0.16) (layer "B.Cu") (net 57))
  (segment (start 149.365 66.135) (end 151.859181 66.135) (width 0.16) (layer "B.Cu") (net 57))
  (segment (start 103.688418 82.34) (end 104.49 82.34) (width 0.16) (layer "B.Cu") (net 57))
  (segment (start 102.633931 86.543911) (end 102.626089 86.543911) (width 0.2) (layer "B.Cu") (net 57))
  (segment (start 103.366709 82.661709) (end 103.371709 82.656709) (width 0.2) (layer "B.Cu") (net 57))
  (segment (start 115.31 71.23) (end 118.69 71.23) (width 0.16) (layer "B.Cu") (net 57))
  (segment (start 167.589414 59.839501) (end 167.589414 59.805424) (width 0.2) (layer "F.Cu") (net 61))
  (segment (start 180.137 62.25) (end 179.197 61.31) (width 0.2) (layer "F.Cu") (net 61))
  (segment (start 186.29 62.25) (end 180.137 62.25) (width 0.2) (layer "F.Cu") (net 61))
  (segment (start 167.589414 59.805424) (end 167.37772 59.59373) (width 0.2) (layer "F.Cu") (net 61))
  (segment (start 196.08 66.41129) (end 196.08 67.52) (width 0.17) (layer "F.Cu") (net 61))
  (segment (start 201.85 73.29) (end 201.85 79.57) (width 0.17) (layer "F.Cu") (net 61))
  (segment (start 200.47 80.95) (end 200.15 80.95) (width 0.17) (layer "F.Cu") (net 61))
  (segment (start 201.85 79.57) (end 200.47 80.95) (width 0.17) (layer "F.Cu") (net 61))
  (segment (start 196.08 67.52) (end 201.85 73.29) (width 0.17) (layer "F.Cu") (net 61))
  (segment (start 167.37772 59.59373) (end 167.37772 58.26168) (width 0.2) (layer "F.Cu") (net 61))
  (segment (start 196.078174 66.409464) (end 196.08 66.41129) (width 0.17) (layer "F.Cu") (net 61))
  (via (at 167.589414 59.839501) (size 0.5) (drill 0.15) (layers "F.Cu" "B.Cu") (net 61))
  (via (at 177.6095 61.31) (size 0.5) (drill 0.15) (layers "F.Cu" "B.Cu") (net 61))
  (via (at 186.29 62.25) (size 0.5) (drill 0.15) (layers "F.Cu" "B.Cu") (net 61))
  (via (at 196.078174 66.409464) (size 0.5) (drill 0.15) (layers "F.Cu" "B.Cu") (net 61))
  (via (at 179.197 61.31) (size 0.5) (drill 0.15) (layers "F.Cu" "B.Cu") (net 61))
  (via (at 200.15 80.95) (size 0.5) (drill 0.15) (layers "F.Cu" "B.Cu") (net 61))
  (segment (start 169.08 61.31) (end 177.6095 61.31) (width 0.2) (layer "In1.Cu") (net 61))
  (segment (start 167.589414 59.839501) (end 167.609501 59.839501) (width 0.2) (layer "In1.Cu") (net 61))
  (segment (start 167.609501 59.839501) (end 169.08 61.31) (width 0.2) (layer "In1.Cu") (net 61))
  (segment (start 186.29 62.25) (end 186.59 62.25) (width 0.2) (layer "B.Cu") (net 61))
  (segment (start 194.19 63.58) (end 196.078174 65.468174) (width 0.2) (layer "B.Cu") (net 61))
  (segment (start 186.59 62.25) (end 187.92 63.58) (width 0.2) (layer "B.Cu") (net 61))
  (segment (start 200.15 80.95) (end 201.244 80.95) (width 0.2) (layer "B.Cu") (net 61))
  (segment (start 177.6095 61.31) (end 179.197 61.31) (width 0.2) (layer "B.Cu") (net 61))
  (segment (start 187.92 63.58) (end 194.19 63.58) (width 0.2) (layer "B.Cu") (net 61))
  (segment (start 201.244 80.95) (end 201.245 80.949) (width 0.2) (layer "B.Cu") (net 61))
  (segment (start 196.078174 65.468174) (end 196.078174 66.409464) (width 0.2) (layer "B.Cu") (net 61))
  (segment (start 189.76 64.61) (end 189.76 64.17) (width 0.2) (layer "F.Cu") (net 65))
  (segment (start 168.17772 59.12128) (end 168.148 59.151) (width 0.2) (layer "F.Cu") (net 65))
  (segment (start 200.134013 83.422883) (end 199.682883 83.422883) (width 0.17) (layer "F.Cu") (net 65))
  (segment (start 179.219 59.3) (end 179.197 59.278) (width 0.2) (layer "F.Cu") (net 65))
  (segment (start 199.682883 83.422883) (end 198.27 82.01) (width 0.17) (layer "F.Cu") (net 65))
  (segment (start 184.89 59.3) (end 179.219 59.3) (width 0.2) (layer "F.Cu") (net 65))
  (segment (start 198.27 73.86) (end 189.76 65.35) (width 0.17) (layer "F.Cu") (net 65))
  (segment (start 168.17772 58.26168) (end 168.17772 59.12128) (width 0.2) (layer "F.Cu") (net 65))
  (segment (start 198.27 82.01) (end 198.27 73.86) (width 0.17) (layer "F.Cu") (net 65))
  (segment (start 189.76 65.35) (end 189.76 64.61) (width 0.17) (layer "F.Cu") (net 65))
  (segment (start 189.76 64.17) (end 184.89 59.3) (width 0.2) (layer "F.Cu") (net 65))
  (via (at 179.197 59.278) (size 0.5) (drill 0.15) (layers "F.Cu" "B.Cu") (net 65))
  (via (at 168.148 59.151) (size 0.5) (drill 0.15) (layers "F.Cu" "B.Cu") (net 65))
  (via (at 177.658335 58.866812) (size 0.5) (drill 0.15) (layers "F.Cu" "B.Cu") (net 65))
  (via (at 200.134013 83.422883) (size 0.5) (drill 0.15) (layers "F.Cu" "B.Cu") (net 65))
  (segment (start 169.119 58.18) (end 168.148 59.151) (width 0.2) (layer "In1.Cu") (net 65))
  (segment (start 177.626812 58.866812) (end 176.94 58.18) (width 0.2) (layer "In1.Cu") (net 65))
  (segment (start 176.94 58.18) (end 169.119 58.18) (width 0.2) (layer "In1.Cu") (net 65))
  (segment (start 177.658335 58.866812) (end 177.626812 58.866812) (width 0.2) (layer "In1.Cu") (net 65))
  (segment (start 200.134013 83.422883) (end 200.16013 83.449) (width 0.254) (layer "B.Cu") (net 65))
  (segment (start 177.658335 58.866812) (end 178.069523 59.278) (width 0.2) (layer "B.Cu") (net 65))
  (segment (start 200.16013 83.449) (end 201.245 83.449) (width 0.254) (layer "B.Cu") (net 65))
  (segment (start 178.069523 59.278) (end 179.197 59.278) (width 0.2) (layer "B.Cu") (net 65))
  (segment (start 199.050152 84.010152) (end 197.87 82.83) (width 0.17) (layer "F.Cu") (net 67))
  (segment (start 197.87 74.09) (end 191.42 67.64) (width 0.17) (layer "F.Cu") (net 67))
  (segment (start 168.7 59.7) (end 168.7 59.684036) (width 0.2) (layer "F.Cu") (net 67))
  (segment (start 199.921602 84.010152) (end 199.050152 84.010152) (width 0.17) (layer "F.Cu") (net 67))
  (segment (start 168.7 59.684036) (end 168.97772 59.406316) (width 0.2) (layer "F.Cu") (net 67))
  (segment (start 197.87 82.83) (end 197.87 74.09) (width 0.17) (layer "F.Cu") (net 67))
  (segment (start 184.76 59.93) (end 189.22 64.39) (width 0.2) (layer "F.Cu") (net 67))
  (segment (start 189.22 64.39) (end 189.22 65.44) (width 0.2) (layer "F.Cu") (net 67))
  (segment (start 189.22 65.44) (end 191.42 67.64) (width 0.2) (layer "F.Cu") (net 67))
  (segment (start 179.19 59.93) (end 184.76 59.93) (width 0.2) (layer "F.Cu") (net 67))
  (segment (start 168.97772 59.406316) (end 168.97772 58.26168) (width 0.2) (layer "F.Cu") (net 67))
  (via (at 177.54 59.48) (size 0.5) (drill 0.15) (layers "F.Cu" "B.Cu") (net 67))
  (via (at 179.19 59.93) (size 0.5) (drill 0.15) (layers "F.Cu" "B.Cu") (net 67))
  (via (at 199.921602 84.010152) (size 0.5) (drill 0.15) (layers "F.Cu" "B.Cu") (net 67))
  (via (at 168.7 59.7) (size 0.5) (drill 0.15) (layers "F.Cu" "B.Cu") (net 67))
  (segment (start 176.62 58.56) (end 171.159778 58.56) (width 0.2) (layer "In1.Cu") (net 67))
  (segment (start 177.54 59.48) (end 176.62 58.56) (width 0.2) (layer "In1.Cu") (net 67))
  (segment (start 169.552778 60.167) (end 169.167 60.167) (width 0.2) (layer "In1.Cu") (net 67))
  (segment (start 169.167 60.167) (end 168.7 59.7) (width 0.2) (layer "In1.Cu") (net 67))
  (segment (start 171.159778 58.56) (end 169.552778 60.167) (width 0.2) (layer "In1.Cu") (net 67))
  (segment (start 177.99 59.93) (end 179.19 59.93) (width 0.2) (layer "B.Cu") (net 67))
  (segment (start 199.921602 84.010152) (end 201.183848 84.010152) (width 0.2) (layer "B.Cu") (net 67))
  (segment (start 201.183848 84.010152) (end 201.245 83.949) (width 0.2) (layer "B.Cu") (net 67))
  (segment (start 177.54 59.48) (end 177.99 59.93) (width 0.2) (layer "B.Cu") (net 67))
  (segment (start 198.69 81.44) (end 198.69 73.71) (width 0.17) (layer "F.Cu") (net 69))
  (segment (start 198.69 73.71) (end 190.22 65.24) (width 0.17) (layer "F.Cu") (net 69))
  (segment (start 179.3175 58.7) (end 179.197 58.5795) (width 0.2) (layer "F.Cu") (net 69))
  (segment (start 190.22 65.24) (end 190.22 64.17) (width 0.17) (layer "F.Cu") (net 69))
  (segment (start 169.38 58.26396) (end 169.37772 58.26168) (width 0.2) (layer "F.Cu") (net 69))
  (segment (start 169.38 59.668026) (end 169.38 58.26396) (width 0.2) (layer "F.Cu") (net 69))
  (segment (start 199.7005 82.4505) (end 198.69 81.44) (width 0.17) (layer "F.Cu") (net 69))
  (segment (start 190.22 63.78) (end 185.14 58.7) (width 0.2) (layer "F.Cu") (net 69))
  (segment (start 185.14 58.7) (end 179.3175 58.7) (width 0.2) (layer "F.Cu") (net 69))
  (segment (start 169.360263 59.687763) (end 169.38 59.668026) (width 0.2) (layer "F.Cu") (net 69))
  (segment (start 200.269116 82.4505) (end 199.7005 82.4505) (width 0.17) (layer "F.Cu") (net 69))
  (segment (start 190.22 64.17) (end 190.22 63.78) (width 0.2) (layer "F.Cu") (net 69))
  (via (at 169.360263 59.687763) (size 0.5) (drill 0.15) (layers "F.Cu" "B.Cu") (net 69))
  (via (at 179.197 58.5795) (size 0.5) (drill 0.15) (layers "F.Cu" "B.Cu") (net 69))
  (via (at 200.269116 82.4505) (size 0.5) (drill 0.15) (layers "F.Cu" "B.Cu") (net 69))
  (segment (start 174.82198 58.51802) (end 175.75699 57.58301) (width 0.2) (layer "B.Cu") (net 69))
  (segment (start 169.926 59.7225) (end 171.13048 58.51802) (width 0.2) (layer "B.Cu") (net 69))
  (segment (start 178.20051 57.58301) (end 179.197 58.5795) (width 0.2) (layer "B.Cu") (net 69))
  (segment (start 171.13048 58.51802) (end 174.82198 58.51802) (width 0.2) (layer "B.Cu") (net 69))
  (segment (start 169.395 59.7225) (end 169.926 59.7225) (width 0.2) (layer "B.Cu") (net 69))
  (segment (start 200.269116 82.4505) (end 201.2435 82.4505) (width 0.2) (layer "B.Cu") (net 69))
  (segment (start 169.360263 59.687763) (end 169.395 59.7225) (width 0.2) (layer "B.Cu") (net 69))
  (segment (start 201.2435 82.4505) (end 201.245 82.449) (width 0.2) (layer "B.Cu") (net 69))
  (segment (start 175.75699 57.58301) (end 178.20051 57.58301) (width 0.2) (layer "B.Cu") (net 69))
  (segment (start 199.11 73.38) (end 190.73 65) (width 0.17) (layer "F.Cu") (net 71))
  (segment (start 169.89 59.04) (end 169.77772 58.92772) (width 0.2) (layer "F.Cu") (net 71))
  (segment (start 199.11 81.25) (end 199.11 73.38) (width 0.17) (layer "F.Cu") (net 71))
  (segment (start 169.77772 58.92772) (end 169.77772 58.26168) (width 0.2) (layer "F.Cu") (net 71))
  (segment (start 185.301 57.881) (end 179.197 57.881) (width 0.2) (layer "F.Cu") (net 71))
  (segment (start 190.73 63.92) (end 190.73 63.31) (width 0.2) (layer "F.Cu") (net 71))
  (segment (start 199.855502 81.859596) (end 199.719596 81.859596) (width 0.17) (layer "F.Cu") (net 71))
  (segment (start 199.719596 81.859596) (end 199.11 81.25) (width 0.17) (layer "F.Cu") (net 71))
  (segment (start 190.73 63.31) (end 185.301 57.881) (width 0.2) (layer "F.Cu") (net 71))
  (segment (start 190.73 65) (end 190.73 63.92) (width 0.17) (layer "F.Cu") (net 71))
  (via (at 199.855502 81.859596) (size 0.5) (drill 0.15) (layers "F.Cu" "B.Cu") (net 71))
  (via (at 169.89 59.04) (size 0.5) (drill 0.15) (layers "F.Cu" "B.Cu") (net 71))
  (via (at 179.197 57.881) (size 0.5) (drill 0.15) (layers "F.Cu" "B.Cu") (net 71))
  (segment (start 199.855502 81.859596) (end 199.944906 81.949) (width 0.254) (layer "B.Cu") (net 71))
  (segment (start 199.944906 81.949) (end 201.245 81.949) (width 0.254) (layer "B.Cu") (net 71))
  (segment (start 174.61 58.14) (end 175.49199 57.25801) (width 0.2) (layer "B.Cu") (net 71))
  (segment (start 169.89 59.04) (end 170.79 58.14) (width 0.2) (layer "B.Cu") (net 71))
  (segment (start 175.49199 57.25801) (end 178.57401 57.25801) (width 0.2) (layer "B.Cu") (net 71))
  (segment (start 178.57401 57.25801) (end 179.197 57.881) (width 0.2) (layer "B.Cu") (net 71))
  (segment (start 170.79 58.14) (end 174.61 58.14) (width 0.2) (layer "B.Cu") (net 71))
  (segment (start 195.34 67.49) (end 195.34 66.43) (width 0.17) (layer "F.Cu") (net 80))
  (segment (start 186.0505 62.7705) (end 179.197 62.7705) (width 0.2) (layer "F.Cu") (net 80))
  (segment (start 173.3105 62.7705) (end 174.6885 62.7705) (width 0.2) (layer "F.Cu") (net 80))
  (segment (start 201.35 73.5) (end 195.34 67.49) (width 0.17) (layer "F.Cu") (net 80))
  (segment (start 186.29 63.01) (end 186.0505 62.7705) (width 0.2) (layer "F.Cu") (net 80))
  (segment (start 172.57772 61.34168) (end 172.57772 62.03772) (width 0.2) (layer "F.Cu") (net 80))
  (segment (start 199.88 80.36) (end 200.12 80.36) (width 0.17) (layer "F.Cu") (net 80))
  (segment (start 172.57772 62.03772) (end 173.3105 62.7705) (width 0.2) (layer "F.Cu") (net 80))
  (segment (start 201.35 79.13) (end 201.35 73.5) (width 0.17) (layer "F.Cu") (net 80))
  (segment (start 200.12 80.36) (end 201.35 79.13) (width 0.17) (layer "F.Cu") (net 80))
  (via (at 199.88 80.36) (size 0.5) (drill 0.15) (layers "F.Cu" "B.Cu") (net 80))
  (via (at 186.29 63.01) (size 0.5) (drill 0.15) (layers "F.Cu" "B.Cu") (net 80))
  (via (at 179.197 62.7705) (size 0.5) (drill 0.15) (layers "F.Cu" "B.Cu") (net 80))
  (via (at 195.34 66.43) (size 0.5) (drill 0.15) (layers "F.Cu" "B.Cu") (net 80))
  (via (at 174.6885 62.7705) (size 0.5) (drill 0.15) (layers "F.Cu" "B.Cu") (net 80))
  (segment (start 186.41 63.01) (end 186.29 63.01) (width 0.2) (layer "B.Cu") (net 80))
  (segment (start 174.6885 62.7705) (end 179.197 62.7705) (width 0.2) (layer "B.Cu") (net 80))
  (segment (start 187.59 64.19) (end 186.41 63.01) (width 0.2) (layer "B.Cu") (net 80))
  (segment (start 195.34 65.67) (end 193.86 64.19) (width 0.2) (layer "B.Cu") (net 80))
  (segment (start 199.88 80.36) (end 201.156 80.36) (width 0.2) (layer "B.Cu") (net 80))
  (segment (start 201.156 80.36) (end 201.245 80.449) (width 0.2) (layer "B.Cu") (net 80))
  (segment (start 193.86 64.19) (end 187.59 64.19) (width 0.2) (layer "B.Cu") (net 80))
  (segment (start 195.34 66.43) (end 195.34 65.67) (width 0.2) (layer "B.Cu") (net 80))
  (segment (start 174.220691 57.240691) (end 174.220691 58.218709) (width 0.15) (layer "F.Cu") (net 84))
  (segment (start 174.220691 58.218709) (end 174.17772 58.26168) (width 0.15) (layer "F.Cu") (net 84))
  (segment (start 174.06 57.08) (end 174.220691 57.240691) (width 0.15) (layer "F.Cu") (net 84))
  (segment (start 170.353 57.197) (end 170.47 57.08) (width 0.15) (layer "F.Cu") (net 84))
  (segment (start 170.353 57.2) (end 170.353 57.197) (width 0.15) (layer "F.Cu") (net 84))
  (segment (start 170.47 57.08) (end 174.06 57.08) (width 0.15) (layer "F.Cu") (net 84))
  (segment (start 170.053 57.5) (end 170.353 57.2) (width 0.15) (layer "F.Cu") (net 84))
  (via (at 170.053 57.5) (size 0.5) (drill 0.15) (layers "F.Cu" "B.Cu") (net 84))
  (segment (start 97.880489 61.535511) (end 95.194489 61.535511) (width 0.15) (layer "B.Cu") (net 84))
  (segment (start 98.97 57) (end 153.6 57) (width 0.15) (layer "B.Cu") (net 84))
  (segment (start 169.403 58.15) (end 154.75 58.15) (width 0.15) (layer "B.Cu") (net 84))
  (segment (start 95.194489 61.535511) (end 93.070995 63.659005) (width 0.15) (layer "B.Cu") (net 84))
  (segment (start 98.185 57.785) (end 98.185 61.231) (width 0.15) (layer "B.Cu") (net 84))
  (segment (start 98.97 57) (end 98.185 57.785) (width 0.15) (layer "B.Cu") (net 84))
  (segment (start 98.185 61.231) (end 97.880489 61.535511) (width 0.15) (layer "B.Cu") (net 84))
  (segment (start 170.053 57.5) (end 169.403 58.15) (width 0.15) (layer "B.Cu") (net 84))
  (segment (start 153.6 57) (end 154.75 58.15) (width 0.15) (layer "B.Cu") (net 84))
  (segment (start 103.725 58.45) (end 103.725 75.1) (width 0.15) (layer "F.Cu") (net 86))
  (segment (start 103.85 58.325) (end 103.725 58.45) (width 0.15) (layer "F.Cu") (net 86))
  (segment (start 94.0791 75.38) (end 93.579618 74.880518) (width 0.15) (layer "F.Cu") (net 86))
  (segment (start 173.77772 57.656338) (end 173.77772 58.26168) (width 0.15) (layer "F.Cu") (net 86))
  (segment (start 103.725 75.1) (end 103.445 75.38) (width 0.15) (layer "F.Cu") (net 86))
  (segment (start 173.770691 57.649309) (end 173.77772 57.656338) (width 0.15) (layer "F.Cu") (net 86))
  (segment (start 103.445 75.38) (end 94.0791 75.38) (width 0.15) (layer "F.Cu") (net 86))
  (via (at 103.85 58.325) (size 0.5) (drill 0.15) (layers "F.Cu" "B.Cu") (net 86))
  (via (at 173.770691 57.649309) (size 0.5) (drill 0.15) (layers "F.Cu" "B.Cu") (net 86))
  (segment (start 112.85 57.98) (end 112.5 57.63) (width 0.15) (layer "B.Cu") (net 86))
  (segment (start 169.8215 58.43) (end 154.63 58.43) (width 0.15) (layer "B.Cu") (net 86))
  (segment (start 171.23 57.02) (end 169.8215 58.4285) (width 0.15) (layer "B.Cu") (net 86))
  (segment (start 169.8215 58.4285) (end 169.8215 58.43) (width 0.15) (layer "B.Cu") (net 86))
  (segment (start 173.141382 57.02) (end 171.23 57.02) (width 0.15) (layer "B.Cu") (net 86))
  (segment (start 149.16 63.9) (end 141.6 63.9) (width 0.15) (layer "B.Cu") (net 86))
  (segment (start 104.545 57.63) (end 103.85 58.325) (width 0.15) (layer "B.Cu") (net 86))
  (segment (start 154.63 58.43) (end 149.16 63.9) (width 0.15) (layer "B.Cu") (net 86))
  (segment (start 141.6 63.9) (end 135.68 57.98) (width 0.15) (layer "B.Cu") (net 86))
  (segment (start 173.770691 57.649309) (end 173.141382 57.02) (width 0.15) (layer "B.Cu") (net 86))
  (segment (start 112.5 57.63) (end 104.545 57.63) (width 0.15) (layer "B.Cu") (net 86))
  (segment (start 135.68 57.98) (end 112.85 57.98) (width 0.15) (layer "B.Cu") (net 86))
  (segment (start 113.262 72.533) (end 113.722 72.073) (width 0.15) (layer "F.Cu") (net 87))
  (segment (start 117.432625 69.589857) (end 117.432626 69.589857) (width 0.15) (layer "F.Cu") (net 87))
  (segment (start 117.432626 69.589857) (end 117.432627 69.589859) (width 0.15) (layer "F.Cu") (net 87))
  (segment (start 119.107995 67.914493) (end 119.377488 67.645) (width 0.15) (layer "F.Cu") (net 87))
  (segment (start 116.743197 70.473743) (end 116.743198 70.473743) (width 0.15) (layer "F.Cu") (net 87))
  (segment (start 116.743198 70.473743) (end 117.195551 70.926096) (width 0.15) (layer "F.Cu") (net 87))
  (segment (start 117.627082 69.589859) (end 118.079435 70.042212) (width 0.15) (layer "F.Cu") (net 87))
  (segment (start 172.584012 59.453) (end 172.411488 59.453) (width 0.15) (layer "F.Cu") (net 87))
  (segment (start 169.582488 67.645) (end 172.26 64.967488) (width 0.15) (layer "F.Cu") (net 87))
  (segment (start 118.316511 68.705976) (end 118.436244 68.586244) (width 0.15) (layer "F.Cu") (net 87))
  (segment (start 114.949488 72.073) (end 116.548743 70.473743) (width 0.15) (layer "F.Cu") (net 87))
  (segment (start 119.052851 68.354323) (end 119.052851 68.354324) (width 0.15) (layer "F.Cu") (net 87))
  (segment (start 119.001927 68.020558) (end 119.001929 68.020558) (width 0.15) (layer "F.Cu") (net 87))
  (segment (start 118.719086 68.586244) (end 118.770009 68.637167) (width 0.15) (layer "F.Cu") (net 87))
  (segment (start 119.052852 68.637166) (end 119.052851 68.637167) (width 0.15) (layer "F.Cu") (net 87))
  (segment (start 172.26 59.604488) (end 172.26 59.9285) (width 0.15) (layer "F.Cu") (net 87))
  (segment (start 172.435 60.1035) (end 172.26 59.9285) (width 0.15) (layer "F.Cu") (net 87))
  (segment (start 117.88498 70.926097) (end 117.88498 70.926096) (width 0.15) (layer "F.Cu") (net 87))
  (segment (start 117.88498 70.236666) (end 117.432626 69.784312) (width 0.15) (layer "F.Cu") (net 87))
  (segment (start 119.377488 67.645) (end 169.582488 67.645) (width 0.15) (layer "F.Cu") (net 87))
  (segment (start 172.26 64.967488) (end 172.26 62.755) (width 0.15) (layer "F.Cu") (net 87))
  (segment (start 113.722 72.073) (end 114.949488 72.073) (width 0.15) (layer "F.Cu") (net 87))
  (segment (start 172.26 62.755) (end 172.435 62.58) (width 0.15) (layer "F.Cu") (net 87))
  (segment (start 174.806512 60.4055) (end 173.536512 60.4055) (width 0.15) (layer "F.Cu") (net 87))
  (segment (start 172.411488 59.453) (end 172.26 59.604488) (width 0.15) (layer "F.Cu") (net 87))
  (segment (start 174.97772 61.34168) (end 174.97772 60.576708) (width 0.15) (layer "F.Cu") (net 87))
  (segment (start 118.768864 69.352782) (end 118.31651 68.900428) (width 0.15) (layer "F.Cu") (net 87))
  (segment (start 119.001928 68.020557) (end 119.001927 68.020558) (width 0.15) (layer "F.Cu") (net 87))
  (segment (start 118.316509 68.705973) (end 118.31651 68.705973) (width 0.15) (layer "F.Cu") (net 87))
  (segment (start 174.97772 60.576708) (end 174.806512 60.4055) (width 0.15) (layer "F.Cu") (net 87))
  (segment (start 119.001929 68.020558) (end 119.107995 67.914493) (width 0.15) (layer "F.Cu") (net 87))
  (segment (start 173.536512 60.4055) (end 172.584012 59.453) (width 0.15) (layer "F.Cu") (net 87))
  (segment (start 117.627081 69.589859) (end 117.627082 69.589859) (width 0.15) (layer "F.Cu") (net 87))
  (segment (start 118.768864 70.042213) (end 118.768864 70.042212) (width 0.15) (layer "F.Cu") (net 87))
  (segment (start 118.31651 68.705973) (end 118.316511 68.705976) (width 0.15) (layer "F.Cu") (net 87))
  (segment (start 119.052851 68.354324) (end 119.001927 68.3034) (width 0.15) (layer "F.Cu") (net 87))
  (via (at 172.435 60.1035) (size 0.5) (drill 0.15) (layers "F.Cu" "B.Cu") (net 87))
  (via (at 172.435 62.58) (size 0.5) (drill 0.15) (layers "F.Cu" "B.Cu") (net 87))
  (arc (start 116.548743 70.473743) (mid 116.64597 70.43347) (end 116.743197 70.473743) (width 0.15) (layer "F.Cu") (net 87))
  (arc (start 117.432627 69.589859) (mid 117.529854 69.549586) (end 117.627081 69.589859) (width 0.15) (layer "F.Cu") (net 87))
  (arc (start 118.079435 70.042212) (mid 118.424149 70.184998) (end 118.768864 70.042213) (width 0.15) (layer "F.Cu") (net 87))
  (arc (start 119.052851 68.637167) (mid 119.11143 68.495745) (end 119.052851 68.354323) (width 0.15) (layer "F.Cu") (net 87))
  (arc (start 118.31651 68.900428) (mid 118.276237 68.803201) (end 118.316509 68.705973) (width 0.15) (layer "F.Cu") (net 87))
  (arc (start 117.88498 70.926096) (mid 118.027766 70.581381) (end 117.88498 70.236666) (width 0.15) (layer "F.Cu") (net 87))
  (arc (start 118.770009 68.637167) (mid 118.911431 68.695745) (end 119.052852 68.637166) (width 0.15) (layer "F.Cu") (net 87))
  (arc (start 117.195551 70.926096) (mid 117.540265 71.068882) (end 117.88498 70.926097) (width 0.15) (layer "F.Cu") (net 87))
  (arc (start 117.432626 69.784312) (mid 117.392353 69.687085) (end 117.432625 69.589857) (width 0.15) (layer "F.Cu") (net 87))
  (arc (start 118.436244 68.586244) (mid 118.577665 68.527666) (end 118.719086 68.586244) (width 0.15) (layer "F.Cu") (net 87))
  (arc (start 119.001927 68.3034) (mid 118.943349 68.161978) (end 119.001928 68.020557) (width 0.15) (layer "F.Cu") (net 87))
  (arc (start 118.768864 70.042212) (mid 118.91165 69.697497) (end 118.768864 69.352782) (width 0.15) (layer "F.Cu") (net 87))
  (segment (start 172.26 60.2785) (end 172.435 60.1035) (width 0.15) (layer "B.Cu") (net 87))
  (segment (start 172.435 62.58) (end 172.26 62.405) (width 0.15) (layer "B.Cu") (net 87))
  (segment (start 172.26 62.405) (end 172.26 60.2785) (width 0.15) (layer "B.Cu") (net 87))
  (segment (start 168.725 65.4) (end 168.9 65.575) (width 0.15) (layer "F.Cu") (net 88))
  (segment (start 174.97772 58.26168) (end 174.97772 57.725292) (width 0.15) (layer "F.Cu") (net 88))
  (segment (start 177.999488 57.2615) (end 178.5465 57.808512) (width 0.15) (layer "F.Cu") (net 88))
  (segment (start 115.855512 64.453) (end 116.802512 65.4) (width 0.15) (layer "F.Cu") (net 88))
  (segment (start 173.125 65.4) (end 172.95 65.575) (width 0.15) (layer "F.Cu") (net 88))
  (segment (start 174.97772 57.725292) (end 175.441512 57.2615) (width 0.15) (layer "F.Cu") (net 88))
  (segment (start 175.441512 57.2615) (end 177.999488 57.2615) (width 0.15) (layer "F.Cu") (net 88))
  (segment (start 116.802512 65.4) (end 168.725 65.4) (width 0.15) (layer "F.Cu") (net 88))
  (segment (start 178.5465 57.808512) (end 178.5465 62.010988) (width 0.15) (layer "F.Cu") (net 88))
  (segment (start 175.157488 65.4) (end 173.125 65.4) (width 0.15) (layer "F.Cu") (net 88))
  (segment (start 178.5465 62.010988) (end 175.157488 65.4) (width 0.15) (layer "F.Cu") (net 88))
  (segment (start 113.722 64.453) (end 115.855512 64.453) (width 0.15) (layer "F.Cu") (net 88))
  (segment (start 113.262 64.913) (end 113.722 64.453) (width 0.15) (layer "F.Cu") (net 88))
  (via (at 168.9 65.575) (size 0.5) (drill 0.15) (layers "F.Cu" "B.Cu") (net 88))
  (via (at 172.95 65.575) (size 0.5) (drill 0.15) (layers "F.Cu" "B.Cu") (net 88))
  (segment (start 168.9 65.575) (end 169.075 65.4) (width 0.15) (layer "B.Cu") (net 88))
  (segment (start 172.775 65.4) (end 172.95 65.575) (width 0.15) (layer "B.Cu") (net 88))
  (segment (start 169.075 65.4) (end 172.775 65.4) (width 0.15) (layer "B.Cu") (net 88))
  (segment (start 171.735 60.1035) (end 171.91 59.9285) (width 0.15) (layer "F.Cu") (net 89))
  (segment (start 118.069023 68.458487) (end 118.069023 68.458488) (width 0.15) (layer "F.Cu") (net 89))
  (segment (start 119.232512 67.295) (end 169.437512 67.295) (width 0.15) (layer "F.Cu") (net 89))
  (segment (start 171.91 62.755) (end 171.735 62.58) (width 0.15) (layer "F.Cu") (net 89))
  (segment (start 118.069022 68.458487) (end 118.069023 68.458487) (width 0.15) (layer "F.Cu") (net 89))
  (segment (start 117.637493 70.484154) (end 117.185139 70.0318) (width 0.15) (layer "F.Cu") (net 89))
  (segment (start 172.266512 59.103) (end 171.91 59.459512) (width 0.15) (layer "F.Cu") (net 89))
  (segment (start 118.521377 69.60027) (end 118.069023 69.147916) (width 0.15) (layer "F.Cu") (net 89))
  (segment (start 114.804512 71.723) (end 116.301256 70.226256) (width 0.15) (layer "F.Cu") (net 89))
  (segment (start 117.637493 70.484153) (end 117.637493 70.484154) (width 0.15) (layer "F.Cu") (net 89))
  (segment (start 171.91 59.459512) (end 171.91 59.9285) (width 0.15) (layer "F.Cu") (net 89))
  (segment (start 171.91 64.822512) (end 171.91 62.755) (width 0.15) (layer "F.Cu") (net 89))
  (segment (start 117.185139 69.342371) (end 117.18514 69.342372) (width 0.15) (layer "F.Cu") (net 89))
  (segment (start 118.069023 68.458488) (end 119.232512 67.295) (width 0.15) (layer "F.Cu") (net 89))
  (segment (start 113.262 71.263) (end 113.722 71.723) (width 0.15) (layer "F.Cu") (net 89))
  (segment (start 116.990684 70.226256) (end 116.990685 70.226256) (width 0.15) (layer "F.Cu") (net 89))
  (segment (start 117.185138 69.342371) (end 117.185139 69.342371) (width 0.15) (layer "F.Cu") (net 89))
  (segment (start 172.728988 59.103) (end 172.266512 59.103) (width 0.15) (layer "F.Cu") (net 89))
  (segment (start 169.437512 67.295) (end 171.91 64.822512) (width 0.15) (layer "F.Cu") (net 89))
  (segment (start 113.722 71.723) (end 114.804512 71.723) (width 0.15) (layer "F.Cu") (net 89))
  (segment (start 118.521377 69.600269) (end 118.521377 69.60027) (width 0.15) (layer "F.Cu") (net 89))
  (segment (start 117.874568 69.342372) (end 117.874569 69.342372) (width 0.15) (layer "F.Cu") (net 89))
  (segment (start 174.951488 60.0555) (end 173.681488 60.0555) (width 0.15) (layer "F.Cu") (net 89))
  (segment (start 116.990685 70.226256) (end 117.443038 70.678609) (width 0.15) (layer "F.Cu") (net 89))
  (segment (start 175.37772 61.34168) (end 175.37772 60.481732) (width 0.15) (layer "F.Cu") (net 89))
  (segment (start 117.874569 69.342372) (end 118.326922 69.794725) (width 0.15) (layer "F.Cu") (net 89))
  (segment (start 118.521377 69.794726) (end 118.521377 69.794725) (width 0.15) (layer "F.Cu") (net 89))
  (segment (start 117.637493 70.67861) (end 117.637493 70.678609) (width 0.15) (layer "F.Cu") (net 89))
  (segment (start 173.681488 60.0555) (end 172.728988 59.103) (width 0.15) (layer "F.Cu") (net 89))
  (segment (start 174.951488 60.0555) (end 175.37772 60.481732) (width 0.15) (layer "F.Cu") (net 89))
  (via (at 171.735 60.1035) (size 0.5) (drill 0.15) (layers "F.Cu" "B.Cu") (net 89))
  (via (at 171.735 62.58) (size 0.5) (drill 0.15) (layers "F.Cu" "B.Cu") (net 89))
  (arc (start 116.301256 70.226256) (mid 116.64597 70.083471) (end 116.990684 70.226256) (width 0.15) (layer "F.Cu") (net 89))
  (arc (start 118.069023 69.147916) (mid 117.926237 68.803202) (end 118.069022 68.458487) (width 0.15) (layer "F.Cu") (net 89))
  (arc (start 118.326922 69.794725) (mid 118.424149 69.834998) (end 118.521377 69.794726) (width 0.15) (layer "F.Cu") (net 89))
  (arc (start 117.443038 70.678609) (mid 117.540265 70.718882) (end 117.637493 70.67861) (width 0.15) (layer "F.Cu") (net 89))
  (arc (start 117.637493 70.678609) (mid 117.677766 70.581381) (end 117.637493 70.484153) (width 0.15) (layer "F.Cu") (net 89))
  (arc (start 118.521377 69.794725) (mid 118.56165 69.697497) (end 118.521377 69.600269) (width 0.15) (layer "F.Cu") (net 89))
  (arc (start 117.18514 69.342372) (mid 117.529854 69.199587) (end 117.874568 69.342372) (width 0.15) (layer "F.Cu") (net 89))
  (arc (start 117.185139 70.0318) (mid 117.042353 69.687086) (end 117.185138 69.342371) (width 0.15) (layer "F.Cu") (net 89))
  (segment (start 171.91 60.2785) (end 171.735 60.1035) (width 0.15) (layer "B.Cu") (net 89))
  (segment (start 171.735 62.58) (end 171.91 62.405) (width 0.15) (layer "B.Cu") (net 89))
  (segment (start 171.91 62.405) (end 171.91 60.2785) (width 0.15) (layer "B.Cu") (net 89))
  (segment (start 115.628 63.694756) (end 115.628 63.878) (width 0.15) (layer "F.Cu") (net 90))
  (segment (start 114.728 63.694756) (end 114.728 63.878) (width 0.15) (layer "F.Cu") (net 90))
  (segment (start 178.1965 61.866012) (end 175.012512 65.05) (width 0.15) (layer "F.Cu") (net 90))
  (segment (start 168.725 65.05) (end 168.9 64.875) (width 0.15) (layer "F.Cu") (net 90))
  (segment (start 175.012512 65.05) (end 173.125 65.05) (width 0.15) (layer "F.Cu") (net 90))
  (segment (start 113.262 63.643) (end 113.722 64.103) (width 0.15) (layer "F.Cu") (net 90))
  (segment (start 175.37772 57.820268) (end 175.586488 57.6115) (width 0.15) (layer "F.Cu") (net 90))
  (segment (start 173.125 65.05) (end 172.95 64.875) (width 0.15) (layer "F.Cu") (net 90))
  (segment (start 115.853 64.103) (end 115.903 64.103) (width 0.15) (layer "F.Cu") (net 90))
  (segment (start 175.37772 58.26168) (end 175.37772 57.820268) (width 0.15) (layer "F.Cu") (net 90))
  (segment (start 116.947488 65.05) (end 168.725 65.05) (width 0.15) (layer "F.Cu") (net 90))
  (segment (start 115.178 63.878) (end 115.178 63.694756) (width 0.15) (layer "F.Cu") (net 90))
  (segment (start 115.903 64.103) (end 116.000488 64.103) (width 0.15) (layer "F.Cu") (net 90))
  (segment (start 114.278 63.878) (end 114.278 63.694756) (width 0.15) (layer "F.Cu") (net 90))
  (segment (start 116.000488 64.103) (end 116.947488 65.05) (width 0.15) (layer "F.Cu") (net 90))
  (segment (start 177.854512 57.6115) (end 178.1965 57.953488) (width 0.15) (layer "F.Cu") (net 90))
  (segment (start 178.1965 57.953488) (end 178.1965 61.866012) (width 0.15) (layer "F.Cu") (net 90))
  (segment (start 175.586488 57.6115) (end 177.854512 57.6115) (width 0.15) (layer "F.Cu") (net 90))
  (segment (start 113.722 64.103) (end 114.053 64.103) (width 0.15) (layer "F.Cu") (net 90))
  (via (at 172.95 64.875) (size 0.5) (drill 0.15) (layers "F.Cu" "B.Cu") (net 90))
  (via (at 168.9 64.875) (size 0.5) (drill 0.15) (layers "F.Cu" "B.Cu") (net 90))
  (arc (start 114.728 63.878) (mid 114.793901 64.037099) (end 114.953 64.103) (width 0.15) (layer "F.Cu") (net 90))
  (arc (start 114.053 64.103) (mid 114.212099 64.037099) (end 114.278 63.878) (width 0.15) (layer "F.Cu") (net 90))
  (arc (start 115.403 63.469756) (mid 115.562099 63.535657) (end 115.628 63.694756) (width 0.15) (layer "F.Cu") (net 90))
  (arc (start 115.178 63.694756) (mid 115.243901 63.535657) (end 115.403 63.469756) (width 0.15) (layer "F.Cu") (net 90))
  (arc (start 114.278 63.694756) (mid 114.343901 63.535657) (end 114.503 63.469756) (width 0.15) (layer "F.Cu") (net 90))
  (arc (start 114.953 64.103) (mid 115.112099 64.037099) (end 115.178 63.878) (width 0.15) (layer "F.Cu") (net 90))
  (arc (start 115.628 63.878) (mid 115.693901 64.037099) (end 115.853 64.103) (width 0.15) (layer "F.Cu") (net 90))
  (arc (start 114.503 63.469756) (mid 114.662099 63.535657) (end 114.728 63.694756) (width 0.15) (layer "F.Cu") (net 90))
  (segment (start 172.775 65.05) (end 172.95 64.875) (width 0.15) (layer "B.Cu") (net 90))
  (segment (start 169.075 65.05) (end 172.775 65.05) (width 0.15) (layer "B.Cu") (net 90))
  (segment (start 168.9 64.875) (end 169.075 65.05) (width 0.15) (layer "B.Cu") (net 90))
  (segment (start 117.163757 67.394303) (end 117.163758 67.394301) (width 0.15) (layer "F.Cu") (net 91))
  (segment (start 115.4995 66.6255) (end 115.4995 69.5505) (width 0.15) (layer "F.Cu") (net 91))
  (segment (start 174.4405 63.4845) (end 175.314512 63.4845) (width 0.15) (layer "F.Cu") (net 91))
  (segment (start 117.163758 67.394301) (end 116.77485 67.005393) (width 0.15) (layer "F.Cu") (net 91))
  (segment (start 118.577512 66.175) (end 169.067512 66.175) (width 0.15) (layer "F.Cu") (net 91))
  (segment (start 176.17772 62.621292) (end 176.17772 61.34168) (width 0.15) (layer "F.Cu") (net 91))
  (segment (start 115.7745 69.5505) (end 115.7745 68.4005) (width 0.15) (layer "F.Cu") (net 91))
  (segment (start 114.5245 67.7755) (end 114.5245 66.6255) (width 0.15) (layer "F.Cu") (net 91))
  (segment (start 174.433684 63.4845) (end 174.4405 63.4845) (width 0.15) (layer "F.Cu") (net 91))
  (segment (start 118.047641 66.704872) (end 118.577512 66.175) (width 0.15) (layer "F.Cu") (net 91))
  (segment (start 118.047644 66.704873) (end 118.047641 66.704872) (width 0.15) (layer "F.Cu") (net 91))
  (segment (start 175.314512 63.4845) (end 176.17772 62.621292) (width 0.15) (layer "F.Cu") (net 91))
  (segment (start 172.974 63.3095) (end 173.149 63.4845) (width 0.15) (layer "F.Cu") (net 91))
  (segment (start 173.749592 63.350407) (end 173.749592 63.350408) (width 0.15) (layer "F.Cu") (net 91))
  (segment (start 169.925 64.037512) (end 170.478012 63.4845) (width 0.15) (layer "F.Cu") (net 91))
  (segment (start 170.478012 63.4845) (end 171.021 63.4845) (width 0.15) (layer "F.Cu") (net 91))
  (segment (start 169.067512 66.175) (end 169.925 65.317512) (width 0.15) (layer "F.Cu") (net 91))
  (segment (start 174.158684 63.216315) (end 174.1655 63.216315) (width 0.15) (layer "F.Cu") (net 91))
  (segment (start 116.839512 67.913) (end 117.163757 67.588757) (width 0.15) (layer "F.Cu") (net 91))
  (segment (start 169.925 65.317512) (end 169.925 64.037512) (width 0.15) (layer "F.Cu") (net 91))
  (segment (start 174.024592 63.350408) (end 174.024592 63.350407) (width 0.15) (layer "F.Cu") (net 91))
  (segment (start 113.262 67.453) (end 113.722 67.913) (width 0.15) (layer "F.Cu") (net 91))
  (segment (start 173.149 63.4845) (end 173.3405 63.4845) (width 0.15) (layer "F.Cu") (net 91))
  (segment (start 118.047642 66.704874) (end 118.047644 66.704873) (width 0.15) (layer "F.Cu") (net 91))
  (segment (start 173.474592 63.350408) (end 173.474592 63.350407) (width 0.15) (layer "F.Cu") (net 91))
  (segment (start 116.262 67.913) (end 116.839512 67.913) (width 0.15) (layer "F.Cu") (net 91))
  (segment (start 173.608684 63.216315) (end 173.6155 63.216315) (width 0.15) (layer "F.Cu") (net 91))
  (segment (start 171.021 63.4845) (end 171.196 63.3095) (width 0.15) (layer "F.Cu") (net 91))
  (segment (start 174.299592 63.350407) (end 174.299592 63.350408) (width 0.15) (layer "F.Cu") (net 91))
  (segment (start 116.774849 66.315964) (end 116.774849 66.315965) (width 0.15) (layer "F.Cu") (net 91))
  (segment (start 113.722 67.913) (end 114.387 67.913) (width 0.15) (layer "F.Cu") (net 91))
  (segment (start 117.464279 66.315965) (end 117.853188 66.704874) (width 0.15) (layer "F.Cu") (net 91))
  (segment (start 173.883684 63.4845) (end 173.8905 63.4845) (width 0.15) (layer "F.Cu") (net 91))
  (via (at 171.196 63.3095) (size 0.5) (drill 0.15) (layers "F.Cu" "B.Cu") (net 91))
  (via (at 172.974 63.3095) (size 0.5) (drill 0.15) (layers "F.Cu" "B.Cu") (net 91))
  (arc (start 115.7745 68.4005) (mid 115.917285 68.055785) (end 116.262 67.913) (width 0.15) (layer "F.Cu") (net 91))
  (arc (start 174.1655 63.216315) (mid 174.260317 63.25559) (end 174.299592 63.350407) (width 0.15) (layer "F.Cu") (net 91))
  (arc (start 114.5245 66.6255) (mid 114.667285 66.280785) (end 115.012 66.138) (width 0.15) (layer "F.Cu") (net 91))
  (arc (start 117.163757 67.588757) (mid 117.20403 67.49153) (end 117.163757 67.394303) (width 0.15) (layer "F.Cu") (net 91))
  (arc (start 115.4995 69.5505) (mid 115.539773 69.647727) (end 115.637 69.688) (width 0.15) (layer "F.Cu") (net 91))
  (arc (start 173.474592 63.350407) (mid 173.513867 63.25559) (end 173.608684 63.216315) (width 0.15) (layer "F.Cu") (net 91))
  (arc (start 173.8905 63.4845) (mid 173.985317 63.445225) (end 174.024592 63.350408) (width 0.15) (layer "F.Cu") (net 91))
  (arc (start 173.3405 63.4845) (mid 173.435317 63.445225) (end 173.474592 63.350408) (width 0.15) (layer "F.Cu") (net 91))
  (arc (start 116.774849 66.315965) (mid 117.119565 66.173178) (end 117.464279 66.315965) (width 0.15) (layer "F.Cu") (net 91))
  (arc (start 115.012 66.138) (mid 115.356715 66.280785) (end 115.4995 66.6255) (width 0.15) (layer "F.Cu") (net 91))
  (arc (start 116.77485 67.005393) (mid 116.632064 66.660679) (end 116.774849 66.315964) (width 0.15) (layer "F.Cu") (net 91))
  (arc (start 173.749592 63.350408) (mid 173.788867 63.445225) (end 173.883684 63.4845) (width 0.15) (layer "F.Cu") (net 91))
  (arc (start 173.6155 63.216315) (mid 173.710317 63.25559) (end 173.749592 63.350407) (width 0.15) (layer "F.Cu") (net 91))
  (arc (start 117.853188 66.704874) (mid 117.950415 66.745147) (end 118.047642 66.704874) (width 0.15) (layer "F.Cu") (net 91))
  (arc (start 114.387 67.913) (mid 114.484227 67.872727) (end 114.5245 67.7755) (width 0.15) (layer "F.Cu") (net 91))
  (arc (start 174.024592 63.350407) (mid 174.063867 63.25559) (end 174.158684 63.216315) (width 0.15) (layer "F.Cu") (net 91))
  (arc (start 115.637 69.688) (mid 115.734227 69.647727) (end 115.7745 69.5505) (width 0.15) (layer "F.Cu") (net 91))
  (arc (start 174.299592 63.350408) (mid 174.338867 63.445225) (end 174.433684 63.4845) (width 0.15) (layer "F.Cu") (net 91))
  (segment (start 171.371 63.4845) (end 171.196 63.3095) (width 0.15) (layer "B.Cu") (net 91))
  (segment (start 172.799 63.4845) (end 171.371 63.4845) (width 0.15) (layer "B.Cu") (net 91))
  (segment (start 172.974 63.3095) (end 172.799 63.4845) (width 0.15) (layer "B.Cu") (net 91))
  (segment (start 114.382 60.068) (end 114.382 60.03491) (width 0.15) (layer "F.Cu") (net 92))
  (segment (start 119.022026 63.544539) (end 119.602488 64.125) (width 0.15) (layer "F.Cu") (net 92))
  (segment (start 118.017242 63.665442) (end 118.020084 63.668284) (width 0.15) (layer "F.Cu") (net 92))
  (segment (start 176.17772 59.270564) (end 176.02772 59.420564) (width 0.15) (layer "F.Cu") (net 92))
  (segment (start 118.703831 62.787244) (end 118.360536 63.130536) (width 0.15) (layer "F.Cu") (net 92))
  (segment (start 169.222512 63.12) (end 169.222512 62.872512) (width 0.15) (layer "F.Cu") (net 92))
  (segment (start 118.211696 63.668284) (end 118.33544 63.544539) (width 0.15) (layer "F.Cu") (net 92))
  (segment (start 117.815685 61.212511) (end 117.818527 61.215353) (width 0.15) (layer "F.Cu") (net 92))
  (segment (start 113.262 59.833) (end 113.722 60.293) (width 0.15) (layer "F.Cu") (net 92))
  (segment (start 117.694782 62.025684) (end 117.475233 62.245233) (width 0.15) (layer "F.Cu") (net 92))
  (segment (start 115.770488 60.293) (end 116.813742 61.336255) (width 0.15) (layer "F.Cu") (net 92))
  (segment (start 114.832 60.03491) (end 114.832 60.068) (width 0.15) (layer "F.Cu") (net 92))
  (segment (start 118.70383 62.787242) (end 118.703831 62.787244) (width 0.15) (layer "F.Cu") (net 92))
  (segment (start 115.107 60.293) (end 115.770488 60.293) (width 0.15) (layer "F.Cu") (net 92))
  (segment (start 117.475233 62.245233) (end 117.476654 62.246654) (width 0.15) (layer "F.Cu") (net 92))
  (segment (start 168.217512 64.125) (end 169.222512 63.12) (width 0.15) (layer "F.Cu") (net 92))
  (segment (start 119.602488 64.125) (end 168.217512 64.125) (width 0.15) (layer "F.Cu") (net 92))
  (segment (start 115.057 60.293) (end 115.107 60.293) (width 0.15) (layer "F.Cu") (net 92))
  (segment (start 117.13336 62.589948) (end 117.476654 62.246654) (width 0.15) (layer "F.Cu") (net 92))
  (segment (start 117.818528 61.901941) (end 117.694782 62.025684) (width 0.15) (layer "F.Cu") (net 92))
  (segment (start 117.327814 62.784402) (end 118.014402 62.097814) (width 0.15) (layer "F.Cu") (net 92))
  (segment (start 176.17772 58.26168) (end 176.17772 59.270564) (width 0.15) (layer "F.Cu") (net 92))
  (segment (start 113.722 60.293) (end 114.157 60.293) (width 0.15) (layer "F.Cu") (net 92))
  (segment (start 117.818527 61.901939) (end 117.818528 61.901941) (width 0.15) (layer "F.Cu") (net 92))
  (segment (start 117.13336 62.78156) (end 117.136202 62.784402) (width 0.15) (layer "F.Cu") (net 92))
  (segment (start 118.360536 63.130536) (end 118.017242 63.47383) (width 0.15) (layer "F.Cu") (net 92))
  (segment (start 117.005356 61.336257) (end 117.129099 61.212511) (width 0.15) (layer "F.Cu") (net 92))
  (segment (start 118.700988 62.097814) (end 118.70383 62.100656) (width 0.15) (layer "F.Cu") (net 92))
  (via (at 169.222512 62.872512) (size 0.5) (drill 0.15) (layers "F.Cu" "B.Cu") (net 92))
  (via (at 176.02772 59.420564) (size 0.5) (drill 0.15) (layers "F.Cu" "B.Cu") (net 92))
  (arc (start 118.014402 62.097814) (mid 118.357695 61.955617) (end 118.700988 62.097814) (width 0.15) (layer "F.Cu") (net 92))
  (arc (start 114.157 60.293) (mid 114.316099 60.227099) (end 114.382 60.068) (width 0.15) (layer "F.Cu") (net 92))
  (arc (start 118.70383 62.100656) (mid 118.846027 62.443949) (end 118.70383 62.787242) (width 0.15) (layer "F.Cu") (net 92))
  (arc (start 114.382 60.03491) (mid 114.447901 59.875811) (end 114.607 59.80991) (width 0.15) (layer "F.Cu") (net 92))
  (arc (start 118.33544 63.544539) (mid 118.678733 63.402342) (end 119.022026 63.544539) (width 0.15) (layer "F.Cu") (net 92))
  (arc (start 117.13336 62.589948) (mid 117.093676 62.685754) (end 117.13336 62.78156) (width 0.15) (layer "F.Cu") (net 92))
  (arc (start 117.129099 61.212511) (mid 117.472392 61.070314) (end 117.815685 61.212511) (width 0.15) (layer "F.Cu") (net 92))
  (arc (start 117.818527 61.215353) (mid 117.960724 61.558646) (end 117.818527 61.901939) (width 0.15) (layer "F.Cu") (net 92))
  (arc (start 116.813742 61.336255) (mid 116.90955 61.375941) (end 117.005356 61.336257) (width 0.15) (layer "F.Cu") (net 92))
  (arc (start 117.136202 62.784402) (mid 117.232008 62.824086) (end 117.327814 62.784402) (width 0.15) (layer "F.Cu") (net 92))
  (arc (start 114.607 59.80991) (mid 114.766099 59.875811) (end 114.832 60.03491) (width 0.15) (layer "F.Cu") (net 92))
  (arc (start 118.017242 63.47383) (mid 117.977558 63.569636) (end 118.017242 63.665442) (width 0.15) (layer "F.Cu") (net 92))
  (arc (start 114.832 60.068) (mid 114.897901 60.227099) (end 115.057 60.293) (width 0.15) (layer "F.Cu") (net 92))
  (arc (start 118.020084 63.668284) (mid 118.11589 63.707968) (end 118.211696 63.668284) (width 0.15) (layer "F.Cu") (net 92))
  (segment (start 174.506488 60.325) (end 173.206488 59.025) (width 0.15) (layer "B.Cu") (net 92))
  (segment (start 176.02772 59.420564) (end 176.20272 59.595564) (width 0.15) (layer "B.Cu") (net 92))
  (segment (start 176.20272 59.595564) (end 176.20272 60.033792) (width 0.15) (layer "B.Cu") (net 92))
  (segment (start 173.206488 59.025) (end 171.211512 59.025) (width 0.15) (layer "B.Cu") (net 92))
  (segment (start 176.20272 60.033792) (end 175.911512 60.325) (width 0.15) (layer "B.Cu") (net 92))
  (segment (start 169.709 62.633512) (end 169.47 62.872512) (width 0.15) (layer "B.Cu") (net 92))
  (segment (start 171.211512 59.025) (end 169.709 60.527512) (width 0.15) (layer "B.Cu") (net 92))
  (segment (start 169.47 62.872512) (end 169.222512 62.872512) (width 0.15) (layer "B.Cu") (net 92))
  (segment (start 175.911512 60.325) (end 174.506488 60.325) (width 0.15) (layer "B.Cu") (net 92))
  (segment (start 169.709 60.527512) (end 169.709 62.633512) (width 0.15) (layer "B.Cu") (net 92))
  (segment (start 118.29513 66.952361) (end 118.295129 66.952361) (width 0.15) (layer "F.Cu") (net 93))
  (segment (start 116.984488 68.263) (end 117.411244 67.836244) (width 0.15) (layer "F.Cu") (net 93))
  (segment (start 117.216792 66.563452) (end 117.216792 66.563451) (width 0.15) (layer "F.Cu") (net 93))
  (segment (start 170.275 65.462488) (end 170.275 64.182488) (width 0.15) (layer "F.Cu") (net 93))
  (segment (start 117.216792 66.563451) (end 117.605701 66.95236) (width 0.15) (layer "F.Cu") (net 93))
  (segment (start 171.021 63.8345) (end 171.196 64.0095) (width 0.15) (layer "F.Cu") (net 93))
  (segment (start 114.8745 67.7755) (end 114.8745 66.6255) (width 0.15) (layer "F.Cu") (net 93))
  (segment (start 115.1495 66.6255) (end 115.1495 69.5505) (width 0.15) (layer "F.Cu") (net 93))
  (segment (start 118.295129 66.95236) (end 118.722488 66.525) (width 0.15) (layer "F.Cu") (net 93))
  (segment (start 117.411245 67.146814) (end 117.022337 66.757906) (width 0.15) (layer "F.Cu") (net 93))
  (segment (start 170.622988 63.8345) (end 171.021 63.8345) (width 0.15) (layer "F.Cu") (net 93))
  (segment (start 118.722488 66.525) (end 169.212488 66.525) (width 0.15) (layer "F.Cu") (net 93))
  (segment (start 173.149 63.8345) (end 172.974 64.0095) (width 0.15) (layer "F.Cu") (net 93))
  (segment (start 175.459488 63.8345) (end 173.149 63.8345) (width 0.15) (layer "F.Cu") (net 93))
  (segment (start 113.262 68.723) (end 113.722 68.263) (width 0.15) (layer "F.Cu") (net 93))
  (segment (start 170.275 64.182488) (end 170.622988 63.8345) (width 0.15) (layer "F.Cu") (net 93))
  (segment (start 176.57772 62.716268) (end 175.459488 63.8345) (width 0.15) (layer "F.Cu") (net 93))
  (segment (start 117.022337 66.563452) (end 117.022336 66.563452) (width 0.15) (layer "F.Cu") (net 93))
  (segment (start 116.1245 69.5505) (end 116.1245 68.4005) (width 0.15) (layer "F.Cu") (net 93))
  (segment (start 169.212488 66.525) (end 170.275 65.462488) (width 0.15) (layer "F.Cu") (net 93))
  (segment (start 113.722 68.263) (end 114.387 68.263) (width 0.15) (layer "F.Cu") (net 93))
  (segment (start 117.411244 67.146816) (end 117.411245 67.146814) (width 0.15) (layer "F.Cu") (net 93))
  (segment (start 118.295129 66.952361) (end 118.295129 66.95236) (width 0.15) (layer "F.Cu") (net 93))
  (segment (start 116.262 68.263) (end 116.984488 68.263) (width 0.15) (layer "F.Cu") (net 93))
  (segment (start 176.57772 61.34168) (end 176.57772 62.716268) (width 0.15) (layer "F.Cu") (net 93))
  (via (at 172.974 64.0095) (size 0.5) (drill 0.15) (layers "F.Cu" "B.Cu") (net 93))
  (via (at 171.196 64.0095) (size 0.5) (drill 0.15) (layers "F.Cu" "B.Cu") (net 93))
  (arc (start 117.022337 66.757906) (mid 116.982064 66.660679) (end 117.022337 66.563452) (width 0.15) (layer "F.Cu") (net 93))
  (arc (start 115.637 70.038) (mid 115.981715 69.895215) (end 116.1245 69.5505) (width 0.15) (layer "F.Cu") (net 93))
  (arc (start 116.1245 68.4005) (mid 116.164773 68.303273) (end 116.262 68.263) (width 0.15) (layer "F.Cu") (net 93))
  (arc (start 117.022336 66.563452) (mid 117.119565 66.523178) (end 117.216792 66.563452) (width 0.15) (layer "F.Cu") (net 93))
  (arc (start 114.8745 66.6255) (mid 114.914773 66.528273) (end 115.012 66.488) (width 0.15) (layer "F.Cu") (net 93))
  (arc (start 117.605701 66.95236) (mid 117.950415 67.095146) (end 118.29513 66.952361) (width 0.15) (layer "F.Cu") (net 93))
  (arc (start 114.387 68.263) (mid 114.731715 68.120215) (end 114.8745 67.7755) (width 0.15) (layer "F.Cu") (net 93))
  (arc (start 115.012 66.488) (mid 115.109227 66.528273) (end 115.1495 66.6255) (width 0.15) (layer "F.Cu") (net 93))
  (arc (start 117.411244 67.836244) (mid 117.55403 67.491529) (end 117.411244 67.146816) (width 0.15) (layer "F.Cu") (net 93))
  (arc (start 115.1495 69.5505) (mid 115.292285 69.895215) (end 115.637 70.038) (width 0.15) (layer "F.Cu") (net 93))
  (segment (start 172.974 64.0095) (end 172.799 63.8345) (width 0.15) (layer "B.Cu") (net 93))
  (segment (start 171.371 63.8345) (end 171.196 64.0095) (width 0.15) (layer "B.Cu") (net 93))
  (segment (start 172.799 63.8345) (end 171.371 63.8345) (width 0.15) (layer "B.Cu") (net 93))
  (segment (start 117.252843 61.583744) (end 117.376586 61.459998) (width 0.15) (layer "F.Cu") (net 94))
  (segment (start 119.457512 64.475) (end 168.362488 64.475) (width 0.15) (layer "F.Cu") (net 94))
  (segment (start 117.227747 61.997746) (end 117.229167 61.999167) (width 0.15) (layer "F.Cu") (net 94))
  (segment (start 117.227747 61.997746) (end 117.57104 61.654452) (width 0.15) (layer "F.Cu") (net 94))
  (segment (start 117.568198 61.459998) (end 117.57104 61.46284) (width 0.15) (layer "F.Cu") (net 94))
  (segment (start 116.885873 63.029047) (end 116.888715 63.031889) (width 0.15) (layer "F.Cu") (net 94))
  (segment (start 169.47 63.367488) (end 169.717488 63.367488) (width 0.15) (layer "F.Cu") (net 94))
  (segment (start 118.77454 63.792026) (end 119.457512 64.475) (width 0.15) (layer "F.Cu") (net 94))
  (segment (start 117.229167 61.999167) (end 116.885873 62.342461) (width 0.15) (layer "F.Cu") (net 94))
  (segment (start 176.57772 58.26168) (end 176.57772 59.270564) (width 0.15) (layer "F.Cu") (net 94))
  (segment (start 117.575302 63.031889) (end 117.918595 62.688595) (width 0.15) (layer "F.Cu") (net 94))
  (segment (start 176.57772 59.270564) (end 176.72772 59.420564) (width 0.15) (layer "F.Cu") (net 94))
  (segment (start 117.769755 63.912929) (end 117.772597 63.915771) (width 0.15) (layer "F.Cu") (net 94))
  (segment (start 118.459183 63.915771) (end 118.459184 63.915771) (width 0.15) (layer "F.Cu") (net 94))
  (segment (start 117.769755 63.226343) (end 118.456343 62.539755) (width 0.15) (layer "F.Cu") (net 94))
  (segment (start 115.625512 60.643) (end 116.566255 61.583742) (width 0.15) (layer "F.Cu") (net 94))
  (segment (start 118.453501 62.345301) (end 118.456343 62.348143) (width 0.15) (layer "F.Cu") (net 94))
  (segment (start 118.04234 62.564853) (end 118.261889 62.345301) (width 0.15) (layer "F.Cu") (net 94))
  (segment (start 113.722 60.643) (end 115.625512 60.643) (width 0.15) (layer "F.Cu") (net 94))
  (segment (start 117.918595 62.688595) (end 118.04234 62.564853) (width 0.15) (layer "F.Cu") (net 94))
  (segment (start 168.362488 64.475) (end 169.47 63.367488) (width 0.15) (layer "F.Cu") (net 94))
  (segment (start 118.459184 63.915771) (end 118.582928 63.792026) (width 0.15) (layer "F.Cu") (net 94))
  (segment (start 117.575301 63.031889) (end 117.575302 63.031889) (width 0.15) (layer "F.Cu") (net 94))
  (segment (start 113.262 61.103) (end 113.722 60.643) (width 0.15) (layer "F.Cu") (net 94))
  (via (at 169.717488 63.367488) (size 0.5) (drill 0.15) (layers "F.Cu" "B.Cu") (net 94))
  (via (at 176.72772 59.420564) (size 0.5) (drill 0.15) (layers "F.Cu" "B.Cu") (net 94))
  (arc (start 117.769755 63.226343) (mid 117.627558 63.569636) (end 117.769755 63.912929) (width 0.15) (layer "F.Cu") (net 94))
  (arc (start 117.772597 63.915771) (mid 118.11589 64.057968) (end 118.459183 63.915771) (width 0.15) (layer "F.Cu") (net 94))
  (arc (start 118.582928 63.792026) (mid 118.678734 63.752342) (end 118.77454 63.792026) (width 0.15) (layer "F.Cu") (net 94))
  (arc (start 117.57104 61.46284) (mid 117.610724 61.558646) (end 117.57104 61.654452) (width 0.15) (layer "F.Cu") (net 94))
  (arc (start 118.456343 62.348143) (mid 118.496027 62.443949) (end 118.456343 62.539755) (width 0.15) (layer "F.Cu") (net 94))
  (arc (start 116.885873 62.342461) (mid 116.743676 62.685754) (end 116.885873 63.029047) (width 0.15) (layer "F.Cu") (net 94))
  (arc (start 116.566255 61.583742) (mid 116.90955 61.725941) (end 117.252843 61.583744) (width 0.15) (layer "F.Cu") (net 94))
  (arc (start 117.376586 61.459998) (mid 117.472392 61.420314) (end 117.568198 61.459998) (width 0.15) (layer "F.Cu") (net 94))
  (arc (start 116.888715 63.031889) (mid 117.232008 63.174086) (end 117.575301 63.031889) (width 0.15) (layer "F.Cu") (net 94))
  (arc (start 118.261889 62.345301) (mid 118.357695 62.305617) (end 118.453501 62.345301) (width 0.15) (layer "F.Cu") (net 94))
  (segment (start 176.056488 60.675) (end 174.361512 60.675) (width 0.15) (layer "B.Cu") (net 94))
  (segment (start 170.059 60.672488) (end 170.059 62.778488) (width 0.15) (layer "B.Cu") (net 94))
  (segment (start 173.061512 59.375) (end 171.356488 59.375) (width 0.15) (layer "B.Cu") (net 94))
  (segment (start 171.356488 59.375) (end 170.059 60.672488) (width 0.15) (layer "B.Cu") (net 94))
  (segment (start 169.717488 63.12) (end 169.717488 63.367488) (width 0.15) (layer "B.Cu") (net 94))
  (segment (start 170.059 62.778488) (end 169.717488 63.12) (width 0.15) (layer "B.Cu") (net 94))
  (segment (start 174.361512 60.675) (end 173.061512 59.375) (width 0.15) (layer "B.Cu") (net 94))
  (segment (start 176.55272 60.178768) (end 176.056488 60.675) (width 0.15) (layer "B.Cu") (net 94))
  (segment (start 176.72772 59.420564) (end 176.55272 59.595564) (width 0.15) (layer "B.Cu") (net 94))
  (segment (start 176.55272 59.595564) (end 176.55272 60.178768) (width 0.15) (layer "B.Cu") (net 94))
  (segment (start 158.35 79.975) (end 158.2375 80.0875) (width 0.254) (layer "F.Cu") (net 95))
  (segment (start 159.2 76.8) (end 159.2 75.415) (width 0.254) (layer "F.Cu") (net 95))
  (segment (start 159.2 81.85) (end 158.2375 80.8875) (width 0.2) (layer "F.Cu") (net 95))
  (segment (start 177.031578 91.378422) (end 177.031578 92.207822) (width 0.2) (layer "F.Cu") (net 95))
  (segment (start 158.94 75.155) (end 159.99 75.155) (width 0.2) (layer "F.Cu") (net 95))
  (segment (start 157.5 77.5) (end 158.2 76.8) (width 0.2) (layer "F.Cu") (net 95))
  (segment (start 169.949 85.329) (end 170.496 85.329) (width 0.254) (layer "F.Cu") (net 95))
  (segment (start 168.13225 86.82775) (end 168.38 87.0755) (width 0.2) (layer "F.Cu") (net 95))
  (segment (start 158.2 76.8) (end 159.2 76.8) (width 0.2) (layer "F.Cu") (net 95))
  (segment (start 159.2 75.415) (end 158.93 75.145) (width 0.254) (layer "F.Cu") (net 95))
  (segment (start 170.496 85.329) (end 171.45 84.375) (width 0.254) (layer "F.Cu") (net 95))
  (segment (start 158.93 75.145) (end 158.94 75.155) (width 0.2) (layer "F.Cu") (net 95))
  (segment (start 170.26 90.6) (end 174 90.6) (width 0.2) (layer "F.Cu") (net 95))
  (segment (start 168.38 88.72) (end 170.26 90.6) (width 0.2) (layer "F.Cu") (net 95))
  (segment (start 158.2375 80.8875) (end 157.5 80.15) (width 0.2) (layer "F.Cu") (net 95))
  (segment (start 158.2375 80.0875) (end 158.2375 80.8875) (width 0.254) (layer "F.Cu") (net 95))
  (segment (start 168.38 87.0755) (end 168.38 88.72) (width 0.2) (layer "F.Cu") (net 95))
  (segment (start 159.2 82.55) (end 159.2 81.85) (width 0.2) (layer "F.Cu") (net 95))
  (segment (start 177.031578 92.207822) (end 176.97772 92.26168) (width 0.2) (layer "F.Cu") (net 95))
  (segment (start 157.5 80.15) (end 157.5 77.5) (width 0.2) (layer "F.Cu") (net 95))
  (via (at 168.13225 86.82775) (size 0.5) (drill 0.15) (layers "F.Cu" "B.Cu") (net 95))
  (via (at 158.35 79.975) (size 0.5) (drill 0.15) (layers "F.Cu" "B.Cu") (net 95))
  (via (at 159.2 82.55) (size 0.5) (drill 0.15) (layers "F.Cu" "B.Cu") (net 95))
  (via (at 171.45 84.375) (size 0.5) (drill 0.15) (layers "F.Cu" "B.Cu") (net 95))
  (via (at 174 90.6) (size 0.5) (drill 0.15) (layers "F.Cu" "B.Cu") (net 95))
  (via (at 177.031578 91.378422) (size 0.5) (drill 0.15) (layers "F.Cu" "B.Cu") (net 95))
  (segment (start 173.935 90.665) (end 174 90.6) (width 0.2) (layer "B.Cu") (net 95))
  (segment (start 168.13225 86.82775) (end 166.6545 85.35) (width 0.2) (layer "B.Cu") (net 95))
  (segment (start 160.525 77.8) (end 158.35 79.975) (width 0.254) (layer "B.Cu") (net 95))
  (segment (start 173.935 91.686752) (end 173.935 90.665) (width 0.2) (layer "B.Cu") (net 95))
  (segment (start 161.15 85.35) (end 159.2 83.4) (width 0.2) (layer "B.Cu") (net 95))
  (segment (start 160.575 77.8) (end 160.525 77.8) (width 0.254) (layer "B.Cu") (net 95))
  (segment (start 171.45 81.175) (end 168.1 77.825) (width 0.254) (layer "B.Cu") (net 95))
  (segment (start 168.1 77.825) (end 160.6 77.825) (width 0.254) (layer "B.Cu") (net 95))
  (segment (start 176.445 91.965) (end 174.213248 91.965) (width 0.2) (layer "B.Cu") (net 95))
  (segment (start 166.6545 85.35) (end 161.15 85.35) (width 0.2) (layer "B.Cu") (net 95))
  (segment (start 160.6 77.825) (end 160.575 77.8) (width 0.254) (layer "B.Cu") (net 95))
  (segment (start 174.213248 91.965) (end 173.935 91.686752) (width 0.2) (layer "B.Cu") (net 95))
  (segment (start 177.031578 91.378422) (end 176.445 91.965) (width 0.2) (layer "B.Cu") (net 95))
  (segment (start 171.45 84.375) (end 171.45 81.175) (width 0.254) (layer "B.Cu") (net 95))
  (segment (start 159.2 83.4) (end 159.2 82.55) (width 0.2) (layer "B.Cu") (net 95))
  (segment (start 186.075 93.925) (end 184.2 95.8) (width 0.2) (layer "F.Cu") (net 96))
  (segment (start 184.2 95.8) (end 177.43604 95.8) (width 0.2) (layer "F.Cu") (net 96))
  (segment (start 177.43604 95.8) (end 176.97772 95.34168) (width 0.2) (layer "F.Cu") (net 96))
  (via (at 186.075 93.925) (size 0.5) (drill 0.15) (layers "F.Cu" "B.Cu") (net 96))
  (segment (start 186.075 93.925) (end 185.05 93.925) (width 0.2) (layer "B.Cu") (net 96))
  (segment (start 182.71 73.4) (end 179.734 73.4) (width 0.2) (layer "B.Cu") (net 96))
  (segment (start 176.07 71.836) (end 177.611 73.377) (width 0.2) (layer "B.Cu") (net 96))
  (segment (start 183.56 87.596719) (end 183.56 74.25) (width 0.2) (layer "B.Cu") (net 96))
  (segment (start 182.9 91.775) (end 182.9 88.256719) (width 0.2) (layer "B.Cu") (net 96))
  (segment (start 176.07 70.846) (end 176.07 71.836) (width 0.2) (layer "B.Cu") (net 96))
  (segment (start 177.611 73.377) (end 179.764 73.377) (width 0.2) (layer "B.Cu") (net 96))
  (segment (start 185.05 93.925) (end 182.9 91.775) (width 0.2) (layer "B.Cu") (net 96))
  (segment (start 182.9 88.256719) (end 183.56 87.596719) (width 0.2) (layer "B.Cu") (net 96))
  (segment (start 183.56 74.25) (end 182.71 73.4) (width 0.2) (layer "B.Cu") (net 96))
  (segment (start 176.57772 92.26168) (end 176.57772 90.23528) (width 0.15) (layer "F.Cu") (net 97))
  (segment (start 176.57772 90.23528) (end 176.951 89.862) (width 0.15) (layer "F.Cu") (net 97))
  (segment (start 176.17772 90.23172) (end 175.808 89.862) (width 0.15) (layer "F.Cu") (net 98))
  (segment (start 176.17772 92.26168) (end 176.17772 90.23172) (width 0.15) (layer "F.Cu") (net 98))
  (segment (start 175.099989 90.570011) (end 175.099989 91.489989) (width 0.2) (layer "F.Cu") (net 99))
  (segment (start 175.1 90.57) (end 175.099989 90.570011) (width 0.2) (layer "F.Cu") (net 99))
  (segment (start 175.37772 91.76772) (end 175.37772 92.26168) (width 0.2) (layer "F.Cu") (net 99))
  (segment (start 175.099989 91.489989) (end 175.37772 91.76772) (width 0.2) (layer "F.Cu") (net 99))
  (via (at 175.1 90.57) (size 0.5) (drill 0.15) (layers "F.Cu" "B.Cu") (net 99))
  (segment (start 183.198 74.488) (end 182.587 73.877) (width 0.2) (layer "B.Cu") (net 99))
  (segment (start 175.1 90.57) (end 180.08 90.57) (width 0.2) (layer "B.Cu") (net 99))
  (segment (start 182.587 73.877) (end 176.761 73.877) (width 0.2) (layer "B.Cu") (net 99))
  (segment (start 174.546 71.662) (end 174.546 70.846) (width 0.2) (layer "B.Cu") (net 99))
  (segment (start 176.761 73.877) (end 174.546 71.662) (width 0.2) (layer "B.Cu") (net 99))
  (segment (start 183.198 87.452) (end 183.198 74.488) (width 0.2) (layer "B.Cu") (net 99))
  (segment (start 180.08 90.57) (end 183.198 87.452) (width 0.2) (layer "B.Cu") (net 99))
  (segment (start 175.36772 95.876681) (end 175.36772 95.963436) (width 0.18) (layer "F.Cu") (net 100))
  (segment (start 175.37772 95.34168) (end 175.37772 95.866681) (width 0.18) (layer "F.Cu") (net 100))
  (segment (start 175.37772 95.866681) (end 175.36772 95.876681) (width 0.18) (layer "F.Cu") (net 100))
  (segment (start 175.36772 95.963436) (end 175.52772 96.123436) (width 0.18) (layer "F.Cu") (net 100))
  (via (at 175.52772 96.123436) (size 0.5) (drill 0.15) (layers "F.Cu" "B.Cu") (net 100))
  (segment (start 186.413102 95.4146) (end 192.082586 89.745116) (width 0.18) (layer "B.Cu") (net 100))
  (segment (start 192.082586 74.888884) (end 189.880702 72.687) (width 0.18) (layer "B.Cu") (net 100))
  (segment (start 175.36772 95.963436) (end 175.36772 95.868182) (width 0.18) (layer "B.Cu") (net 100))
  (segment (start 175.821302 95.4146) (end 186.413102 95.4146) (width 0.18) (layer "B.Cu") (net 100))
  (segment (start 189.880702 72.687) (end 187.999 72.687) (width 0.18) (layer "B.Cu") (net 100))
  (segment (start 192.082586 89.745116) (end 192.082586 74.888884) (width 0.18) (layer "B.Cu") (net 100))
  (segment (start 175.52772 96.123436) (end 175.36772 95.963436) (width 0.18) (layer "B.Cu") (net 100))
  (segment (start 175.36772 95.868182) (end 175.821302 95.4146) (width 0.18) (layer "B.Cu") (net 100))
  (segment (start 174.97772 95.34168) (end 174.97772 95.866681) (width 0.18) (layer "F.Cu") (net 102))
  (segment (start 174.97772 95.866681) (end 174.98772 95.876681) (width 0.18) (layer "F.Cu") (net 102))
  (segment (start 174.98772 95.876681) (end 174.98772 95.963436) (width 0.18) (layer "F.Cu") (net 102))
  (segment (start 174.98772 95.963436) (end 174.82772 96.123436) (width 0.18) (layer "F.Cu") (net 102))
  (via (at 174.82772 96.123436) (size 0.5) (drill 0.15) (layers "F.Cu" "B.Cu") (net 102))
  (segment (start 186.255698 95.0346) (end 178.6046 95.0346) (width 0.18) (layer "B.Cu") (net 102))
  (segment (start 190.354407 73.698108) (end 190.434545 73.778247) (width 0.18) (layer "B.Cu") (net 102))
  (segment (start 190.116346 73.698108) (end 190.116347 73.698108) (width 0.18) (layer "B.Cu") (net 102))
  (segment (start 174.98772 95.710778) (end 174.98772 95.963436) (width 0.18) (layer "B.Cu") (net 102))
  (segment (start 191.702586 75.046288) (end 191.702586 89.587712) (width 0.18) (layer "B.Cu") (net 102))
  (segment (start 178.3046 94.7346) (end 178.2546 94.7346) (width 0.18) (layer "B.Cu") (net 102))
  (segment (start 175.663898 95.0346) (end 174.98772 95.710778) (width 0.18) (layer "B.Cu") (net 102))
  (segment (start 190.434545 73.778247) (end 191.702586 75.046288) (width 0.18) (layer "B.Cu") (net 102))
  (segment (start 177.9546 95.0346) (end 175.663898 95.0346) (width 0.18) (layer "B.Cu") (net 102))
  (segment (start 189.723298 73.067) (end 189.798149 73.141851) (width 0.18) (layer "B.Cu") (net 102))
  (segment (start 191.702586 89.587712) (end 186.255698 95.0346) (width 0.18) (layer "B.Cu") (net 102))
  (segment (start 187.999 73.067) (end 189.723298 73.067) (width 0.18) (layer "B.Cu") (net 102))
  (segment (start 189.798148 73.379912) (end 189.798149 73.379911) (width 0.18) (layer "B.Cu") (net 102))
  (segment (start 189.798149 73.617971) (end 189.878286 73.698108) (width 0.18) (layer "B.Cu") (net 102))
  (segment (start 174.98772 95.963436) (end 174.82772 96.123436) (width 0.18) (layer "B.Cu") (net 102))
  (arc (start 178.2546 94.7346) (mid 178.148534 94.778534) (end 178.1046 94.8846) (width 0.18) (layer "B.Cu") (net 102))
  (arc (start 189.798149 73.141851) (mid 189.847453 73.260882) (end 189.798148 73.379912) (width 0.18) (layer "B.Cu") (net 102))
  (arc (start 189.878286 73.698108) (mid 189.997316 73.747412) (end 190.116346 73.698108) (width 0.18) (layer "B.Cu") (net 102))
  (arc (start 178.4546 94.8846) (mid 178.410666 94.778534) (end 178.3046 94.7346) (width 0.18) (layer "B.Cu") (net 102))
  (arc (start 178.6046 95.0346) (mid 178.498534 94.990666) (end 178.4546 94.8846) (width 0.18) (layer "B.Cu") (net 102))
  (arc (start 190.116347 73.698108) (mid 190.235377 73.648804) (end 190.354407 73.698108) (width 0.18) (layer "B.Cu") (net 102))
  (arc (start 189.798149 73.379911) (mid 189.748845 73.498941) (end 189.798149 73.617971) (width 0.18) (layer "B.Cu") (net 102))
  (arc (start 178.1046 94.8846) (mid 178.060666 94.990666) (end 177.9546 95.0346) (width 0.18) (layer "B.Cu") (net 102))
  (segment (start 183.3995 77.2) (end 182.2895 78.31) (width 0.2) (layer "F.Cu") (net 125))
  (segment (start 197.2 76.757948) (end 196.757948 77.2) (width 0.18) (layer "F.Cu") (net 125))
  (segment (start 182.09 82.2545) (end 182.09 82.88) (width 0.2) (layer "F.Cu") (net 125))
  (segment (start 182.09 82.88) (end 179.9805 84.9895) (width 0.2) (layer "F.Cu") (net 125))
  (segment (start 196.757948 77.2) (end 183.3995 77.2) (width 0.2) (layer "F.Cu") (net 125))
  (segment (start 167.5 90.76) (end 166.97772 91.28228) (width 0.2) (layer "F.Cu") (net 125))
  (segment (start 166.97772 91.28228) (end 166.97772 92.26168) (width 0.2) (layer "F.Cu") (net 125))
  (segment (start 179.9805 84.9895) (end 179.9805 89.9105) (width 0.2) (layer "F.Cu") (net 125))
  (via (at 182.09 82.2545) (size 0.5) (drill 0.15) (layers "F.Cu" "B.Cu") (net 125))
  (via (at 179.9805 89.9105) (size 0.5) (drill 0.15) (layers "F.Cu" "B.Cu") (net 125))
  (via (at 197.2 76.757948) (size 0.5) (drill 0.15) (layers "F.Cu" "B.Cu") (net 125))
  (via (at 167.5 90.76) (size 0.5) (drill 0.15) (layers "F.Cu" "B.Cu") (net 125))
  (via (at 182.2895 78.31) (size 0.5) (drill 0.15) (layers "F.Cu" "B.Cu") (net 125))
  (segment (start 167.5 90.76) (end 168.26 90) (width 0.2) (layer "B.Cu") (net 125))
  (segment (start 168.26 90) (end 179.891 90) (width 0.2) (layer "B.Cu") (net 125))
  (segment (start 197.27085 76.757948) (end 197.461902 76.949) (width 0.18) (layer "B.Cu") (net 125))
  (segment (start 182.18 82.1645) (end 182.09 82.2545) (width 0.2) (layer "B.Cu") (net 125))
  (segment (start 182.2895 78.31) (end 182.18 78.4195) (width 0.2) (layer "B.Cu") (net 125))
  (segment (start 197.2 76.757948) (end 197.27085 76.757948) (width 0.2) (layer "B.Cu") (net 125))
  (segment (start 179.891 90) (end 179.9805 89.9105) (width 0.2) (layer "B.Cu") (net 125))
  (segment (start 182.18 78.4195) (end 182.18 82.1645) (width 0.2) (layer "B.Cu") (net 125))
  (segment (start 197.461902 76.949) (end 198.581 76.949) (width 0.18) (layer "B.Cu") (net 125))
  (segment (start 197.086221 77.66) (end 183.69 77.66) (width 0.2) (layer "F.Cu") (net 127))
  (segment (start 166.57772 90.63128) (end 166.684 90.525) (width 0.2) (layer "F.Cu") (net 127))
  (segment (start 197.297221 77.449) (end 197.086221 77.66) (width 0.18) (layer "F.Cu") (net 127))
  (segment (start 180.45 88.997999) (end 180.6695 89.217499) (width 0.2) (layer "F.Cu") (net 127))
  (segment (start 166.57772 92.26168) (end 166.57772 90.63128) (width 0.2) (layer "F.Cu") (net 127))
  (segment (start 183.69 77.66) (end 182.67 78.68) (width 0.2) (layer "F.Cu") (net 127))
  (segment (start 180.45 85.23) (end 180.45 88.997999) (width 0.2) (layer "F.Cu") (net 127))
  (segment (start 182.71 82.86) (end 182.71 82.97) (width 0.2) (layer "F.Cu") (net 127))
  (segment (start 182.71 82.97) (end 180.45 85.23) (width 0.2) (layer "F.Cu") (net 127))
  (segment (start 182.67 78.68) (end 182.67 78.97) (width 0.2) (layer "F.Cu") (net 127))
  (via (at 182.71 82.86) (size 0.5) (drill 0.15) (layers "F.Cu" "B.Cu") (net 127))
  (via (at 197.297221 77.449) (size 0.5) (drill 0.15) (layers "F.Cu" "B.Cu") (net 127))
  (via (at 182.67 78.97) (size 0.5) (drill 0.15) (layers "F.Cu" "B.Cu") (net 127))
  (via (at 166.684 90.525) (size 0.5) (drill 0.15) (layers "F.Cu" "B.Cu") (net 127))
  (via (at 180.6695 89.217499) (size 0.5) (drill 0.15) (layers "F.Cu" "B.Cu") (net 127))
  (segment (start 182.71 82.86) (end 182.71 79.01) (width 0.2) (layer "B.Cu") (net 127))
  (segment (start 167.859 89.35) (end 180.536999 89.35) (width 0.2) (layer "B.Cu") (net 127))
  (segment (start 182.71 79.01) (end 182.67 78.97) (width 0.2) (layer "B.Cu") (net 127))
  (segment (start 197.297221 77.449) (end 198.581 77.449) (width 0.2) (layer "B.Cu") (net 127))
  (segment (start 180.536999 89.35) (end 180.6695 89.217499) (width 0.2) (layer "B.Cu") (net 127))
  (segment (start 167.859 89.35) (end 166.684 90.525) (width 0.2) (layer "B.Cu") (net 127))
  (segment (start 163.762894 82.45959) (end 163.762895 82.459592) (width 0.15) (layer "F.Cu") (net 142))
  (segment (start 160.97772 93.591) (end 161.12772 93.441) (width 0.15) (layer "F.Cu") (net 142))
  (segment (start 163.762895 82.459592) (end 163.762895 82.459591) (width 0.15) (layer "F.Cu") (net 142))
  (segment (start 162.260667 84.687353) (end 161.995126 84.421812) (width 0.15) (layer "F.Cu") (net 142))
  (segment (start 173.514999 72.707488) (end 194.537488 72.707488) (width 0.15) (layer "F.Cu") (net 142))
  (segment (start 163.144551 83.803469) (end 162.87901 83.537928) (width 0.15) (layer "F.Cu") (net 142))
  (segment (start 163.073466 83.343475) (end 163.339006 83.609015) (width 0.15) (layer "F.Cu") (net 142))
  (segment (start 163.144552 84.492899) (end 163.144551 84.492899) (width 0.15) (layer "F.Cu") (net 142))
  (segment (start 162.87901 83.343474) (end 162.879011 83.343476) (width 0.15) (layer "F.Cu") (net 142))
  (segment (start 160.97772 95.34168) (end 160.97772 93.591) (width 0.15) (layer "F.Cu") (net 142))
  (segment (start 160.95272 85.269768) (end 161.111243 85.111243) (width 0.15) (layer "F.Cu") (net 142))
  (segment (start 162.879011 83.343476) (end 162.879011 83.343475) (width 0.15) (layer "F.Cu") (net 142))
  (segment (start 164.91232 82.725131) (end 164.912319 82.725131) (width 0.15) (layer "F.Cu") (net 142))
  (segment (start 164.028435 82.919585) (end 163.762894 82.654044) (width 0.15) (layer "F.Cu") (net 142))
  (segment (start 160.95272 89.6465) (end 160.95272 85.269768) (width 0.15) (layer "F.Cu") (net 142))
  (segment (start 163.95735 82.459591) (end 164.22289 82.725131) (width 0.15) (layer "F.Cu") (net 142))
  (segment (start 162.189582 84.227359) (end 162.455122 84.492899) (width 0.15) (layer "F.Cu") (net 142))
  (segment (start 164.646779 81.575708) (end 173.514999 72.707488) (width 0.15) (layer "F.Cu") (net 142))
  (segment (start 161.995127 84.22736) (end 161.995127 84.227359) (width 0.15) (layer "F.Cu") (net 142))
  (segment (start 164.912319 82.035701) (end 164.646778 81.77016) (width 0.15) (layer "F.Cu") (net 142))
  (segment (start 161.12772 89.8215) (end 160.95272 89.6465) (width 0.15) (layer "F.Cu") (net 142))
  (segment (start 164.028436 83.609015) (end 164.028435 83.609015) (width 0.15) (layer "F.Cu") (net 142))
  (segment (start 161.995126 84.227358) (end 161.995127 84.22736) (width 0.15) (layer "F.Cu") (net 142))
  (segment (start 164.646778 81.575706) (end 164.646779 81.575708) (width 0.15) (layer "F.Cu") (net 142))
  (segment (start 161.305697 85.111243) (end 161.305698 85.111243) (width 0.15) (layer "F.Cu") (net 142))
  (segment (start 163.073465 83.343475) (end 163.073466 83.343475) (width 0.15) (layer "F.Cu") (net 142))
  (segment (start 162.189581 84.227359) (end 162.189582 84.227359) (width 0.15) (layer "F.Cu") (net 142))
  (segment (start 161.305698 85.111243) (end 161.571238 85.376783) (width 0.15) (layer "F.Cu") (net 142))
  (segment (start 163.957349 82.459591) (end 163.95735 82.459591) (width 0.15) (layer "F.Cu") (net 142))
  (segment (start 162.260668 85.376783) (end 162.260667 85.376783) (width 0.15) (layer "F.Cu") (net 142))
  (via (at 194.537488 72.707488) (size 0.5) (drill 0.15) (layers "F.Cu" "B.Cu") (net 142))
  (via (at 161.12772 93.441) (size 0.5) (drill 0.15) (layers "F.Cu" "B.Cu") (net 142))
  (via (at 161.12772 89.8215) (size 0.5) (drill 0.15) (layers "F.Cu" "B.Cu") (net 142))
  (arc (start 164.028435 83.609015) (mid 164.171221 83.2643) (end 164.028435 82.919585) (width 0.15) (layer "F.Cu") (net 142))
  (arc (start 163.762894 82.654044) (mid 163.722621 82.556817) (end 163.762894 82.45959) (width 0.15) (layer "F.Cu") (net 142))
  (arc (start 161.111243 85.111243) (mid 161.20847 85.07097) (end 161.305697 85.111243) (width 0.15) (layer "F.Cu") (net 142))
  (arc (start 161.571238 85.376783) (mid 161.915953 85.519569) (end 162.260668 85.376783) (width 0.15) (layer "F.Cu") (net 142))
  (arc (start 164.912319 82.725131) (mid 165.055105 82.380416) (end 164.912319 82.035701) (width 0.15) (layer "F.Cu") (net 142))
  (arc (start 161.995126 84.421812) (mid 161.954853 84.324585) (end 161.995126 84.227358) (width 0.15) (layer "F.Cu") (net 142))
  (arc (start 164.646778 81.77016) (mid 164.606505 81.672933) (end 164.646778 81.575706) (width 0.15) (layer "F.Cu") (net 142))
  (arc (start 164.22289 82.725131) (mid 164.567605 82.867917) (end 164.91232 82.725131) (width 0.15) (layer "F.Cu") (net 142))
  (arc (start 162.260667 85.376783) (mid 162.403453 85.032068) (end 162.260667 84.687353) (width 0.15) (layer "F.Cu") (net 142))
  (arc (start 161.995127 84.227359) (mid 162.092354 84.187086) (end 162.189581 84.227359) (width 0.15) (layer "F.Cu") (net 142))
  (arc (start 162.879011 83.343475) (mid 162.976238 83.303202) (end 163.073465 83.343475) (width 0.15) (layer "F.Cu") (net 142))
  (arc (start 162.87901 83.537928) (mid 162.838737 83.440701) (end 162.87901 83.343474) (width 0.15) (layer "F.Cu") (net 142))
  (arc (start 163.144551 84.492899) (mid 163.287337 84.148184) (end 163.144551 83.803469) (width 0.15) (layer "F.Cu") (net 142))
  (arc (start 162.455122 84.492899) (mid 162.799837 84.635685) (end 163.144552 84.492899) (width 0.15) (layer "F.Cu") (net 142))
  (arc (start 163.339006 83.609015) (mid 163.683721 83.751801) (end 164.028436 83.609015) (width 0.15) (layer "F.Cu") (net 142))
  (arc (start 163.762895 82.459591) (mid 163.860122 82.419318) (end 163.957349 82.459591) (width 0.15) (layer "F.Cu") (net 142))
  (segment (start 197.831 81.45) (end 197.756 81.525) (width 0.15) (layer "B.Cu") (net 142))
  (segment (start 197.756 81.525) (end 195.785 81.525) (width 0.15) (layer "B.Cu") (net 142))
  (segment (start 194.225 81.257512) (end 194.225 72.772488) (width 0.15) (layer "B.Cu") (net 142))
  (segment (start 194.225 72.772488) (end 194.29 72.707488) (width 0.15) (layer "B.Cu") (net 142))
  (segment (start 195.502366 81.242366) (end 195.335 81.242366) (width 0.15) (layer "B.Cu") (net 142))
  (segment (start 160.95272 93.266) (end 161.12772 93.441) (width 0.15) (layer "B.Cu") (net 142))
  (segment (start 194.492488 81.525) (end 194.225 81.257512) (width 0.15) (layer "B.Cu") (net 142))
  (segment (start 160.95272 89.9965) (end 160.95272 93.266) (width 0.15) (layer "B.Cu") (net 142))
  (segment (start 161.12772 89.8215) (end 160.95272 89.9965) (width 0.15) (layer "B.Cu") (net 142))
  (segment (start 194.29 72.707488) (end 194.537488 72.707488) (width 0.15) (layer "B.Cu") (net 142))
  (segment (start 194.492488 81.525) (end 195.052366 81.525) (width 0.15) (layer "B.Cu") (net 142))
  (segment (start 198.581 81.45) (end 197.831 81.45) (width 0.15) (layer "B.Cu") (net 142))
  (arc (start 195.643683 81.383683) (mid 195.602292 81.283757) (end 195.502366 81.242366) (width 0.15) (layer "B.Cu") (net 142))
  (arc (start 195.785 81.525) (mid 195.685074 81.483609) (end 195.643683 81.383683) (width 0.15) (layer "B.Cu") (net 142))
  (arc (start 195.193683 81.383683) (mid 195.152292 81.483609) (end 195.052366 81.525) (width 0.15) (layer "B.Cu") (net 142))
  (arc (start 195.335 81.242366) (mid 195.235074 81.283757) (end 195.193683 81.383683) (width 0.15) (layer "B.Cu") (net 142))
  (segment (start 173.370021 72.357488) (end 193.897536 72.357488) (width 0.15) (layer "F.Cu") (net 144))
  (segment (start 163.320953 83.095988) (end 163.586493 83.361528) (width 0.15) (layer "F.Cu") (net 144))
  (segment (start 160.57772 93.591) (end 160.42772 93.441) (width 0.15) (layer "F.Cu") (net 144))
  (segment (start 162.013179 84.934841) (end 161.747638 84.6693) (width 0.15) (layer "F.Cu") (net 144))
  (segment (start 164.39929 81.328219) (end 164.957185 80.770327) (width 0.15) (layer "F.Cu") (net 144))
  (segment (start 161.553185 84.863756) (end 161.818725 85.129296) (width 0.15) (layer "F.Cu") (net 144))
  (segment (start 164.957185 80.770327) (end 173.370021 72.357491) (width 0.15) (layer "F.Cu") (net 144))
  (segment (start 160.60272 85.124792) (end 160.863756 84.863756) (width 0.15) (layer "F.Cu") (net 144))
  (segment (start 161.747638 83.979871) (end 161.74764 83.979872) (width 0.15) (layer "F.Cu") (net 144))
  (segment (start 163.780947 83.167072) (end 163.780947 83.167073) (width 0.15) (layer "F.Cu") (net 144))
  (segment (start 164.664831 82.283188) (end 164.664831 82.283189) (width 0.15) (layer "F.Cu") (net 144))
  (segment (start 160.57772 95.34168) (end 160.57772 93.591) (width 0.15) (layer "F.Cu") (net 144))
  (segment (start 162.897063 84.050957) (end 162.631522 83.785416) (width 0.15) (layer "F.Cu") (net 144))
  (segment (start 164.664831 82.283189) (end 164.39929 82.017648) (width 0.15) (layer "F.Cu") (net 144))
  (segment (start 163.320952 83.095988) (end 163.320953 83.095988) (width 0.15) (layer "F.Cu") (net 144))
  (segment (start 160.42772 89.8215) (end 160.60272 89.6465) (width 0.15) (layer "F.Cu") (net 144))
  (segment (start 161.553184 84.863756) (end 161.553185 84.863756) (width 0.15) (layer "F.Cu") (net 144))
  (segment (start 162.897063 84.050956) (end 162.897063 84.050957) (width 0.15) (layer "F.Cu") (net 144))
  (segment (start 161.747638 83.97987) (end 161.747638 83.979871) (width 0.15) (layer "F.Cu") (net 144))
  (segment (start 162.631522 83.095987) (end 162.631524 83.095988) (width 0.15) (layer "F.Cu") (net 144))
  (segment (start 162.631522 83.095986) (end 162.631522 83.095987) (width 0.15) (layer "F.Cu") (net 144))
  (segment (start 162.437069 83.979872) (end 162.702609 84.245412) (width 0.15) (layer "F.Cu") (net 144))
  (segment (start 164.39929 81.328218) (end 164.39929 81.328219) (width 0.15) (layer "F.Cu") (net 144))
  (segment (start 164.204836 82.212104) (end 164.204837 82.212104) (width 0.15) (layer "F.Cu") (net 144))
  (segment (start 163.780947 83.167073) (end 163.515406 82.901532) (width 0.15) (layer "F.Cu") (net 144))
  (segment (start 164.204837 82.212104) (end 164.470377 82.477644) (width 0.15) (layer "F.Cu") (net 144))
  (segment (start 162.437068 83.979872) (end 162.437069 83.979872) (width 0.15) (layer "F.Cu") (net 144))
  (segment (start 163.515406 82.212102) (end 163.515406 82.212103) (width 0.15) (layer "F.Cu") (net 144))
  (segment (start 163.515406 82.212103) (end 163.515408 82.212104) (width 0.15) (layer "F.Cu") (net 144))
  (segment (start 162.013179 84.93484) (end 162.013179 84.934841) (width 0.15) (layer "F.Cu") (net 144))
  (segment (start 160.60272 89.6465) (end 160.60272 85.124792) (width 0.15) (layer "F.Cu") (net 144))
  (segment (start 193.897536 72.357488) (end 194.042512 72.212512) (width 0.15) (layer "F.Cu") (net 144))
  (segment (start 173.370021 72.357491) (end 173.370021 72.357488) (width 0.15) (layer "F.Cu") (net 144))
  (via (at 160.42772 93.441) (size 0.5) (drill 0.15) (layers "F.Cu" "B.Cu") (net 144))
  (via (at 194.042512 72.212512) (size 0.5) (drill 0.15) (layers "F.Cu" "B.Cu") (net 144))
  (via (at 160.42772 89.8215) (size 0.5) (drill 0.15) (layers "F.Cu" "B.Cu") (net 144))
  (arc (start 161.747638 84.6693) (mid 161.604852 84.324585) (end 161.747638 83.97987) (width 0.15) (layer "F.Cu") (net 144))
  (arc (start 162.897063 84.245412) (mid 162.937336 84.148184) (end 162.897063 84.050956) (width 0.15) (layer "F.Cu") (net 144))
  (arc (start 162.631524 83.095988) (mid 162.976238 82.953203) (end 163.320952 83.095988) (width 0.15) (layer "F.Cu") (net 144))
  (arc (start 164.470377 82.477644) (mid 164.567604 82.517917) (end 164.664831 82.477644) (width 0.15) (layer "F.Cu") (net 144))
  (arc (start 163.586493 83.361528) (mid 163.68372 83.401801) (end 163.780947 83.361528) (width 0.15) (layer "F.Cu") (net 144))
  (arc (start 161.74764 83.979872) (mid 162.092354 83.837087) (end 162.437068 83.979872) (width 0.15) (layer "F.Cu") (net 144))
  (arc (start 162.013179 85.129296) (mid 162.053452 85.032068) (end 162.013179 84.93484) (width 0.15) (layer "F.Cu") (net 144))
  (arc (start 161.818725 85.129296) (mid 161.915952 85.169569) (end 162.013179 85.129296) (width 0.15) (layer "F.Cu") (net 144))
  (arc (start 163.515406 82.901532) (mid 163.37262 82.556817) (end 163.515406 82.212102) (width 0.15) (layer "F.Cu") (net 144))
  (arc (start 160.863756 84.863756) (mid 161.20847 84.720971) (end 161.553184 84.863756) (width 0.15) (layer "F.Cu") (net 144))
  (arc (start 162.702609 84.245412) (mid 162.799836 84.285685) (end 162.897063 84.245412) (width 0.15) (layer "F.Cu") (net 144))
  (arc (start 164.664831 82.477644) (mid 164.705104 82.380416) (end 164.664831 82.283188) (width 0.15) (layer "F.Cu") (net 144))
  (arc (start 163.515408 82.212104) (mid 163.860122 82.069319) (end 164.204836 82.212104) (width 0.15) (layer "F.Cu") (net 144))
  (arc (start 163.780947 83.361528) (mid 163.82122 83.2643) (end 163.780947 83.167072) (width 0.15) (layer "F.Cu") (net 144))
  (arc (start 164.39929 82.017648) (mid 164.256504 81.672933) (end 164.39929 81.328218) (width 0.15) (layer "F.Cu") (net 144))
  (arc (start 162.631522 83.785416) (mid 162.488736 83.440701) (end 162.631522 83.095986) (width 0.15) (layer "F.Cu") (net 144))
  (segment (start 160.60272 89.9965) (end 160.60272 93.266) (width 0.15) (layer "B.Cu") (net 144))
  (segment (start 193.875 72.627512) (end 194.042512 72.46) (width 0.15) (layer "B.Cu") (net 144))
  (segment (start 193.875 81.402488) (end 193.875 72.627512) (width 0.15) (layer "B.Cu") (net 144))
  (segment (start 197.756 81.875) (end 194.347512 81.875) (width 0.15) (layer "B.Cu") (net 144))
  (segment (start 194.347512 81.875) (end 193.875 81.402488) (width 0.15) (layer "B.Cu") (net 144))
  (segment (start 197.831 81.95) (end 197.756 81.875) (width 0.15) (layer "B.Cu") (net 144))
  (segment (start 194.042512 72.46) (end 194.042512 72.212512) (width 0.15) (layer "B.Cu") (net 144))
  (segment (start 160.42772 89.8215) (end 160.60272 89.9965) (width 0.15) (layer "B.Cu") (net 144))
  (segment (start 160.60272 93.266) (end 160.42772 93.441) (width 0.15) (layer "B.Cu") (net 144))
  (segment (start 181.47 82.75) (end 181.41 82.75) (width 0.2) (layer "F.Cu") (net 151))
  (segment (start 182.99 76.74) (end 181.63 78.1) (width 0.2) (layer "F.Cu") (net 151))
  (segment (start 181.63 78.94) (end 181.61 78.96) (width 0.2) (layer "F.Cu") (net 151))
  (segment (start 179.4695 84.6905) (end 179.4695 91.4) (width 0.2) (layer "F.Cu") (net 151))
  (segment (start 197.2 76.093974) (end 196.553974 76.74) (width 0.18) (layer "F.Cu") (net 151))
  (segment (start 181.41 82.75) (end 179.4695 84.6905) (width 0.2) (layer "F.Cu") (net 151))
  (segment (start 157.37772 93.11872) (end 157.384 93.125) (width 0.2) (layer "F.Cu") (net 151))
  (segment (start 181.63 78.1) (end 181.63 78.94) (width 0.2) (layer "F.Cu") (net 151))
  (segment (start 196.553974 76.74) (end 182.99 76.74) (width 0.2) (layer "F.Cu") (net 151))
  (segment (start 157.37772 92.26168) (end 157.37772 93.11872) (width 0.2) (layer "F.Cu") (net 151))
  (via (at 197.2 76.093974) (size 0.5) (drill 0.15) (layers "F.Cu" "B.Cu") (net 151))
  (via (at 181.61 78.96) (size 0.5) (drill 0.15) (layers "F.Cu" "B.Cu") (net 151))
  (via (at 157.384 93.125) (size 0.5) (drill 0.15) (layers "F.Cu" "B.Cu") (net 151))
  (via (at 181.47 82.75) (size 0.5) (drill 0.15) (layers "F.Cu" "B.Cu") (net 151))
  (via (at 179.4695 91.4) (size 0.5) (drill 0.15) (layers "F.Cu" "B.Cu") (net 151))
  (segment (start 178.2445 92.625) (end 179.4695 91.4) (width 0.2) (layer "B.Cu") (net 151))
  (segment (start 181.6 78.97) (end 181.6 82.62) (width 0.2) (layer "B.Cu") (net 151))
  (segment (start 158.984 94.725) (end 163.984 94.725) (width 0.2) (layer "B.Cu") (net 151))
  (segment (start 163.984 94.725) (end 166.084 92.625) (width 0.2) (layer "B.Cu") (net 151))
  (segment (start 181.61 78.96) (end 181.6 78.97) (width 0.2) (layer "B.Cu") (net 151))
  (segment (start 197.2 76.093974) (end 197.556026 76.45) (width 0.18) (layer "B.Cu") (net 151))
  (segment (start 197.556026 76.45) (end 198.581 76.45) (width 0.18) (layer "B.Cu") (net 151))
  (segment (start 166.084 92.625) (end 178.2445 92.625) (width 0.2) (layer "B.Cu") (net 151))
  (segment (start 157.384 93.125) (end 158.984 94.725) (width 0.2) (layer "B.Cu") (net 151))
  (segment (start 181.6 82.62) (end 181.47 82.75) (width 0.2) (layer "B.Cu") (net 151))
  (segment (start 197.2 75.43) (end 196.32 76.31) (width 0.18) (layer "F.Cu") (net 152))
  (segment (start 178.93 92.53) (end 179 92.6) (width 0.2) (layer "F.Cu") (net 152))
  (segment (start 181.07 82.2545) (end 181.07 82.33) (width 0.2) (layer "F.Cu") (net 152))
  (segment (start 181.07 82.33) (end 178.93 84.47) (width 0.2) (layer "F.Cu") (net 152))
  (segment (start 182.69 76.31) (end 196.32 76.31) (width 0.2) (layer "F.Cu") (net 152))
  (segment (start 181.1 77.9) (end 182.69 76.31) (width 0.2) (layer "F.Cu") (net 152))
  (segment (start 181.1 78.23) (end 181.1 77.9) (width 0.2) (layer "F.Cu") (net 152))
  (segment (start 157.37772 95.34168) (end 157.37772 94.58128) (width 0.2) (layer "F.Cu") (net 152))
  (segment (start 157.37772 94.58128) (end 157.384 94.575) (width 0.2) (layer "F.Cu") (net 152))
  (segment (start 178.93 84.47) (end 178.93 92.53) (width 0.2) (layer "F.Cu") (net 152))
  (via (at 181.1 78.23) (size 0.5) (drill 0.15) (layers "F.Cu" "B.Cu") (net 152))
  (via (at 179 92.6) (size 0.5) (drill 0.15) (layers "F.Cu" "B.Cu") (net 152))
  (via (at 181.07 82.2545) (size 0.5) (drill 0.15) (layers "F.Cu" "B.Cu") (net 152))
  (via (at 157.384 94.575) (size 0.5) (drill 0.15) (layers "F.Cu" "B.Cu") (net 152))
  (via (at 197.2 75.43) (size 0.5) (drill 0.15) (layers "F.Cu" "B.Cu") (net 152))
  (segment (start 197.2 75.43) (end 197.72 75.95) (width 0.18) (layer "B.Cu") (net 152))
  (segment (start 157.909 95.1) (end 157.384 94.575) (width 0.2) (layer "B.Cu") (net 152))
  (segment (start 181.1 78.23) (end 181.07 78.26) (width 0.2) (layer "B.Cu") (net 152))
  (segment (start 197.72 75.95) (end 198.581 75.95) (width 0.2) (layer "B.Cu") (net 152))
  (segment (start 181.07 78.26) (end 181.07 82.2545) (width 0.2) (layer "B.Cu") (net 152))
  (segment (start 166.259 93) (end 164.159 95.1) (width 0.2) (layer "B.Cu") (net 152))
  (segment (start 164.159 95.1) (end 157.909 95.1) (width 0.2) (layer "B.Cu") (net 152))
  (segment (start 178.6 93) (end 179 92.6) (width 0.2) (layer "B.Cu") (net 152))
  (segment (start 166.259 93) (end 178.6 93) (width 0.2) (layer "B.Cu") (net 152))
  (segment (start 94 70.95) (end 93.825 70.775) (width 0.15) (layer "F.Cu") (net 153))
  (segment (start 94 71.197488) (end 94 70.95) (width 0.15) (layer "F.Cu") (net 153))
  (segment (start 96.652 72.073) (end 94.875512 72.073) (width 0.15) (layer "F.Cu") (net 153))
  (segment (start 97.112 72.533) (end 96.652 72.073) (width 0.15) (layer "F.Cu") (net 153))
  (segment (start 94.875512 72.073) (end 94 71.197488) (width 0.15) (layer "F.Cu") (net 153))
  (via (at 93.825 70.775) (size 0.5) (drill 0.15) (layers "F.Cu" "B.Cu") (net 153))
  (segment (start 93.247488 69.375) (end 92.95 69.672488) (width 0.15) (layer "B.Cu") (net 153))
  (segment (start 91.834771 71.480717) (end 88.930998 71.480717) (width 0.15) (layer "B.Cu") (net 153))
  (segment (start 92.95 69.672488) (end 92.95 70.365488) (width 0.15) (layer "B.Cu") (net 153))
  (segment (start 92.95 70.365488) (end 91.834771 71.480717) (width 0.15) (layer "B.Cu") (net 153))
  (segment (start 93.677512 69.375) (end 94 69.697488) (width 0.15) (layer "B.Cu") (net 153))
  (segment (start 94 69.697488) (end 94 70.6) (width 0.15) (layer "B.Cu") (net 153))
  (segment (start 93.247488 69.375) (end 93.677512 69.375) (width 0.15) (layer "B.Cu") (net 153))
  (segment (start 93.825 70.775) (end 94 70.6) (width 0.15) (layer "B.Cu") (net 153))
  (segment (start 94.35 70.95) (end 94.35 71.052512) (width 0.15) (layer "F.Cu") (net 154))
  (segment (start 94.35 71.052512) (end 95.020488 71.723) (width 0.15) (layer "F.Cu") (net 154))
  (segment (start 96.652 71.723) (end 97.112 71.263) (width 0.15) (layer "F.Cu") (net 154))
  (segment (start 96.227 71.723) (end 96.652 71.723) (width 0.15) (layer "F.Cu") (net 154))
  (segment (start 95.020488 71.723) (end 95.177 71.723) (width 0.15) (layer "F.Cu") (net 154))
  (segment (start 95.927 71.007751) (end 95.927 71.473) (width 0.15) (layer "F.Cu") (net 154))
  (segment (start 95.427 71.473) (end 95.427 71.007751) (width 0.15) (layer "F.Cu") (net 154))
  (segment (start 96.177 71.723) (end 96.227 71.723) (width 0.15) (layer "F.Cu") (net 154))
  (segment (start 94.525 70.775) (end 94.35 70.95) (width 0.15) (layer "F.Cu") (net 154))
  (via (at 94.525 70.775) (size 0.5) (drill 0.15) (layers "F.Cu" "B.Cu") (net 154))
  (arc (start 95.427 71.007751) (mid 95.500223 70.830974) (end 95.677 70.757751) (width 0.15) (layer "F.Cu") (net 154))
  (arc (start 95.927 71.473) (mid 96.000223 71.649777) (end 96.177 71.723) (width 0.15) (layer "F.Cu") (net 154))
  (arc (start 95.177 71.723) (mid 95.353777 71.649777) (end 95.427 71.473) (width 0.15) (layer "F.Cu") (net 154))
  (arc (start 95.677 70.757751) (mid 95.853777 70.830974) (end 95.927 71.007751) (width 0.15) (layer "F.Cu") (net 154))
  (segment (start 93.102512 69.025) (end 92.6 69.527512) (width 0.15) (layer "B.Cu") (net 154))
  (segment (start 91.689795 71.130717) (end 91.379816 71.130717) (width 0.15) (layer "B.Cu") (net 154))
  (segment (start 93.102512 69.025) (end 93.822488 69.025) (width 0.15) (layer "B.Cu") (net 154))
  (segment (start 93.822488 69.025) (end 94.35 69.552512) (width 0.15) (layer "B.Cu") (net 154))
  (segment (start 91.379816 71.130717) (end 90.709816 70.460717) (width 0.15) (layer "B.Cu") (net 154))
  (segment (start 92.6 70.220512) (end 91.689795 71.130717) (width 0.15) (layer "B.Cu") (net 154))
  (segment (start 94.525 70.775) (end 94.35 70.6) (width 0.15) (layer "B.Cu") (net 154))
  (segment (start 92.6 69.527512) (end 92.6 70.220512) (width 0.15) (layer "B.Cu") (net 154))
  (segment (start 94.35 69.552512) (end 94.35 70.6) (width 0.15) (layer "B.Cu") (net 154))
  (segment (start 96.652 68.263) (end 97.112 68.723) (width 0.15) (layer "F.Cu") (net 155))
  (segment (start 94.8495 68.4005) (end 94.8495 69.4005) (width 0.15) (layer "F.Cu") (net 155))
  (segment (start 95.8245 69.4005) (end 95.8245 68.4005) (width 0.15) (layer "F.Cu") (net 155))
  (segment (start 94.283088 68.263) (end 94.712 68.263) (width 0.15) (layer "F.Cu") (net 155))
  (segment (start 94.108088 68.438) (end 94.283088 68.263) (width 0.15) (layer "F.Cu") (net 155))
  (segment (start 95.962 68.263) (end 96.652 68.263) (width 0.15) (layer "F.Cu") (net 155))
  (via (at 94.108088 68.438) (size 0.5) (drill 0.15) (layers "F.Cu" "B.Cu") (net 155))
  (arc (start 94.712 68.263) (mid 94.809227 68.303273) (end 94.8495 68.4005) (width 0.15) (layer "F.Cu") (net 155))
  (arc (start 95.8245 68.4005) (mid 95.864773 68.303273) (end 95.962 68.263) (width 0.15) (layer "F.Cu") (net 155))
  (arc (start 94.8495 69.4005) (mid 94.992285 69.745215) (end 95.337 69.888) (width 0.15) (layer "F.Cu") (net 155))
  (arc (start 95.337 69.888) (mid 95.681715 69.745215) (end 95.8245 69.4005) (width 0.15) (layer "F.Cu") (net 155))
  (segment (start 91.878 69.447) (end 88.937281 69.447) (width 0.15) (layer "B.Cu") (net 155))
  (segment (start 94.108088 68.438) (end 93.945088 68.275) (width 0.15) (layer "B.Cu") (net 155))
  (segment (start 93.945088 68.275) (end 93.05 68.275) (width 0.15) (layer "B.Cu") (net 155))
  (segment (start 93.05 68.275) (end 91.878 69.447) (width 0.15) (layer "B.Cu") (net 155))
  (segment (start 95.713127 65.699219) (end 95.713128 65.699219) (width 0.15) (layer "F.Cu") (net 156))
  (segment (start 93.164609 68.045773) (end 93.921893 67.288489) (width 0.15) (layer "F.Cu") (net 156))
  (segment (start 95.176212 66.041655) (end 95.32422 65.893674) (width 0.15) (layer "F.Cu") (net 156))
  (segment (start 96.22578 66.211872) (end 95.713127 65.699219) (width 0.15) (layer "F.Cu") (net 156))
  (segment (start 95.083896 66.133971) (end 95.176212 66.041655) (width 0.15) (layer "F.Cu") (net 156))
  (segment (start 95.713128 65.504763) (end 96.757512 64.460379) (width 0.15) (layer "F.Cu") (net 156))
  (segment (start 96.757512 64.460379) (end 96.757512 64.453) (width 0.15) (layer "F.Cu") (net 156))
  (segment (start 95.076479 66.133971) (end 95.083896 66.133971) (width 0.15) (layer "F.Cu") (net 156))
  (segment (start 97.427 64.453) (end 97.887 64.913) (width 0.15) (layer "F.Cu") (net 156))
  (segment (start 94.069588 65.81638) (end 94.38718 66.133972) (width 0.15) (layer "F.Cu") (net 156))
  (segment (start 95.518674 65.893674) (end 96.031326 66.406326) (width 0.15) (layer "F.Cu") (net 156))
  (segment (start 92.467748 68.220773) (end 92.642748 68.045773) (width 0.15) (layer "F.Cu") (net 156))
  (segment (start 92.642748 68.045773) (end 93.164609 68.045773) (width 0.15) (layer "F.Cu") (net 156))
  (segment (start 94.192725 66.328424) (end 93.875134 66.010833) (width 0.15) (layer "F.Cu") (net 156))
  (segment (start 93.922023 67.288489) (end 94.192755 67.017757) (width 0.15) (layer "F.Cu") (net 156))
  (segment (start 96.757512 64.453) (end 97.427 64.453) (width 0.15) (layer "F.Cu") (net 156))
  (segment (start 94.192724 66.328424) (end 94.192725 66.328424) (width 0.15) (layer "F.Cu") (net 156))
  (segment (start 94.06959 65.816379) (end 94.069588 65.81638) (width 0.15) (layer "F.Cu") (net 156))
  (segment (start 93.921893 67.288489) (end 93.922023 67.288489) (width 0.15) (layer "F.Cu") (net 156))
  (segment (start 94.192755 67.017757) (end 94.192724 67.017724) (width 0.15) (layer "F.Cu") (net 156))
  (via (at 92.467748 68.220773) (size 0.5) (drill 0.15) (layers "F.Cu" "B.Cu") (net 156))
  (arc (start 96.22578 66.406326) (mid 96.266053 66.309099) (end 96.22578 66.211872) (width 0.15) (layer "F.Cu") (net 156))
  (arc (start 93.875134 66.010833) (mid 93.834861 65.913606) (end 93.875134 65.816379) (width 0.15) (layer "F.Cu") (net 156))
  (arc (start 96.031326 66.406326) (mid 96.128553 66.446599) (end 96.22578 66.406326) (width 0.15) (layer "F.Cu") (net 156))
  (arc (start 95.32422 65.893674) (mid 95.421447 65.853401) (end 95.518674 65.893674) (width 0.15) (layer "F.Cu") (net 156))
  (arc (start 94.192724 67.017724) (mid 94.335484 66.673073) (end 94.192724 66.328424) (width 0.15) (layer "F.Cu") (net 156))
  (arc (start 94.38718 66.133972) (mid 94.73183 66.27673) (end 95.076479 66.133971) (width 0.15) (layer "F.Cu") (net 156))
  (arc (start 95.713128 65.699219) (mid 95.672854 65.601992) (end 95.713128 65.504763) (width 0.15) (layer "F.Cu") (net 156))
  (arc (start 93.875134 65.816379) (mid 93.972361 65.776107) (end 94.06959 65.816379) (width 0.15) (layer "F.Cu") (net 156))
  (segment (start 91.325283 68.420717) (end 91.700227 68.045773) (width 0.15) (layer "B.Cu") (net 156))
  (segment (start 91.700227 68.045773) (end 92.292748 68.045773) (width 0.15) (layer "B.Cu") (net 156))
  (segment (start 92.292748 68.045773) (end 92.467748 68.220773) (width 0.15) (layer "B.Cu") (net 156))
  (segment (start 95.249785 65.465752) (end 96.612537 64.103) (width 0.15) (layer "F.Cu") (net 157))
  (segment (start 94.829057 65.886548) (end 94.829056 65.886547) (width 0.15) (layer "F.Cu") (net 157))
  (segment (start 94.829056 65.886547) (end 95.249785 65.465752) (width 0.15) (layer "F.Cu") (net 157))
  (segment (start 93.945268 66.770269) (end 93.945301 66.770301) (width 0.15) (layer "F.Cu") (net 157))
  (segment (start 94.317011 65.568956) (end 94.634603 65.886548) (width 0.15) (layer "F.Cu") (net 157))
  (segment (start 92.642748 67.695773) (end 93.019764 67.695773) (width 0.15) (layer "F.Cu") (net 157))
  (segment (start 93.019764 67.695773) (end 93.945268 66.770269) (width 0.15) (layer "F.Cu") (net 157))
  (segment (start 93.627711 65.568957) (end 93.627711 65.568956) (width 0.15) (layer "F.Cu") (net 157))
  (segment (start 92.467748 67.520773) (end 92.642748 67.695773) (width 0.15) (layer "F.Cu") (net 157))
  (segment (start 96.612537 64.103) (end 97.427 64.103) (width 0.15) (layer "F.Cu") (net 157))
  (segment (start 97.427 64.103) (end 97.887 63.643) (width 0.15) (layer "F.Cu") (net 157))
  (segment (start 93.945301 66.575847) (end 93.62771 66.258256) (width 0.15) (layer "F.Cu") (net 157))
  (via (at 92.467748 67.520773) (size 0.5) (drill 0.15) (layers "F.Cu" "B.Cu") (net 157))
  (arc (start 93.627711 65.568956) (mid 93.97236 65.426198) (end 94.317011 65.568956) (width 0.15) (layer "F.Cu") (net 157))
  (arc (start 93.62771 66.258256) (mid 93.484952 65.913606) (end 93.627711 65.568957) (width 0.15) (layer "F.Cu") (net 157))
  (arc (start 94.634603 65.886548) (mid 94.73183 65.926821) (end 94.829057 65.886548) (width 0.15) (layer "F.Cu") (net 157))
  (arc (start 93.945301 66.770301) (mid 93.985574 66.673074) (end 93.945301 66.575847) (width 0.15) (layer "F.Cu") (net 157))
  (segment (start 92.292748 67.695773) (end 91.589773 67.695773) (width 0.15) (layer "B.Cu") (net 157))
  (segment (start 91.589773 67.695773) (end 91.294717 67.400717) (width 0.15) (layer "B.Cu") (net 157))
  (segment (start 92.467748 67.520773) (end 92.292748 67.695773) (width 0.15) (layer "B.Cu") (net 157))
  (segment (start 91.294717 67.400717) (end 88.930998 67.400717) (width 0.15) (layer "B.Cu") (net 157))
  (segment (start 95.1995 68.4005) (end 95.1995 69.4005) (width 0.15) (layer "F.Cu") (net 158))
  (segment (start 94.283088 67.913) (end 94.712 67.913) (width 0.15) (layer "F.Cu") (net 158))
  (segment (start 96.652 67.913) (end 97.112 67.453) (width 0.15) (layer "F.Cu") (net 158))
  (segment (start 95.4745 69.4005) (end 95.4745 68.4005) (width 0.15) (layer "F.Cu") (net 158))
  (segment (start 95.962 67.913) (end 96.652 67.913) (width 0.15) (layer "F.Cu") (net 158))
  (segment (start 94.108088 67.738) (end 94.283088 67.913) (width 0.15) (layer "F.Cu") (net 158))
  (via (at 94.108088 67.738) (size 0.5) (drill 0.15) (layers "F.Cu" "B.Cu") (net 158))
  (arc (start 94.712 67.913) (mid 95.056715 68.055785) (end 95.1995 68.4005) (width 0.15) (layer "F.Cu") (net 158))
  (arc (start 95.4745 68.4005) (mid 95.617285 68.055785) (end 95.962 67.913) (width 0.15) (layer "F.Cu") (net 158))
  (arc (start 95.1995 69.4005) (mid 95.239773 69.497727) (end 95.337 69.538) (width 0.15) (layer "F.Cu") (net 158))
  (arc (start 95.337 69.538) (mid 95.434227 69.497727) (end 95.4745 69.4005) (width 0.15) (layer "F.Cu") (net 158))
  (segment (start 92.471365 66.888683) (end 92.471365 66.888684) (width 0.15) (layer "B.Cu") (net 158))
  (segment (start 93.482681 67.9) (end 92.966341 67.38366) (width 0.15) (layer "B.Cu") (net 158))
  (segment (start 92.471365 66.888684) (end 91.963398 66.380717) (width 0.15) (layer "B.Cu") (net 158))
  (segment (start 92.930986 66.676551) (end 92.930985 66.676552) (width 0.15) (layer "B.Cu") (net 158))
  (segment (start 94.108088 67.738) (end 93.946088 67.9) (width 0.15) (layer "B.Cu") (net 158))
  (segment (start 93.946088 67.9) (end 93.482681 67.9) (width 0.15) (layer "B.Cu") (net 158))
  (segment (start 91.963398 66.380717) (end 90.709816 66.380717) (width 0.15) (layer "B.Cu") (net 158))
  (segment (start 92.930985 66.676552) (end 92.718852 66.888684) (width 0.15) (layer "B.Cu") (net 158))
  (segment (start 92.96634 67.136173) (end 92.966341 67.136172) (width 0.15) (layer "B.Cu") (net 158))
  (segment (start 92.966341 67.136172) (end 93.178473 66.924039) (width 0.15) (layer "B.Cu") (net 158))
  (segment (start 93.178472 66.676552) (end 93.178473 66.676552) (width 0.15) (layer "B.Cu") (net 158))
  (arc (start 92.966341 67.38366) (mid 92.915084 67.259917) (end 92.96634 67.136173) (width 0.15) (layer "B.Cu") (net 158))
  (arc (start 93.178473 66.676552) (mid 93.05473 66.625295) (end 92.930986 66.676551) (width 0.15) (layer "B.Cu") (net 158))
  (arc (start 92.718852 66.888684) (mid 92.595108 66.93994) (end 92.471365 66.888683) (width 0.15) (layer "B.Cu") (net 158))
  (arc (start 93.178473 66.924039) (mid 93.229729 66.800295) (end 93.178472 66.676552) (width 0.15) (layer "B.Cu") (net 158))
  (segment (start 96.652 60.643) (end 97.112 61.103) (width 0.15) (layer "F.Cu") (net 159))
  (segment (start 94.897039 63.102258) (end 94.897039 61.998449) (width 0.15) (layer "F.Cu") (net 159))
  (segment (start 96.252488 60.643) (end 96.652 60.643) (width 0.15) (layer "F.Cu") (net 159))
  (segment (start 94.897039 61.998449) (end 96.252488 60.643) (width 0.15) (layer "F.Cu") (net 159))
  (segment (start 95.072039 63.277258) (end 94.897039 63.102258) (width 0.15) (layer "F.Cu") (net 159))
  (via (at 95.072039 63.277258) (size 0.5) (drill 0.15) (layers "F.Cu" "B.Cu") (net 159))
  (segment (start 88.930998 65.360717) (end 93.717283 65.360717) (width 0.15) (layer "B.Cu") (net 159))
  (segment (start 93.717283 65.360717) (end 94.897039 64.180961) (width 0.15) (layer "B.Cu") (net 159))
  (segment (start 94.897039 64.180961) (end 94.897039 63.452258) (width 0.15) (layer "B.Cu") (net 159))
  (segment (start 94.897039 63.452258) (end 95.072039 63.277258) (width 0.15) (layer "B.Cu") (net 159))
  (segment (start 94.680595 61.025292) (end 94.713343 61.017817) (width 0.15) (layer "F.Cu") (net 160))
  (segment (start 95.048334 60.848676) (end 95.02739 60.822415) (width 0.15) (layer "F.Cu") (net 160))
  (segment (start 94.769756 61.630756) (end 94.790699 61.604495) (width 0.15) (layer "F.Cu") (net 160))
  (segment (start 94.650333 61.039865) (end 94.680595 61.025292) (width 0.15) (layer "F.Cu") (net 160))
  (segment (start 95.071162 61.249484) (end 95.10475 61.249485) (width 0.15) (layer "F.Cu") (net 160))
  (segment (start 94.588554 61.216414) (end 94.581079 61.183668) (width 0.15) (layer "F.Cu") (net 160))
  (segment (start 94.603127 61.246678) (end 94.588554 61.216414) (width 0.15) (layer "F.Cu") (net 160))
  (segment (start 95.137498 61.24201) (end 95.16776 61.227437) (width 0.15) (layer "F.Cu") (net 160))
  (segment (start 95.214961 61.020624) (end 95.194019 60.994361) (width 0.15) (layer "F.Cu") (net 160))
  (segment (start 94.624071 61.060807) (end 94.650333 61.039865) (width 0.15) (layer "F.Cu") (net 160))
  (segment (start 94.790699 61.604495) (end 94.805272 61.574233) (width 0.15) (layer "F.Cu") (net 160))
  (segment (start 95.529013 60.825222) (end 95.561761 60.817747) (width 0.15) (layer "F.Cu") (net 160))
  (segment (start 94.836203 61.060808) (end 94.981889 61.206494) (width 0.15) (layer "F.Cu") (net 160))
  (segment (start 94.547039 63.102258) (end 94.547039 61.853473) (width 0.15) (layer "F.Cu") (net 160))
  (segment (start 95.234204 60.615603) (end 95.260466 60.636545) (width 0.15) (layer "F.Cu") (net 160))
  (segment (start 95.027391 60.662805) (end 95.048334 60.636544) (width 0.15) (layer "F.Cu") (net 160))
  (segment (start 94.624071 61.272939) (end 94.603127 61.246678) (width 0.15) (layer "F.Cu") (net 160))
  (segment (start 95.214962 61.180232) (end 95.229535 61.14997) (width 0.15) (layer "F.Cu") (net 160))
  (segment (start 95.203942 60.601028) (end 95.234204 60.615603) (width 0.15) (layer "F.Cu") (net 160))
  (segment (start 95.194019 60.994361) (end 95.048334 60.848676) (width 0.15) (layer "F.Cu") (net 160))
  (segment (start 95.02739 60.822415) (end 95.012817 60.792151) (width 0.15) (layer "F.Cu") (net 160))
  (segment (start 95.260466 60.636545) (end 95.406152 60.782231) (width 0.15) (layer "F.Cu") (net 160))
  (segment (start 94.713343 61.017817) (end 94.746931 61.017818) (width 0.15) (layer "F.Cu") (net 160))
  (segment (start 95.048334 60.636544) (end 95.074596 60.615602) (width 0.15) (layer "F.Cu") (net 160))
  (segment (start 94.58108 61.150078) (end 94.588553 61.117332) (width 0.15) (layer "F.Cu") (net 160))
  (segment (start 94.588553 61.117332) (end 94.603128 61.087068) (width 0.15) (layer "F.Cu") (net 160))
  (segment (start 95.012817 60.792151) (end 95.005342 60.759405) (width 0.15) (layer "F.Cu") (net 160))
  (segment (start 95.561761 60.817747) (end 95.592023 60.803174) (width 0.15) (layer "F.Cu") (net 160))
  (segment (start 94.812746 61.507897) (end 94.805273 61.475149) (width 0.15) (layer "F.Cu") (net 160))
  (segment (start 94.809941 61.039866) (end 94.836203 61.060808) (width 0.15) (layer "F.Cu") (net 160))
  (segment (start 94.805273 61.475149) (end 94.790698 61.444887) (width 0.15) (layer "F.Cu") (net 160))
  (segment (start 95.23701 61.117222) (end 95.237009 61.083634) (width 0.15) (layer "F.Cu") (net 160))
  (segment (start 94.981889 61.206494) (end 95.008152 61.227436) (width 0.15) (layer "F.Cu") (net 160))
  (segment (start 95.406152 60.782231) (end 95.432415 60.803173) (width 0.15) (layer "F.Cu") (net 160))
  (segment (start 95.005342 60.759405) (end 95.005343 60.725815) (width 0.15) (layer "F.Cu") (net 160))
  (segment (start 95.074596 60.615602) (end 95.104858 60.601029) (width 0.15) (layer "F.Cu") (net 160))
  (segment (start 94.805272 61.574233) (end 94.812747 61.541485) (width 0.15) (layer "F.Cu") (net 160))
  (segment (start 95.137606 60.593554) (end 95.171194 60.593555) (width 0.15) (layer "F.Cu") (net 160))
  (segment (start 95.012816 60.693069) (end 95.027391 60.662805) (width 0.15) (layer "F.Cu") (net 160))
  (segment (start 94.603128 61.087068) (end 94.624071 61.060807) (width 0.15) (layer "F.Cu") (net 160))
  (segment (start 95.194019 61.206493) (end 95.214962 61.180232) (width 0.15) (layer "F.Cu") (net 160))
  (segment (start 96.652 60.293) (end 97.112 59.833) (width 0.15) (layer "F.Cu") (net 160))
  (segment (start 95.229535 61.14997) (end 95.23701 61.117222) (width 0.15) (layer "F.Cu") (net 160))
  (segment (start 94.790698 61.444887) (end 94.769756 61.418624) (width 0.15) (layer "F.Cu") (net 160))
  (segment (start 95.462677 60.817748) (end 95.495425 60.825221) (width 0.15) (layer "F.Cu") (net 160))
  (segment (start 95.432415 60.803173) (end 95.462677 60.817748) (width 0.15) (layer "F.Cu") (net 160))
  (segment (start 94.769756 61.418624) (end 94.624071 61.272939) (width 0.15) (layer "F.Cu") (net 160))
  (segment (start 94.581079 61.183668) (end 94.58108 61.150078) (width 0.15) (layer "F.Cu") (net 160))
  (segment (start 95.005343 60.725815) (end 95.012816 60.693069) (width 0.15) (layer "F.Cu") (net 160))
  (segment (start 94.779679 61.025291) (end 94.809941 61.039866) (width 0.15) (layer "F.Cu") (net 160))
  (segment (start 95.592023 60.803174) (end 95.618283 60.78223) (width 0.15) (layer "F.Cu") (net 160))
  (segment (start 95.104858 60.601029) (end 95.137606 60.593554) (width 0.15) (layer "F.Cu") (net 160))
  (segment (start 95.237009 61.083634) (end 95.229536 61.050886) (width 0.15) (layer "F.Cu") (net 160))
  (segment (start 94.746931 61.017818) (end 94.779679 61.025291) (width 0.15) (layer "F.Cu") (net 160))
  (segment (start 95.16776 61.227437) (end 95.194019 61.206493) (width 0.15) (layer "F.Cu") (net 160))
  (segment (start 95.229536 61.050886) (end 95.214961 61.020624) (width 0.15) (layer "F.Cu") (net 160))
  (segment (start 95.038414 61.242011) (end 95.071162 61.249484) (width 0.15) (layer "F.Cu") (net 160))
  (segment (start 95.618283 60.78223) (end 96.107512 60.293) (width 0.15) (layer "F.Cu") (net 160))
  (segment (start 94.812747 61.541485) (end 94.812746 61.507897) (width 0.15) (layer "F.Cu") (net 160))
  (segment (start 96.107512 60.293) (end 96.652 60.293) (width 0.15) (layer "F.Cu") (net 160))
  (segment (start 95.008152 61.227436) (end 95.038414 61.242011) (width 0.15) (layer "F.Cu") (net 160))
  (segment (start 95.10475 61.249485) (end 95.137498 61.24201) (width 0.15) (layer "F.Cu") (net 160))
  (segment (start 94.547039 61.853473) (end 94.769756 61.630756) (width 0.15) (layer "F.Cu") (net 160))
  (segment (start 95.495425 60.825221) (end 95.529013 60.825222) (width 0.15) (layer "F.Cu") (net 160))
  (segment (start 94.372039 63.277258) (end 94.547039 63.102258) (width 0.15) (layer "F.Cu") (net 160))
  (segment (start 95.171194 60.593555) (end 95.203942 60.601028) (width 0.15) (layer "F.Cu") (net 160))
  (via (at 94.372039 63.277258) (size 0.5) (drill 0.15) (layers "F.Cu" "B.Cu") (net 160))
  (segment (start 93.567283 65.010717) (end 94.547039 64.030961) (width 0.15) (layer "B.Cu") (net 160))
  (segment (start 90.709816 64.340717) (end 91.379816 65.010717) (width 0.15) (layer "B.Cu") (net 160))
  (segment (start 94.547039 63.452258) (end 94.372039 63.277258) (width 0.15) (layer "B.Cu") (net 160))
  (segment (start 91.379816 65.010717) (end 93.567283 65.010717) (width 0.15) (layer "B.Cu") (net 160))
  (segment (start 94.547039 64.030961) (end 94.547039 63.452258) (width 0.15) (layer "B.Cu") (net 160))
  (segment (start 177.594 70.846) (end 177.594 71.81) (width 0.254) (layer "B.Cu") (net 162))
  (segment (start 178.661 72.877) (end 179.764 72.877) (width 0.254) (layer "B.Cu") (net 162))
  (segment (start 177.594 71.81) (end 178.661 72.877) (width 0.254) (layer "B.Cu") (net 162))
  (segment (start 100.95 87.85) (end 100.15627 87.05627) (width 0.254) (layer "F.Cu") (net 170))
  (segment (start 124.6 93.6) (end 120.4 93.6) (width 0.254) (layer "F.Cu") (net 170))
  (segment (start 128.15 85.6) (end 139.5 74.25) (width 0.254) (layer "F.Cu") (net 170))
  (segment (start 103.9 87.85) (end 100.95 87.85) (width 0.254) (layer "F.Cu") (net 170))
  (segment (start 79.86 78.63) (end 79.85 78.62) (width 0.254) (layer "F.Cu") (net 170))
  (segment (start 104.95 94.72) (end 104.95 88.9) (width 0.254) (layer "F.Cu") (net 170))
  (segment (start 120.4 93.6) (end 118.54 95.46) (width 0.254) (layer "F.Cu") (net 170))
  (segment (start 104.95 88.9) (end 103.9 87.85) (width 0.254) (layer "F.Cu") (net 170))
  (segment (start 126.4 91.8) (end 124.6 93.6) (width 0.254) (layer "F.Cu") (net 170))
  (segment (start 125.4 88) (end 126.4 89) (width 0.254) (layer "F.Cu") (net 170))
  (segment (start 105.69 95.46) (end 104.95 94.72) (width 0.254) (layer "F.Cu") (net 170))
  (segment (start 124.6 88) (end 125.4 88) (width 0.254) (layer "F.Cu") (net 170))
  (segment (start 126.4 89) (end 126.4 91.8) (width 0.254) (layer "F.Cu") (net 170))
  (segment (start 79.85 78.62) (end 79.85 77.94) (width 0.254) (layer "F.Cu") (net 170))
  (segment (start 118.54 95.46) (end 105.69 95.46) (width 0.254) (layer "F.Cu") (net 170))
  (segment (start 139.5 69.7) (end 138.862 69.062) (width 0.254) (layer "F.Cu") (net 170))
  (segment (start 124.6 85.6) (end 128.15 85.6) (width 0.254) (layer "F.Cu") (net 170))
  (segment (start 100.15627 87.05627) (end 100.15627 87.05277) (width 0.254) (layer "F.Cu") (net 170))
  (segment (start 139.5 74.25) (end 139.5 69.7) (width 0.254) (layer "F.Cu") (net 170))
  (via (at 171.45 71.755) (size 0.5) (drill 0.15) (layers "F.Cu" "B.Cu") (net 170))
  (via (at 172.70984 69.215) (size 0.5) (drill 0.15) (layers "F.Cu" "B.Cu") (net 170))
  (via (at 173.96968 69.215) (size 0.5) (drill 0.15) (layers "F.Cu" "B.Cu") (net 170))
  (via (at 153.25 93.35) (size 0.5) (drill 0.15) (layers "F.Cu" "B.Cu") (net 170))
  (via (at 148.9202 77.6986) (size 0.5) (drill 0.15) (layers "F.Cu" "B.Cu") (free) (net 170))
  (via (at 151.6634 77.6986) (size 0.5) (drill 0.15) (layers "F.Cu" "B.Cu") (free) (net 170))
  (via (at 152.35 92.7) (size 0.5) (drill 0.15) (layers "F.Cu" "B.Cu") (net 170))
  (via (at 177.634 84.05) (size 0.5) (drill 0.15) (layers "F.Cu" "B.Cu") (net 170))
  (via (at 171.45 69.215) (size 0.5) (drill 0.15) (layers "F.Cu" "B.Cu") (net 170))
  (via (at 124.6 88) (size 0.5) (drill 0.15) (layers "F.Cu" "B.Cu") (free) (net 170))
  (via (at 150.7744 78.4606) (size 0.5) (drill 0.15) (layers "F.Cu" "B.Cu") (free) (net 170))
  (via (at 79.86 78.63) (size 0.5) (drill 0.15) (layers "F.Cu" "B.Cu") (net 170))
  (via (at 150.1902 77.6986) (size 0.5) (drill 0.15) (layers "F.Cu" "B.Cu") (free) (net 170))
  (via (at 178.334 83.35) (size 0.5) (drill 0.15) (layers "F.Cu" "B.Cu") (net 170))
  (via (at 172.334 70.485) (size 0.5) (drill 0.15) (layers "F.Cu" "B.Cu") (net 170))
  (via (at 177.634 82.75) (size 0.5) (drill 0.15) (layers "F.Cu" "B.Cu") (net 170))
  (via (at 176.48936 69.215) (size 0.5) (drill 0.15) (layers "F.Cu" "B.Cu") (net 170))
  (via (at 124.6 87.2) (size 0.5) (drill 0.15) (layers "F.Cu" "B.Cu") (free) (net 170))
  (via (at 173.084 69.85) (size 0.5) (drill 0.15) (layers "F.Cu" "B.Cu") (net 170))
  (via (at 124 85.2) (size 0.5) (drill 0.15) (layers "F.Cu" "B.Cu") (free) (net 170))
  (via (at 124 86.8) (size 0.5) (drill 0.15) (layers "F.Cu" "B.Cu") (free) (net 170))
  (via (at 171.45 70.485) (size 0.5) (drill 0.15) (layers "F.Cu" "B.Cu") (net 170))
  (via (at 148.082 78.4352) (size 0.5) (drill 0.15) (layers "F.Cu" "B.Cu") (free) (net 170))
  (via (at 151.45 93.35) (size 0.5) (drill 0.15) (layers "F.Cu" "B.Cu") (net 170))
  (via (at 149.4028 78.4606) (size 0.5) (drill 0.15) (layers "F.Cu" "B.Cu") (free) (net 170))
  (via (at 100.15627 87.05277) (size 0.5) (drill 0.15) (layers "F.Cu" "B.Cu") (net 170))
  (via (at 153.25 92.05) (size 0.5) (drill 0.15) (layers "F.Cu" "B.Cu") (net 170))
  (via (at 124.6 86.4) (size 0.5) (drill 0.15) (layers "F.Cu" "B.Cu") (free) (net 170))
  (via (at 175.22952 69.215) (size 0.5) (drill 0.15) (layers "F.Cu" "B.Cu") (net 170))
  (via (at 124.6 85.6) (size 0.5) (drill 0.15) (layers "F.Cu" "B.Cu") (free) (net 170))
  (via (at 124 86) (size 0.5) (drill 0.15) (layers "F.Cu" "B.Cu") (free) (net 170))
  (via (at 124 87.6) (size 0.5) (drill 0.15) (layers "F.Cu" "B.Cu") (free) (net 170))
  (via (at 177.7492 69.2658) (size 0.5) (drill 0.15) (layers "F.Cu" "B.Cu") (net 170))
  (via (at 151.5 92.05) (size 0.5) (drill 0.15) (layers "F.Cu" "B.Cu") (net 170))
  (segment (start 79.8655 80.3455) (end 80.93 81.41) (width 0.254) (layer "B.Cu") (net 170))
  (segment (start 126.215 84.285) (end 126.215 87) (width 0.5) (layer "B.Cu") (net 170))
  (segment (start 79.8655 79.292064) (end 79.8655 80.3455) (width 0.254) (layer "B.Cu") (net 170))
  (segment (start 126.7 83.8) (end 126.215 84.285) (width 0.5) (layer "B.Cu") (net 170))
  (segment (start 80.93 81.41) (end 97.885 81.41) (width 0.254) (layer "B.Cu") (net 170))
  (segment (start 97.885 81.41) (end 100.18 83.705) (width 0.254) (layer "B.Cu") (net 170))
  (segment (start 79.86 78.63) (end 79.86 79.286564) (width 0.254) (layer "B.Cu") (net 170))
  (segment (start 100.18 83.705) (end 100.18 87.02904) (width 0.254) (layer "B.Cu") (net 170))
  (segment (start 79.86 79.286564) (end 79.8655 79.292064) (width 0.254) (layer "B.Cu") (net 170))
  (segment (start 100.18 87.02904) (end 100.15627 87.05277) (width 0.254) (layer "B.Cu") (net 170))
  (segment (start 128.715 83.8) (end 126.7 83.8) (width 0.5) (layer "B.Cu") (net 170))
  (segment (start 109.39 68.72) (end 108.374 67.704) (width 0.4) (layer "B.Cu") (net 175))
  (segment (start 109.39 69.124) (end 109.39 68.72) (width 0.4) (layer "B.Cu") (net 175))
  (segment (start 109.39 65.48) (end 108.374 64.464) (width 0.4) (layer "B.Cu") (net 175))
  (segment (start 109.39 66.011) (end 109.39 65.48) (width 0.4) (layer "B.Cu") (net 175))
  (segment (start 108.374 64.464) (end 108.374 59.624) (width 0.4) (layer "B.Cu") (net 175))
  (segment (start 108.374 67.704) (end 108.374 69.1) (width 0.4) (layer "B.Cu") (net 175))
  (segment (start 108.374 67.704) (end 108.374 66.876) (width 0.4) (layer "B.Cu") (net 175))
  (segment (start 108.374 66.876) (end 109.239 66.011) (width 0.4) (layer "B.Cu") (net 175))
  (segment (start 109.2675 62.1375) (end 108.37 61.24) (width 0.4) (layer "B.Cu") (net 175))
  (segment (start 109.239 66.011) (end 109.39 66.011) (width 0.4) (layer "B.Cu") (net 175))
  (segment (start 78.45 77.94) (end 76.109 77.94) (width 0.254) (layer "F.Cu") (net 188))
  (segment (start 76.109 77.94) (end 76.1 77.931) (width 0.254) (layer "F.Cu") (net 188))
  (via (at 95.6 77.09) (size 0.5) (drill 0.15) (layers "F.Cu" "B.Cu") (net 191))
  (via (at 96.26 77.084) (size 0.5) (drill 0.15) (layers "F.Cu" "B.Cu") (net 191))
  (via (at 94.88 77.606) (size 0.5) (drill 0.15) (layers "F.Cu" "B.Cu") (net 191))
  (via (at 95.6 77.606) (size 0.5) (drill 0.15) (layers "F.Cu" "B.Cu") (net 191))
  (via (at 96.26 77.6) (size 0.5) (drill 0.15) (layers "F.Cu" "B.Cu") (net 191))
  (via (at 82.15 92.706) (size 0.5) (drill 0.15) (layers "F.Cu" "B.Cu") (net 191))
  (via (at 81.15 93.706) (size 0.5) (drill 0.15) (layers "F.Cu" "B.Cu") (net 191))
  (via (at 82.15 93.706) (size 0.5) (drill 0.15) (layers "F.Cu" "B.Cu") (net 191))
  (via (at 81.15 94.706) (size 0.5) (drill 0.15) (layers "F.Cu" "B.Cu") (net 191))
  (via (at 82.15 94.706) (size 0.5) (drill 0.15) (layers "F.Cu" "B.Cu") (net 191))
  (via (at 81.15 95.706) (size 0.5) (drill 0.15) (layers "F.Cu" "B.Cu") (net 191))
  (via (at 82.15 95.706) (size 0.5) (drill 0.15) (layers "F.Cu" "B.Cu") (net 191))
  (via (at 81.15 92.706) (size 0.5) (drill 0.15) (layers "F.Cu" "B.Cu") (net 191))
  (via (at 94.88 77.09) (size 0.5) (drill 0.15) (layers "F.Cu" "B.Cu") (net 191))
  (segment (start 99.682 68.584) (end 96.196 72.07) (width 0.75) (layer "B.Cu") (net 191))
  (segment (start 96.196 72.07) (end 96.196 74.332) (width 0.75) (layer "B.Cu") (net 191))
  (segment (start 87.33622 90.72978) (end 85.72226 90.72978) (width 0.254) (layer "B.Cu") (net 201))
  (segment (start 88.425 89.641) (end 87.33622 90.72978) (width 0.254) (layer "B.Cu") (net 201))
  (segment (start 108.3 71.35) (end 110.753 73.803) (width 0.254) (layer "F.Cu") (net 222))
  (segment (start 110.753 73.803) (end 112.487 73.803) (width 0.254) (layer "F.Cu") (net 222))
  (via (at 108.3 71.35) (size 0.5) (drill 0.15) (layers "F.Cu" "B.Cu") (net 222))
  (segment (start 108.3 70.144) (end 108.3 71.359) (width 0.4) (layer "B.Cu") (net 222))
  (segment (start 112.487 69.993) (end 110.457 69.993) (width 0.254) (layer "F.Cu") (net 223))
  (segment (start 110.457 69.993) (end 110.25 70.2) (width 0.254) (layer "F.Cu") (net 223))
  (via (at 110.25 70.2) (size 0.5) (drill 0.15) (layers "F.Cu" "B.Cu") (net 223))
  (segment (start 109.783 70.2) (end 109.779 70.196) (width 0.4) (layer "B.Cu") (net 223))
  (segment (start 110.25 70.2) (end 109.783 70.2) (width 0.4) (layer "B.Cu") (net 223))
  (segment (start 109.779 70.196) (end 109.39 70.196) (width 0.4) (layer "B.Cu") (net 223))
  (segment (start 109.391 67.902) (end 109.391 67.037) (width 0.254) (layer "F.Cu") (net 224))
  (segment (start 110.245 66.183) (end 112.487 66.183) (width 0.254) (layer "F.Cu") (net 224))
  (segment (start 109.391 67.037) (end 110.245 66.183) (width 0.254) (layer "F.Cu") (net 224))
  (via (at 109.391 67.902) (size 0.5) (drill 0.15) (layers "F.Cu" "B.Cu") (net 224))
  (segment (start 109.39 67.893) (end 109.39 66.981) (width 0.4) (layer "B.Cu") (net 224))
  (segment (start 109.39 67.901) (end 109.391 67.902) (width 0.254) (layer "B.Cu") (net 224))
  (segment (start 109.39 67.893) (end 109.39 67.901) (width 0.254) (layer "B.Cu") (net 224))
  (segment (start 91.9 60.356) (end 90.765 59.221) (width 0.254) (layer "F.Cu") (net 225))
  (segment (start 93.071499 72.15047) (end 92.19447 72.15047) (width 0.254) (layer "F.Cu") (net 225))
  (segment (start 90.765 59.221) (end 90.765 58.106) (width 0.254) (layer "F.Cu") (net 225))
  (segment (start 91.9 71.856) (end 91.9 60.356) (width 0.254) (layer "F.Cu") (net 225))
  (segment (start 92.19447 72.15047) (end 91.9 71.856) (width 0.254) (layer "F.Cu") (net 225))
  (segment (start 93.775 60.696465) (end 93.070995 61.40047) (width 0.254) (layer "F.Cu") (net 226))
  (segment (start 93.775 60.696465) (end 93.775 58.106) (width 0.254) (layer "F.Cu") (net 226))
  (segment (start 119.86 76.73) (end 119.86 76.71) (width 0.15) (layer "F.Cu") (net 227))
  (segment (start 84.18 81.69) (end 79.99 81.69) (width 0.15) (layer "F.Cu") (net 227))
  (segment (start 103.558908 75.655) (end 93.965191 75.655) (width 0.15) (layer "F.Cu") (net 227))
  (segment (start 173.94 59.7) (end 172.97772 58.73772) (width 0.2) (layer "F.Cu") (net 227))
  (segment (start 119.86 76.71) (end 118.02 74.87) (width 0.15) (layer "F.Cu") (net 227))
  (segment (start 93.940191 75.63) (end 90.24 75.63) (width 0.15) (layer "F.Cu") (net 227))
  (segment (start 118.02 74.87) (end 104.343908 74.87) (width 0.15) (layer "F.Cu") (net 227))
  (segment (start 104.343908 74.87) (end 103.558908 75.655) (width 0.15) (layer "F.Cu") (net 227))
  (segment (start 90.24 75.63) (end 84.18 81.69) (width 0.15) (layer "F.Cu") (net 227))
  (segment (start 178.00091 63.333) (end 179.877 63.333) (width 0.15) (layer "F.Cu") (net 227))
  (segment (start 169.712936 68.167064) (end 171.78 66.1) (width 0.15) (layer "F.Cu") (net 227))
  (segment (start 177.56 60.42) (end 177.39 60.25) (width 0.2) (layer "F.Cu") (net 227))
  (segment (start 175.634 60.25) (end 175.084 59.7) (width 0.2) (layer "F.Cu") (net 227))
  (segment (start 150.680209 68.167064) (end 169.712936 68.167064) (width 0.15) (layer "F.Cu") (net 227))
  (segment (start 177.39 60.25) (end 175.634 60.25) (width 0.2) (layer "F.Cu") (net 227))
  (segment (start 93.965191 75.655) (end 93.940191 75.63) (width 0.15) (layer "F.Cu") (net 227))
  (segment (start 175.23391 66.1) (end 178.00091 63.333) (width 0.15) (layer "F.Cu") (net 227))
  (segment (start 175.084 59.7) (end 173.94 59.7) (width 0.2) (layer "F.Cu") (net 227))
  (segment (start 172.97772 58.73772) (end 172.97772 58.26168) (width 0.2) (layer "F.Cu") (net 227))
  (segment (start 171.78 66.1) (end 175.23391 66.1) (width 0.15) (layer "F.Cu") (net 227))
  (via (at 177.56 60.42) (size 0.5) (drill 0.15) (layers "F.Cu" "B.Cu") (net 227))
  (via (at 150.680209 68.167064) (size 0.5) (drill 0.15) (layers "F.Cu" "B.Cu") (net 227))
  (via (at 179.877 63.333) (size 0.5) (drill 0.15) (layers "F.Cu" "B.Cu") (net 227))
  (via (at 119.86 76.73) (size 0.5) (drill 0.15) (layers "F.Cu" "B.Cu") (net 227))
  (segment (start 122.387 79.077) (end 142.95027 79.077) (width 0.15) (layer "B.Cu") (net 227))
  (segment (start 120.04 76.73) (end 122.387 79.077) (width 0.15) (layer "B.Cu") (net 227))
  (segment (start 142.95727 79.07) (end 143.9 79.07) (width 0.15) (layer "B.Cu") (net 227))
  (segment (start 179.877 60.997) (end 179.877 63.333) (width 0.2) (layer "B.Cu") (net 227))
  (segment (start 149.82 73.15) (end 149.82 69.027273) (width 0.15) (layer "B.Cu") (net 227))
  (segment (start 179.3 60.42) (end 179.877 60.997) (width 0.2) (layer "B.Cu") (net 227))
  (segment (start 119.86 76.73) (end 120.04 76.73) (width 0.15) (layer "B.Cu") (net 227))
  (segment (start 149.82 69.027273) (end 150.680209 68.167064) (width 0.15) (layer "B.Cu") (net 227))
  (segment (start 177.56 60.42) (end 179.3 60.42) (width 0.2) (layer "B.Cu") (net 227))
  (segment (start 142.95027 79.077) (end 142.95727 79.07) (width 0.15) (layer "B.Cu") (net 227))
  (segment (start 143.9 79.07) (end 149.82 73.15) (width 0.15) (layer "B.Cu") (net 227))
  (segment (start 110.97301 62.373) (end 109.39 63.95601) (width 0.254) (layer "F.Cu") (net 228))
  (segment (start 112.487 62.373) (end 110.97301 62.373) (width 0.254) (layer "F.Cu") (net 228))
  (via (at 109.39 63.95601) (size 0.5) (drill 0.15) (layers "F.Cu" "B.Cu") (net 228))
  (segment (start 109.39 63.171) (end 109.39 63.95601) (width 0.4) (layer "B.Cu") (net 228))
  (via (at 106.306 66.512) (size 0.5) (drill 0.15) (layers "F.Cu" "B.Cu") (net 230))
  (via (at 95.511 59.512) (size 0.5) (drill 0.15) (layers "F.Cu" "B.Cu") (net 230))
  (via (at 100.651 59.132) (size 0.5) (drill 0.15) (layers "F.Cu" "B.Cu") (net 230))
  (segment (start 95.512 59.511) (end 95.511 59.512) (width 1) (layer "B.Cu") (net 230))
  (segment (start 106.306 64.857) (end 106.306 66.512) (width 1) (layer "B.Cu") (net 230))
  (segment (start 102.018 59.13) (end 100.653 59.13) (width 1) (layer "B.Cu") (net 230))
  (segment (start 96.831 59.511) (end 95.512 59.511) (width 1) (layer "B.Cu") (net 230))
  (segment (start 100.653 59.13) (end 100.651 59.132) (width 1) (layer "B.Cu") (net 230))
  (segment (start 102.786 69.544) (end 101.008 69.544) (width 1.25) (layer "F.Cu") (net 231))
  (via (at 83.9 92.081) (size 0.5) (drill 0.15) (layers "F.Cu" "B.Cu") (free) (net 231))
  (via (at 84.05 92.931) (size 0.5) (drill 0.15) (layers "F.Cu" "B.Cu") (free) (net 231))
  (via (at 84.7 93.581) (size 0.5) (drill 0.15) (layers "F.Cu" "B.Cu") (free) (net 231))
  (via (at 102.786 69.544) (size 0.5) (drill 0.15) (layers "F.Cu" "B.Cu") (net 231))
  (via (at 101.897 69.544) (size 0.5) (drill 0.15) (layers "F.Cu" "B.Cu") (net 231))
  (via (at 101.008 69.544) (size 0.5) (drill 0.15) (layers "F.Cu" "B.Cu") (net 231))
  (segment (start 101.008 67.385) (end 101.008 69.951) (width 0.75) (layer "B.Cu") (net 231))
  (segment (start 100.5 66.877) (end 101.008 67.385) (width 0.75) (layer "B.Cu") (net 231))
  (segment (start 97.706 66.877) (end 100.5 66.877) (width 0.75) (layer "B.Cu") (net 231))
  (segment (start 97.243 67.34) (end 97.706 66.877) (width 0.75) (layer "B.Cu") (net 231))
  (segment (start 97.243 68.584) (end 97.243 67.34) (width 0.75) (layer "B.Cu") (net 231))
  (segment (start 98.693 72.266) (end 101.008 69.951) (width 0.75) (layer "B.Cu") (net 231))
  (segment (start 98.693 74.266) (end 98.693 72.266) (width 0.75) (layer "B.Cu") (net 231))
  (segment (start 101.008 69.544) (end 102.786 69.544) (width 1.25) (layer "B.Cu") (net 231))
  (segment (start 160.17772 61.34168) (end 160.17772 61.90628) (width 0.2) (layer "F.Cu") (net 232))
  (segment (start 160.17772 61.90628) (end 159.834 62.25) (width 0.2) (layer "F.Cu") (net 232))
  (segment (start 161.77772 62.2) (end 161.82772 62.25) (width 0.2) (layer "F.Cu") (net 232))
  (segment (start 93.22 84.83) (end 92.64 84.25) (width 0.5) (layer "F.Cu") (net 232))
  (segment (start 100.315 86.475) (end 100.90648 87.06648) (width 0.254) (layer "F.Cu") (net 232))
  (segment (start 167.9194 74.1426) (end 165.262 76.8) (width 0.2) (layer "F.Cu") (net 232))
  (segment (start 78.591 80.791) (end 79.04 81.24) (width 0.15) (layer "F.Cu") (net 232))
  (segment (start 87.25 84.25) (end 86.515 84.985) (width 0.5) (layer "F.Cu") (net 232))
  (segment (start 92.805 58.106) (end 92.805 58.77) (width 0.254) (layer "F.Cu") (net 232))
  (segment (start 104.758638 87.06648) (end 104.963281 87.271123) (width 0.254) (layer "F.Cu") (net 232))
  (segment (start 75.821 80.791) (end 78.591 80.791) (width 0.15) (layer "F.Cu") (net 232))
  (segment (start 92.805 58.106) (end 91.735 58.106) (width 0.254) (layer "F.Cu") (net 232))
  (segment (start 100.90648 87.06648) (end 104.758638 87.06648) (width 0.254) (layer "F.Cu") (net 232))
  (segment (start 173.3872 82.6968) (end 173.384 82.7) (width 0.4) (layer "F.Cu") (net 232))
  (segment (start 92.805 58.77) (end 92.8 58.775) (width 0.254) (layer "F.Cu") (net 232))
  (segment (start 84.644 84.985) (end 84.407 85.222) (width 0.5) (layer "F.Cu") (net 232))
  (segment (start 165.262 76.8) (end 163.6 76.8) (width 0.2) (layer "F.Cu") (net 232))
  (segment (start 95.275 86.475) (end 100.315 86.475) (width 0.254) (layer "F.Cu") (net 232))
  (segment (start 174.285 83.916) (end 174.285 85.265) (width 0.4) (layer "F.Cu") (net 232))
  (segment (start 174.285 82.9) (end 174.285 83.916) (width 0.4) (layer "F.Cu") (net 232))
  (segment (start 80.791091 84.11) (end 81.76 84.11) (width 0.15) (layer "F.Cu") (net 232))
  (segment (start 128.2858 68.8842) (end 128.2858 69.6342) (width 0.15) (layer "F.Cu") (net 232))
  (segment (start 174.2802 82.6968) (end 173.3872 82.6968) (width 0.4) (layer "F.Cu") (net 232))
  (segment (start 86.515 84.985) (end 84.644 84.985) (width 0.5) (layer "F.Cu") (net 232))
  (segment (start 161.77772 61.34168) (end 161.77772 62.2) (width 0.2) (layer "F.Cu") (net 232))
  (segment (start 79.04 82.358909) (end 80.791091 84.11) (width 0.15) (layer "F.Cu") (net 232))
  (segment (start 94.66 85.86) (end 95.275 86.475) (width 0.254) (layer "F.Cu") (net 232))
  (segment (start 92.64 84.25) (end 87.25 84.25) (width 0.5) (layer "F.Cu") (net 232))
  (segment (start 160.57772 62) (end 160.52772 62.05) (width 0.2) (layer "F.Cu") (net 232))
  (segment (start 93.22 85.86) (end 94.66 85.86) (width 0.254) (layer "F.Cu") (net 232))
  (segment (start 160.57772 61.34168) (end 160.57772 62) (width 0.2) (layer "F.Cu") (net 232))
  (segment (start 79.04 81.24) (end 79.04 82.358909) (width 0.15) (layer "F.Cu") (net 232))
  (segment (start 93.22 85.86) (end 93.22 84.83) (width 0.5) (layer "F.Cu") (net 232))
  (via (at 153 84.1) (size 0.5) (drill 0.15) (layers "F.Cu" "B.Cu") (net 232))
  (via (at 153 82.5) (size 0.5) (drill 0.15) (layers "F.Cu" "B.Cu") (net 232))
  (via (at 153.45 83.3) (size 0.5) (drill 0.15) (layers "F.Cu" "B.Cu") (net 232))
  (via (at 153.9 82.5) (size 0.5) (drill 0.15) (layers "F.Cu" "B.Cu") (net 232))
  (via (at 151.9352 74.1864) (size 0.5) (drill 0.15) (layers "F.Cu" "B.Cu") (net 232))
  (via (at 159.834 62.25) (size 0.5) (drill 0.15) (layers "F.Cu" "B.Cu") (net 232))
  (via (at 167.9194 74.1426) (size 0.5) (drill 0.15) (layers "F.Cu" "B.Cu") (net 232))
  (via (at 160.52772 62.05) (size 0.5) (drill 0.15) (layers "F.Cu" "B.Cu") (net 232))
  (via (at 92.8 58.775) (size 0.5) (drill 0.15) (layers "F.Cu" "B.Cu") (net 232))
  (via (at 152.9258 74.1864) (size 0.5) (drill 0.15) (layers "F.Cu" "B.Cu") (net 232))
  (via (at 104.963281 87.271123) (size 0.5) (drill 0.15) (layers "F.Cu" "B.Cu") (net 232))
  (via (at 128.2858 69.6342) (size 0.5) (drill 0.15) (layers "F.Cu" "B.Cu") (net 232))
  (via (at 93.22 85.86) (size 0.5) (drill 0.15) (layers "F.Cu" "B.Cu") (net 232))
  (via (at 84.407 85.222) (size 0.5) (drill 0.15) (layers "F.Cu" "B.Cu") (net 232))
  (via (at 173.384 82.7) (size 0.5) (drill 0.15) (layers "F.Cu" "B.Cu") (net 232))
  (via (at 161.82772 62.25) (size 0.5) (drill 0.15) (layers "F.Cu" "B.Cu") (net 232))
  (via (at 81.76 84.11) (size 0.5) (drill 0.15) (layers "F.Cu" "B.Cu") (net 232))
  (segment (start 93.77 86.87) (end 94.22856 86.87) (width 0.254) (layer "B.Cu") (net 232))
  (segment (start 84.399554 85.229446) (end 84.407 85.222) (width 0.5) (layer "B.Cu") (net 232))
  (segment (start 98.4455 86.8695) (end 99.4615 86.8695) (width 0.254) (layer "B.Cu") (net 232))
  (segment (start 76.418042 85.229446) (end 84.399554 85.229446) (width 0.5) (layer "B.Cu") (net 232))
  (segment (start 93.22 86.32) (end 93.77 86.87) (width 0.254) (layer "B.Cu") (net 232))
  (segment (start 153 84.1) (end 152.1 84.1) (width 0.254) (layer "B.Cu") (net 232))
  (segment (start 94.3815 86.8695) (end 95.3975 86.8695) (width 0.254) (layer "B.Cu") (net 232))
  (segment (start 93.22 85.86) (end 93.22 86.32) (width 0.254) (layer "B.Cu") (net 232))
  (segment (start 81.76 85.07) (end 81.912 85.222) (width 0.2) (layer "B.Cu") (net 232))
  (segment (start 151.9352 74.1864) (end 152.9258 74.1864) (width 0.2) (layer "B.Cu") (net 232))
  (segment (start 96.4135 86.8695) (end 97.4295 86.8695) (width 0.254) (layer "B.Cu") (net 232))
  (segment (start 81.912 85.222) (end 84.407 85.222) (width 0.2) (layer "B.Cu") (net 232))
  (segment (start 81.76 84.11) (end 81.76 85.07) (width 0.2) (layer "B.Cu") (net 232))
  (segment (start 95.3975 86.8695) (end 96.4135 86.8695) (width 0.254) (layer "B.Cu") (net 232))
  (segment (start 152.1 84.1) (end 151.6 83.6) (width 0.254) (layer "B.Cu") (net 232))
  (segment (start 98.4455 86.8695) (end 97.4295 86.8695) (width 0.254) (layer "B.Cu") (net 232))
  (segment (start 77.989 82.291) (end 78.52 81.76) (width 0.2) (layer "F.Cu") (net 233))
  (segment (start 75.821 82.291) (end 77.989 82.291) (width 0.2) (layer "F.Cu") (net 233))
  (segment (start 160.697488 80.571213) (end 162.468701 78.8) (width 0.18) (layer "F.Cu") (net 235))
  (segment (start 80.648721 86.723) (end 80.783721 86.858) (width 0.18) (layer "F.Cu") (net 235))
  (segment (start 160.697488 80.797488) (end 160.697488 80.571213) (width 0.18) (layer "F.Cu") (net 235))
  (segment (start 89.965 86.728403) (end 89.965 85.652298) (width 0.18) (layer "F.Cu") (net 235))
  (segment (start 89.403702 85.091) (end 87.696298 85.091) (width 0.18) (layer "F.Cu") (net 235))
  (segment (start 81.835 86.806) (end 81.270528 86.806) (width 0.18) (layer "F.Cu") (net 235))
  (segment (start 81.002528 86.858) (end 81.162528 86.698) (width 0.18) (layer "F.Cu") (net 235))
  (segment (start 85.3425 86.698) (end 85.5025 86.858) (width 0.18) (layer "F.Cu") (net 235))
  (segment (start 80.783721 86.858) (end 81.002528 86.858) (width 0.18) (layer "F.Cu") (net 235))
  (segment (start 85.5025 86.858) (end 85.929298 86.858) (width 0.18) (layer "F.Cu") (net 235))
  (segment (start 79.61372 86.723) (end 80.648721 86.723) (width 0.18) (layer "F.Cu") (net 235))
  (segment (start 89.22619 87.693488) (end 89.22619 87.467213) (width 0.18) (layer "F.Cu") (net 235))
  (segment (start 89.965 85.652298) (end 89.403702 85.091) (width 0.18) (layer "F.Cu") (net 235))
  (segment (start 85.929298 86.858) (end 87.696298 85.091) (width 0.18) (layer "F.Cu") (net 235))
  (segment (start 89.22619 87.467213) (end 89.965 86.728403) (width 0.18) (layer "F.Cu") (net 235))
  (segment (start 162.468701 78.8) (end 163.6 78.8) (width 0.18) (layer "F.Cu") (net 235))
  (segment (start 81.270528 86.806) (end 81.162528 86.698) (width 0.18) (layer "F.Cu") (net 235))
  (via (at 85.3425 86.698) (size 0.5) (drill 0.15) (layers "F.Cu" "B.Cu") (net 235))
  (via (at 81.162528 86.698) (size 0.5) (drill 0.15) (layers "F.Cu" "B.Cu") (net 235))
  (via (at 89.22619 87.693488) (size 0.5) (drill 0.15) (layers "F.Cu" "B.Cu") (net 235))
  (via (at 160.697488 80.797488) (size 0.5) (drill 0.15) (layers "F.Cu" "B.Cu") (net 235))
  (segment (start 118.896298 78.915) (end 121.071298 81.09) (width 0.18) (layer "B.Cu") (net 235))
  (segment (start 147.1275 80.9) (end 147.1275 81.405083) (width 0.18) (layer "B.Cu") (net 235))
  (segment (start 148.1925 81.405083) (end 148.1925 81.215082) (width 0.18) (layer "B.Cu") (net 235))
  (segment (start 115.978702 78.915) (end 118.896298 78.915) (width 0.18) (layer "B.Cu") (net 235))
  (segment (start 121.071298 81.09) (end 146.29 81.09) (width 0.18) (layer "B.Cu") (net 235))
  (segment (start 90.6 87.936) (end 100.564 87.936) (width 0.18) (layer "B.Cu") (net 235))
  (segment (start 108.86 79.64) (end 115.253702 79.64) (width 0.18) (layer "B.Cu") (net 235))
  (segment (start 115.253702 79.64) (end 115.978702 78.915) (width 0.18) (layer "B.Cu") (net 235))
  (segment (start 146.795082 80.584918) (end 146.795082 80.394917) (width 0.18) (layer "B.Cu") (net 235))
  (segment (start 100.564 87.936) (end 108.86 79.64) (width 0.18) (layer "B.Cu") (net 235))
  (segment (start 147.100082 80.9) (end 147.1275 80.9) (width 0.18) (layer "B.Cu") (net 235))
  (segment (start 89.22619 87.693488) (end 89.22619 87.467213) (width 0.18) (layer "B.Cu") (net 235))
  (segment (start 89.9 87.236) (end 90.6 87.936) (width 0.18) (layer "B.Cu") (net 235))
  (segment (start 85.1825 86.858) (end 85.3425 86.698) (width 0.18) (layer "B.Cu") (net 235))
  (segment (start 81.162528 86.698) (end 81.322528 86.858) (width 0.18) (layer "B.Cu") (net 235))
  (segment (start 148.317582 81.09) (end 160.178701 81.09) (width 0.18) (layer "B.Cu") (net 235))
  (segment (start 89.457403 87.236) (end 89.9 87.236) (width 0.18) (layer "B.Cu") (net 235))
  (segment (start 160.471213 80.797488) (end 160.697488 80.797488) (width 0.18) (layer "B.Cu") (net 235))
  (segment (start 89.22619 87.467213) (end 89.457403 87.236) (width 0.18) (layer "B.Cu") (net 235))
  (segment (start 146.920164 80.269835) (end 146.975 80.269835) (width 0.18) (layer "B.Cu") (net 235))
  (segment (start 147.632582 81.910165) (end 147.687418 81.910165) (width 0.18) (layer "B.Cu") (net 235))
  (segment (start 160.178701 81.09) (end 160.471213 80.797488) (width 0.18) (layer "B.Cu") (net 235))
  (segment (start 147.100082 80.394917) (end 147.100082 80.9) (width 0.18) (layer "B.Cu") (net 235))
  (segment (start 81.322528 86.858) (end 85.1825 86.858) (width 0.18) (layer "B.Cu") (net 235))
  (arc (start 146.975 80.269835) (mid 147.063446 80.306471) (end 147.100082 80.394917) (width 0.18) (layer "B.Cu") (net 235))
  (arc (start 146.795082 80.394917) (mid 146.831718 80.306471) (end 146.920164 80.269835) (width 0.18) (layer "B.Cu") (net 235))
  (arc (start 147.687418 81.910165) (mid 148.044565 81.76223) (end 148.1925 81.405083) (width 0.18) (layer "B.Cu") (net 235))
  (arc (start 147.1275 81.405083) (mid 147.275435 81.76223) (end 147.632582 81.910165) (width 0.18) (layer "B.Cu") (net 235))
  (arc (start 146.29 81.09) (mid 146.647147 80.942065) (end 146.795082 80.584918) (width 0.18) (layer "B.Cu") (net 235))
  (arc (start 148.1925 81.215082) (mid 148.229136 81.126636) (end 148.317582 81.09) (width 0.18) (layer "B.Cu") (net 235))
  (segment (start 80.783721 87.238) (end 81.002528 87.238) (width 0.18) (layer "F.Cu") (net 236))
  (segment (start 81.85 87.306) (end 81.254528 87.306) (width 0.18) (layer "F.Cu") (net 236))
  (segment (start 89.246298 85.471) (end 87.853702 85.471) (width 0.18) (layer "F.Cu") (net 236))
  (segment (start 81.002528 87.238) (end 81.162528 87.398) (width 0.18) (layer "F.Cu") (net 236))
  (segment (start 79.61372 87.373) (end 80.648721 87.373) (width 0.18) (layer "F.Cu") (net 236))
  (segment (start 85.5025 87.238) (end 86.086702 87.238) (width 0.18) (layer "F.Cu") (net 236))
  (segment (start 85.3425 87.398) (end 85.5025 87.238) (width 0.18) (layer "F.Cu") (net 236))
  (segment (start 161.05 79.681299) (end 161.05 79.345) (width 0.18) (layer "F.Cu") (net 236))
  (segment (start 88.957489 87.198512) (end 89.585 86.571001) (width 0.18) (layer "F.Cu") (net 236))
  (segment (start 160.428787 80.302512) (end 161.05 79.681299) (width 0.18) (layer "F.Cu") (net 236))
  (segment (start 80.648721 87.373) (end 80.783721 87.238) (width 0.18) (layer "F.Cu") (net 236))
  (segment (start 161.05 79.345) (end 160.005 78.3) (width 0.18) (layer "F.Cu") (net 236))
  (segment (start 81.254528 87.306) (end 81.162528 87.398) (width 0.18) (layer "F.Cu") (net 236))
  (segment (start 88.731214 87.198512) (end 88.957489 87.198512) (width 0.18) (layer "F.Cu") (net 236))
  (segment (start 160.202512 80.302512) (end 160.428787 80.302512) (width 0.18) (layer "F.Cu") (net 236))
  (segment (start 89.585 86.571001) (end 89.585 85.809702) (width 0.18) (layer "F.Cu") (net 236))
  (segment (start 160.005 78.3) (end 159.2 78.3) (width 0.18) (layer "F.Cu") (net 236))
  (segment (start 86.086702 87.238) (end 87.853702 85.471) (width 0.18) (layer "F.Cu") (net 236))
  (segment (start 89.585 85.809702) (end 89.246298 85.471) (width 0.18) (layer "F.Cu") (net 236))
  (via (at 160.202512 80.302512) (size 0.5) (drill 0.15) (layers "F.Cu" "B.Cu") (net 236))
  (via (at 81.162528 87.398) (size 0.5) (drill 0.15) (layers "F.Cu" "B.Cu") (net 236))
  (via (at 85.3425 87.398) (size 0.5) (drill 0.15) (layers "F.Cu" "B.Cu") (net 236))
  (via (at 88.731214 87.198512) (size 0.5) (drill 0.15) (layers "F.Cu" "B.Cu") (net 236))
  (segment (start 81.322528 87.238) (end 85.1825 87.238) (width 0.18) (layer "B.Cu") (net 236))
  (segment (start 81.162528 87.398) (end 81.322528 87.238) (width 0.18) (layer "B.Cu") (net 236))
  (segment (start 115.821298 78.535) (end 119.053702 78.535) (width 0.18) (layer "B.Cu") (net 236))
  (segment (start 146.415082 80.584918) (end 146.415082 80.394917) (width 0.18) (layer "B.Cu") (net 236))
  (segment (start 160.021299 80.71) (end 160.202512 80.528787) (width 0.18) (layer "B.Cu") (net 236))
  (segment (start 90.757404 87.556) (end 100.394 87.556) (width 0.18) (layer "B.Cu") (net 236))
  (segment (start 147.632582 81.530165) (end 147.687418 81.530165) (width 0.18) (layer "B.Cu") (net 236))
  (segment (start 148.317582 80.71) (end 160.021299 80.71) (width 0.18) (layer "B.Cu") (net 236))
  (segment (start 147.5075 80.9) (end 147.5075 81.405083) (width 0.18) (layer "B.Cu") (net 236))
  (segment (start 121.228702 80.71) (end 146.29 80.71) (width 0.18) (layer "B.Cu") (net 236))
  (segment (start 119.053702 78.535) (end 121.228702 80.71) (width 0.18) (layer "B.Cu") (net 236))
  (segment (start 88.957489 87.198512) (end 89.300001 86.856) (width 0.18) (layer "B.Cu") (net 236))
  (segment (start 85.1825 87.238) (end 85.3425 87.398) (width 0.18) (layer "B.Cu") (net 236))
  (segment (start 160.202512 80.528787) (end 160.202512 80.302512) (width 0.18) (layer "B.Cu") (net 236))
  (segment (start 146.920164 79.889835) (end 146.975 79.889835) (width 0.18) (layer "B.Cu") (net 236))
  (segment (start 147.8125 81.405083) (end 147.8125 81.215082) (width 0.18) (layer "B.Cu") (net 236))
  (segment (start 115.096298 79.26) (end 115.821298 78.535) (width 0.18) (layer "B.Cu") (net 236))
  (segment (start 147.480082 80.9) (end 147.5075 80.9) (width 0.18) (layer "B.Cu") (net 236))
  (segment (start 89.300001 86.856) (end 90.057404 86.856) (width 0.18) (layer "B.Cu") (net 236))
  (segment (start 147.480082 80.394917) (end 147.480082 80.9) (width 0.18) (layer "B.Cu") (net 236))
  (segment (start 108.69 79.26) (end 115.096298 79.26) (width 0.18) (layer "B.Cu") (net 236))
  (segment (start 90.057404 86.856) (end 90.757404 87.556) (width 0.18) (layer "B.Cu") (net 236))
  (segment (start 100.394 87.556) (end 108.69 79.26) (width 0.18) (layer "B.Cu") (net 236))
  (segment (start 88.731214 87.198512) (end 88.957489 87.198512) (width 0.18) (layer "B.Cu") (net 236))
  (arc (start 146.975 79.889835) (mid 147.332147 80.03777) (end 147.480082 80.394917) (width 0.18) (layer "B.Cu") (net 236))
  (arc (start 146.29 80.71) (mid 146.378446 80.673364) (end 146.415082 80.584918) (width 0.18) (layer "B.Cu") (net 236))
  (arc (start 147.5075 81.405083) (mid 147.544136 81.493529) (end 147.632582 81.530165) (width 0.18) (layer "B.Cu") (net 236))
  (arc (start 147.8125 81.215082) (mid 147.960435 80.857935) (end 148.317582 80.71) (width 0.18) (layer "B.Cu") (net 236))
  (arc (start 147.687418 81.530165) (mid 147.775864 81.493529) (end 147.8125 81.405083) (width 0.18) (layer "B.Cu") (net 236))
  (arc (start 146.415082 80.394917) (mid 146.563017 80.03777) (end 146.920164 79.889835) (width 0.18) (layer "B.Cu") (net 236))
  (segment (start 184.001039 84.455) (end 182.653564 85.802475) (width 0.2) (layer "F.Cu") (net 237))
  (segment (start 193.112658 86.002658) (end 191.565 84.455) (width 0.2) (layer "F.Cu") (net 237))
  (segment (start 191.565 84.455) (end 184.001039 84.455) (width 0.2) (layer "F.Cu") (net 237))
  (segment (start 156.55 81.05) (end 156.55 73.43222) (width 0.2) (layer "F.Cu") (net 237))
  (segment (start 156.55 73.43222) (end 155.18288 72.0651) (width 0.2) (layer "F.Cu") (net 237))
  (segment (start 157.25 81.75) (end 156.55 81.05) (width 0.2) (layer "F.Cu") (net 237))
  (segment (start 194.067342 86.002658) (end 193.112658 86.002658) (width 0.2) (layer "F.Cu") (net 237))
  (via (at 194.067342 86.002658) (size 0.5) (drill 0.15) (layers "F.Cu" "B.Cu") (net 237))
  (via (at 157.25 81.75) (size 0.5) (drill 0.15) (layers "F.Cu" "B.Cu") (net 237))
  (via (at 182.653564 85.802475) (size 0.5) (drill 0.15) (layers "F.Cu" "B.Cu") (net 237))
  (segment (start 160.72 87.87) (end 157.75 84.9) (width 0.2) (layer "B.Cu") (net 237))
  (segment (start 202.05 75.95) (end 201.245 75.95) (width 0.127) (layer "B.Cu") (net 237))
  (segment (start 203.075 76.975) (end 202.05 75.95) (width 0.127) (layer "B.Cu") (net 237))
  (segment (start 194.067342 86.002658) (end 196.357183 88.2925) (width 0.127) (layer "B.Cu") (net 237))
  (segment (start 157.75 82.25) (end 157.25 81.75) (width 0.2) (layer "B.Cu") (net 237))
  (segment (start 182.653564 85.802475) (end 182.47904 85.976999) (width 0.2) (layer "B.Cu") (net 237))
  (segment (start 181.663001 85.976999) (end 178.9 88.74) (width 0.2) (layer "B.Cu") (net 237))
  (segment (start 182.47904 85.976999) (end 181.663001 85.976999) (width 0.2) (layer "B.Cu") (net 237))
  (segment (start 171.779 87.87) (end 160.72 87.87) (width 0.2) (layer "B.Cu") (net 237))
  (segment (start 172.649 88.74) (end 171.779 87.87) (width 0.2) (layer "B.Cu") (net 237))
  (segment (start 157.75 84.9) (end 157.75 82.25) (width 0.2) (layer "B.Cu") (net 237))
  (segment (start 178.9 88.74) (end 172.649 88.74) (width 0.2) (layer "B.Cu") (net 237))
  (segment (start 200.059265 88.2925) (end 203.075 85.276765) (width 0.127) (layer "B.Cu") (net 237))
  (segment (start 203.075 85.276765) (end 203.075 76.975) (width 0.127) (layer "B.Cu") (net 237))
  (segment (start 196.357183 88.2925) (end 200.059265 88.2925) (width 0.127) (layer "B.Cu") (net 237))
  (segment (start 183.326 84.074) (end 191.784 84.074) (width 0.2) (layer "F.Cu") (net 238))
  (segment (start 158 81.75) (end 156.93 80.68) (width 0.2) (layer "F.Cu") (net 238))
  (segment (start 182.19 85.21) (end 183.326 84.074) (width 0.2) (layer "F.Cu") (net 238))
  (segment (start 156.93 80.68) (end 156.93 73.49436) (width 0.2) (layer "F.Cu") (net 238))
  (segment (start 192.96 85.25) (end 194.02 85.25) (width 0.2) (layer "F.Cu") (net 238))
  (segment (start 191.784 84.074) (end 192.96 85.25) (width 0.2) (layer "F.Cu") (net 238))
  (segment (start 156.93 73.49436) (end 158.37916 72.0452) (width 0.2) (layer "F.Cu") (net 238))
  (via (at 158 81.75) (size 0.5) (drill 0.15) (layers "F.Cu" "B.Cu") (net 238))
  (via (at 182.19 85.21) (size 0.5) (drill 0.15) (layers "F.Cu" "B.Cu") (net 238))
  (via (at 194.002675 85.312747) (size 0.5) (drill 0.15) (layers "F.Cu" "B.Cu") (net 238))
  (segment (start 194.585781 84.729641) (end 194.002675 85.312747) (width 0.127) (layer "B.Cu") (net 238))
  (segment (start 172.78362 88.415) (end 166.11862 81.75) (width 0.2) (layer "B.Cu") (net 238))
  (segment (start 182.19 85.21) (end 181.796 85.21) (width 0.2) (layer "B.Cu") (net 238))
  (segment (start 202.823 78.230633) (end 202.69 78.363633) (width 0.127) (layer "B.Cu") (net 238))
  (segment (start 201.245 76.45) (end 202.105633 76.45) (width 0.127) (layer "B.Cu") (net 238))
  (segment (start 178.591 88.415) (end 172.78362 88.415) (width 0.2) (layer "B.Cu") (net 238))
  (segment (start 181.796 85.21) (end 178.591 88.415) (width 0.2) (layer "B.Cu") (net 238))
  (segment (start 202.105633 76.45) (end 202.823 77.167367) (width 0.127) (layer "B.Cu") (net 238))
  (segment (start 166.11862 81.75) (end 158 81.75) (width 0.2) (layer "B.Cu") (net 238))
  (segment (start 201.796359 84.729641) (end 194.585781 84.729641) (width 0.127) (layer "B.Cu") (net 238))
  (segment (start 202.823 77.167367) (end 202.823 78.230633) (width 0.127) (layer "B.Cu") (net 238))
  (segment (start 202.69 83.836) (end 201.796359 84.729641) (width 0.127) (layer "B.Cu") (net 238))
  (segment (start 202.69 78.363633) (end 202.69 83.836) (width 0.127) (layer "B.Cu") (net 238))
  (segment (start 172.21 82.61) (end 172.21 84.79) (width 0.18) (layer "F.Cu") (net 239))
  (segment (start 202.685 81.921298) (end 202.540649 82.065649) (width 0.18) (layer "F.Cu") (net 239))
  (segment (start 202.116384 82.065649) (end 202.051841 82.001106) (width 0.18) (layer "F.Cu") (net 239))
  (segment (start 200.121298 84.485) (end 194.283701 84.485) (width 0.18) (layer "F.Cu") (net 239))
  (segment (start 201.69212 82.914177) (end 200.121298 84.485) (width 0.18) (layer "F.Cu") (net 239))
  (segment (start 201.692119 82.914176) (end 201.69212 82.914177) (width 0.18) (layer "F.Cu") (net 239))
  (segment (start 173.41 81.41) (end 172.21 82.61) (width 0.18) (layer "F.Cu") (net 239))
  (segment (start 171.171 85.829) (end 169.949 85.829) (width 0.18) (layer "F.Cu") (net 239))
  (segment (start 172.21 84.79) (end 171.171 85.829) (width 0.18) (layer "F.Cu") (net 239))
  (segment (start 201.627577 82.42537) (end 201.692119 82.489912) (width 0.18) (layer "F.Cu") (net 239))
  (segment (start 202.547098 78.049) (end 202.685 78.186902) (width 0.18) (layer "F.Cu") (net 239))
  (segment (start 191.208701 81.41) (end 173.41 81.41) (width 0.18) (layer "F.Cu") (net 239))
  (segment (start 194.283701 84.485) (end 191.208701 81.41) (width 0.18) (layer "F.Cu") (net 239))
  (segment (start 202.685 78.186902) (end 202.685 81.921298) (width 0.18) (layer "F.Cu") (net 239))
  (segment (start 202.116383 82.065649) (end 202.116384 82.065649) (width 0.18) (layer "F.Cu") (net 239))
  (segment (start 202.3845 78.049) (end 202.547098 78.049) (width 0.18) (layer "F.Cu") (net 239))
  (via (at 202.3845 78.049) (size 0.5) (drill 0.15) (layers "F.Cu" "B.Cu") (net 239))
  (arc (start 202.051841 82.001106) (mid 201.839709 81.913238) (end 201.627577 82.001106) (width 0.18) (layer "F.Cu") (net 239))
  (arc (start 201.627577 82.001106) (mid 201.539709 82.213238) (end 201.627577 82.42537) (width 0.18) (layer "F.Cu") (net 239))
  (arc (start 202.540649 82.065649) (mid 202.328516 82.153517) (end 202.116383 82.065649) (width 0.18) (layer "F.Cu") (net 239))
  (arc (start 201.692119 82.489912) (mid 201.779987 82.702044) (end 201.692119 82.914176) (width 0.18) (layer "F.Cu") (net 239))
  (segment (start 202.2245 77.889) (end 202.3845 78.049) (width 0.18) (layer "B.Cu") (net 239))
  (segment (start 201.91 77.949) (end 201.97 77.889) (width 0.18) (layer "B.Cu") (net 239))
  (segment (start 201.97 77.889) (end 202.2245 77.889) (width 0.18) (layer "B.Cu") (net 239))
  (segment (start 201.245 77.949) (end 201.91 77.949) (width 0.18) (layer "B.Cu") (net 239))
  (segment (start 173.54 81.79) (end 172.54 82.79) (width 0.18) (layer "F.Cu") (net 240))
  (segment (start 191.051299 81.79) (end 173.54 81.79) (width 0.18) (layer "F.Cu") (net 240))
  (segment (start 203.065 78.0295) (end 203.065 82.078702) (width 0.18) (layer "F.Cu") (net 240))
  (segment (start 173.544 86.329) (end 174.349 86.329) (width 0.18) (layer "F.Cu") (net 240))
  (segment (start 172.54 82.79) (end 172.54 85.325) (width 0.18) (layer "F.Cu") (net 240))
  (segment (start 203.065 82.078702) (end 200.278702 84.865) (width 0.18) (layer "F.Cu") (net 240))
  (segment (start 200.278702 84.865) (end 194.126299 84.865) (width 0.18) (layer "F.Cu") (net 240))
  (segment (start 202.3845 77.349) (end 203.065 78.0295) (width 0.18) (layer "F.Cu") (net 240))
  (segment (start 194.126299 84.865) (end 191.051299 81.79) (width 0.18) (layer "F.Cu") (net 240))
  (segment (start 172.54 85.325) (end 173.544 86.329) (width 0.18) (layer "F.Cu") (net 240))
  (via (at 202.3845 77.349) (size 0.5) (drill 0.15) (layers "F.Cu" "B.Cu") (net 240))
  (segment (start 201.245 77.449) (end 201.91 77.449) (width 0.18) (layer "B.Cu") (net 240))
  (segment (start 201.97 77.509) (end 202.2245 77.509) (width 0.18) (layer "B.Cu") (net 240))
  (segment (start 201.91 77.449) (end 201.97 77.509) (width 0.18) (layer "B.Cu") (net 240))
  (segment (start 202.2245 77.509) (end 202.3845 77.349) (width 0.18) (layer "B.Cu") (net 240))
  (segment (start 166.97772 59.69228) (end 166.97772 58.26168) (width 0.2) (layer "F.Cu") (net 241))
  (segment (start 166.83 59.84) (end 166.97772 59.69228) (width 0.2) (layer "F.Cu") (net 241))
  (segment (start 157.4292 71.0636) (end 158.39708 71.0636) (width 0.2) (layer "F.Cu") (net 241))
  (via (at 166.83 59.84) (size 0.5) (drill 0.15) (layers "F.Cu" "B.Cu") (net 241))
  (via (at 157.4292 71.0636) (size 0.5) (drill 0.15) (layers "F.Cu" "B.Cu") (net 241))
  (segment (start 166.83 59.987053) (end 166.42 60.397053) (width 0.2) (layer "B.Cu") (net 241))
  (segment (start 171.911061 66.439309) (end 172.189309 66.717557) (width 0.2) (layer "B.Cu") (net 241))
  (segment (start 162.841477 66.439309) (end 171.911061 66.439309) (width 0.2) (layer "B.Cu") (net 241))
  (segment (start 172.189309 66.717557) (end 172.189309 67.282443) (width 0.2) (layer "B.Cu") (net 241))
  (segment (start 170.896752 68.575) (end 159.9178 68.575) (width 0.2) (layer "B.Cu") (net 241))
  (segment (start 166.42 62.860786) (end 162.841477 66.439309) (width 0.2) (layer "B.Cu") (net 241))
  (segment (start 166.83 59.84) (end 166.83 59.987053) (width 0.2) (layer "B.Cu") (net 241))
  (segment (start 172.189309 67.282443) (end 170.896752 68.575) (width 0.2) (layer "B.Cu") (net 241))
  (segment (start 159.9178 68.575) (end 157.4292 71.0636) (width 0.2) (layer "B.Cu") (net 241))
  (segment (start 166.42 60.397053) (end 166.42 62.860786) (width 0.2) (layer "B.Cu") (net 241))
  (segment (start 166.17772 59.847714) (end 166.1795 59.849494) (width 0.2) (layer "F.Cu") (net 242))
  (segment (start 166.17772 58.26168) (end 166.17772 59.847714) (width 0.2) (layer "F.Cu") (net 242))
  (segment (start 155.92798 70.35) (end 155.18288 71.0951) (width 0.2) (layer "F.Cu") (net 242))
  (segment (start 156 70.35) (end 155.92798 70.35) (width 0.2) (layer "F.Cu") (net 242))
  (via (at 166.1795 59.849494) (size 0.5) (drill 0.15) (layers "F.Cu" "B.Cu") (net 242))
  (via (at 156 70.35) (size 0.5) (drill 0.15) (layers "F.Cu" "B.Cu") (net 242))
  (segment (start 165.934 62.85) (end 166.04 62.744) (width 0.2) (layer "B.Cu") (net 242))
  (segment (start 157.48 64.604) (end 159.234 62.85) (width 0.2) (layer "B.Cu") (net 242))
  (segment (start 156 70.35) (end 157.48 68.87) (width 0.2) (layer "B.Cu") (net 242))
  (segment (start 166.04 59.988994) (end 166.1795 59.849494) (width 0.2) (layer "B.Cu") (net 242))
  (segment (start 159.234 62.85) (end 165.934 62.85) (width 0.2) (layer "B.Cu") (net 242))
  (segment (start 166.04 62.744) (end 166.04 59.988994) (width 0.2) (layer "B.Cu") (net 242))
  (segment (start 157.48 68.87) (end 157.48 64.604) (width 0.2) (layer "B.Cu") (net 242))
  (segment (start 152.35 57.55) (end 151.892 58.008) (width 0.15) (layer "F.Cu") (net 243))
  (segment (start 158.57772 58.26168) (end 158.57772 57.822658) (width 0.15) (layer "F.Cu") (net 243))
  (segment (start 158.305062 57.55) (end 152.35 57.55) (width 0.15) (layer "F.Cu") (net 243))
  (segment (start 158.57772 57.822658) (end 158.305062 57.55) (width 0.15) (layer "F.Cu") (net 243))
  (segment (start 149.48569 62.78569) (end 149.488 62.788) (width 0.2) (layer "F.Cu") (net 244))
  (segment (start 155.233974 63.43) (end 151.564 63.43) (width 0.2) (layer "F.Cu") (net 244))
  (segment (start 121.849022 60.55) (end 120.6 60.55) (width 0.2) (layer "F.Cu") (net 244))
  (segment (start 124.62452 57.774502) (end 121.849022 60.55) (width 0.2) (layer "F.Cu") (net 244))
  (segment (start 124.62452 57.5305) (end 124.62452 57.774502) (width 0.2) (layer "F.Cu") (net 244))
  (segment (start 159.9946 73.1104) (end 158.93 74.175) (width 0.2) (layer "F.Cu") (net 244))
  (segment (start 159.9946 72.0796) (end 159.9946 73.1104) (width 0.2) (layer "F.Cu") (net 244))
  (segment (start 151.564 63.43) (end 150.922 62.788) (width 0.2) (layer "F.Cu") (net 244))
  (segment (start 149.488 62.788) (end 150.922 62.788) (width 0.15) (layer "F.Cu") (net 244))
  (segment (start 155.244487 63.419487) (end 155.233974 63.43) (width 0.2) (layer "F.Cu") (net 244))
  (via (at 159.9946 72.0796) (size 0.5) (drill 0.15) (layers "F.Cu" "B.Cu") (net 244))
  (via (at 149.48569 62.78569) (size 0.5) (drill 0.15) (layers "F.Cu" "B.Cu") (net 244))
  (via (at 155.244487 63.419487) (size 0.5) (drill 0.15) (layers "F.Cu" "B.Cu") (net 244))
  (via (at 124.62452 57.5305) (size 0.5) (drill 0.15) (layers "F.Cu" "B.Cu") (net 244))
  (segment (start 124.62452 57.5305) (end 124.62954 57.52548) (width 0.15) (layer "B.Cu") (net 244))
  (segment (start 148.858486 63.625) (end 149.48569 62.997796) (width 0.15) (layer "B.Cu") (net 244))
  (segment (start 155.25 70.8) (end 156.5296 72.0796) (width 0.2) (layer "B.Cu") (net 244))
  (segment (start 149.48569 62.997796) (end 149.48569 62.78569) (width 0.15) (layer "B.Cu") (net 244))
  (segment (start 135.881994 57.52548) (end 141.981514 63.625) (width 0.15) (layer "B.Cu") (net 244))
  (segment (start 124.62954 57.52548) (end 135.881994 57.52548) (width 0.15) (layer "B.Cu") (net 244))
  (segment (start 155.25 63.425) (end 155.25 70.8) (width 0.2) (layer "B.Cu") (net 244))
  (segment (start 155.244487 63.419487) (end 155.25 63.425) (width 0.2) (layer "B.Cu") (net 244))
  (segment (start 141.981514 63.625) (end 148.858486 63.625) (width 0.15) (layer "B.Cu") (net 244))
  (segment (start 156.5296 72.0796) (end 159.9946 72.0796) (width 0.2) (layer "B.Cu") (net 244))
  (segment (start 151.877 61.818) (end 150.922 61.818) (width 0.254) (layer "F.Cu") (net 246))
  (segment (start 150.922 61.818) (end 150.922 60.475) (width 0.254) (layer "F.Cu") (net 246))
  (segment (start 171.125 86.829) (end 173.188 88.892) (width 0.18) (layer "F.Cu") (net 247))
  (segment (start 169.949 86.829) (end 171.125 86.829) (width 0.18) (layer "F.Cu") (net 247))
  (segment (start 173.188 88.892) (end 175.808 88.892) (width 0.18) (layer "F.Cu") (net 247))
  (segment (start 176.249 88.19) (end 175.21 88.19) (width 0.254) (layer "F.Cu") (net 248))
  (segment (start 176.951 88.892) (end 176.249 88.19) (width 0.254) (layer "F.Cu") (net 248))
  (segment (start 175.21 88.19) (end 174.349 87.329) (width 0.254) (layer "F.Cu") (net 248))
  (segment (start 163.366883 75.765484) (end 163.366883 75.765483) (width 0.18) (layer "F.Cu") (net 249))
  (segment (start 164.51 75.64) (end 165.77956 74.37044) (width 0.18) (layer "F.Cu") (net 249))
  (segment (start 163.142366 75.890967) (end 163.2414 75.890967) (width 0.18) (layer "F.Cu") (net 249))
  (segment (start 162.677502 75.64) (end 162.8914 75.64) (width 0.18) (layer "F.Cu") (net 249))
  (segment (start 165.77956 74.37044) (end 165.77956 74.33512) (width 0.18) (layer "F.Cu") (net 249))
  (segment (start 162.3058 77.8) (end 161.7726 77.2668) (width 0.18) (layer "F.Cu") (net 249))
  (segment (start 163.5914 75.64) (end 164.51 75.64) (width 0.18) (layer "F.Cu") (net 249))
  (segment (start 163.6 77.8) (end 162.3058 77.8) (width 0.18) (layer "F.Cu") (net 249))
  (segment (start 161.7726 76.5556) (end 162.207327 76.120873) (width 0.18) (layer "F.Cu") (net 249))
  (segment (start 161.7726 77.2668) (end 161.7726 76.5556) (width 0.18) (layer "F.Cu") (net 249))
  (segment (start 162.207327 76.110175) (end 162.677502 75.64) (width 0.18) (layer "F.Cu") (net 249))
  (segment (start 163.016883 75.765483) (end 163.016883 75.765484) (width 0.18) (layer "F.Cu") (net 249))
  (segment (start 163.492366 75.64) (end 163.5914 75.64) (width 0.18) (layer "F.Cu") (net 249))
  (segment (start 162.207327 76.120873) (end 162.207327 76.110175) (width 0.18) (layer "F.Cu") (net 249))
  (arc (start 163.366883 75.765483) (mid 163.403636 75.676753) (end 163.492366 75.64) (width 0.18) (layer "F.Cu") (net 249))
  (arc (start 163.2414 75.890967) (mid 163.33013 75.854214) (end 163.366883 75.765484) (width 0.18) (layer "F.Cu") (net 249))
  (arc (start 163.016883 75.765484) (mid 163.053636 75.854214) (end 163.142366 75.890967) (width 0.18) (layer "F.Cu") (net 249))
  (arc (start 162.8914 75.64) (mid 162.98013 75.676753) (end 163.016883 75.765483) (width 0.18) (layer "F.Cu") (net 249))
  (segment (start 174.349 85.829) (end 175.801 85.829) (width 0.254) (layer "F.Cu") (net 250))
  (segment (start 161.417 76.3524) (end 161.417 77.089) (width 0.18) (layer "F.Cu") (net 251))
  (segment (start 161.206 77.3) (end 159.2 77.3) (width 0.18) (layer "F.Cu") (net 251))
  (segment (start 161.417 77.089) (end 161.206 77.3) (width 0.18) (layer "F.Cu") (net 251))
  (segment (start 164.95 74.76773) (end 164.45773 75.26) (width 0.18) (layer "F.Cu") (net 251))
  (segment (start 164.83004 74.33004) (end 164.95 74.45) (width 0.18) (layer "F.Cu") (net 251))
  (segment (start 164.45773 75.26) (end 162.5094 75.26) (width 0.18) (layer "F.Cu") (net 251))
  (segment (start 162.5094 75.26) (end 161.417 76.3524) (width 0.18) (layer "F.Cu") (net 251))
  (segment (start 164.95 74.45) (end 164.95 74.76773) (width 0.18) (layer "F.Cu") (net 251))
  (segment (start 164.61956 74.33004) (end 164.83004 74.33004) (width 0.18) (layer "F.Cu") (net 251))
  (segment (start 131.05 85.7) (end 131.05 83.835) (width 0.5) (layer "B.Cu") (net 252))
  (segment (start 129.685 83.8) (end 131.015 83.8) (width 0.5) (layer "B.Cu") (net 252))
  (via (at 202.6435 69.73445) (size 0.5) (drill 0.15) (layers "F.Cu" "B.Cu") (net 253))
  (via (at 202.6435 71.07815) (size 0.5) (drill 0.15) (layers "F.Cu" "B.Cu") (net 253))
  (via (at 202.6435 70.4063) (size 0.5) (drill 0.15) (layers "F.Cu" "B.Cu") (net 253))
  (via (at 202.6435 71.75) (size 0.5) (drill 0.15) (layers "F.Cu" "B.Cu") (net 253))
  (via (at 202.6505 69.0626) (size 0.5) (drill 0.15) (layers "F.Cu" "B.Cu") (net 253))
  (via (at 201.6091 69.0118) (size 0.5) (drill 0.15) (layers "F.Cu" "B.Cu") (net 253))
  (via (at 200.5677 69.0118) (size 0.5) (drill 0.15) (layers "F.Cu" "B.Cu") (net 253))
  (via (at 149.6 86.5) (size 0.5) (drill 0.15) (layers "F.Cu" "B.Cu") (net 253))
  (via (at 148 86.5) (size 0.5) (drill 0.15) (layers "F.Cu" "B.Cu") (net 253))
  (via (at 148 87.8) (size 0.5) (drill 0.15) (layers "F.Cu" "B.Cu") (net 253))
  (via (at 149.6 87.8) (size 0.5) (drill 0.15) (layers "F.Cu" "B.Cu") (net 253))
  (via (at 148.8 87.15) (size 0.5) (drill 0.15) (layers "F.Cu" "B.Cu") (net 253))
  (via (at 148 88.65) (size 0.5) (drill 0.15) (layers "F.Cu" "B.Cu") (net 253))
  (via (at 184.2008 89.7668) (size 0.5) (drill 0.15) (layers "F.Cu" "B.Cu") (free) (net 253))
  (via (at 183.5658 89.7668) (size 0.5) (drill 0.15) (layers "F.Cu" "B.Cu") (free) (net 253))
  (via (at 196.3166 89.0556) (size 0.5) (drill 0.15) (layers "F.Cu" "B.Cu") (free) (net 253))
  (via (at 149.65 88.6) (size 0.5) (drill 0.15) (layers "F.Cu" "B.Cu") (net 253))
  (via (at 184.2008 89.1826) (size 0.5) (drill 0.15) (layers "F.Cu" "B.Cu") (free) (net 253))
  (via (at 196.9516 89.7414) (size 0.5) (drill 0.15) (layers "F.Cu" "B.Cu") (free) (net 253))
  (via (at 184.8358 89.1572) (size 0.5) (drill 0.15) (layers "F.Cu" "B.Cu") (free) (net 253))
  (via (at 197.5866 89.716) (size 0.5) (drill 0.15) (layers "F.Cu" "B.Cu") (free) (net 253))
  (via (at 196.9262 89.0556) (size 0.5) (drill 0.15) (layers "F.Cu" "B.Cu") (free) (net 253))
  (via (at 197.5612 89.0556) (size 0.5) (drill 0.15) (layers "F.Cu" "B.Cu") (free) (net 253))
  (via (at 183.5658 89.1826) (size 0.5) (drill 0.15) (layers "F.Cu" "B.Cu") (free) (net 253))
  (via (at 184.8358 89.7668) (size 0.5) (drill 0.15) (layers "F.Cu" "B.Cu") (free) (net 253))
  (via (at 196.2912 89.7414) (size 0.5) (drill 0.15) (layers "F.Cu" "B.Cu") (free) (net 253))
  (segment (start 201.246 69.45) (end 201.246 69.95) (width 0.254) (layer "B.Cu") (net 253))
  (segment (start 151 87.8) (end 151.6 87.2) (width 0.254) (layer "B.Cu") (net 253))
  (segment (start 149.6 87.8) (end 151 87.8) (width 0.254) (layer "B.Cu") (net 253))
  (segment (start 87.4 91.15) (end 89.15 91.15) (width 0.15) (layer "F.Cu") (net 254))
  (segment (start 89.15 91.15) (end 89.4 91.4) (width 0.15) (layer "F.Cu") (net 254))
  (segment (start 86.4 92.15) (end 87.4 91.15) (width 0.15) (layer "F.Cu") (net 254))
  (segment (start 89.4 91.4) (end 90.073 91.4) (width 0.15) (layer "F.Cu") (net 254))
  (segment (start 94.65 90.791) (end 96.258 90.791) (width 0.254) (layer "B.Cu") (net 255))
  (segment (start 94.65 92.271) (end 96.208 92.271) (width 0.254) (layer "B.Cu") (net 256))
  (segment (start 89.8 94.1) (end 90.175 93.725) (width 0.15) (layer "F.Cu") (net 257))
  (segment (start 90.175 93.725) (end 91.099 93.725) (width 0.15) (layer "F.Cu") (net 257))
  (segment (start 89.8 95.115) (end 89.8 94.1) (width 0.15) (layer "F.Cu") (net 257))
  (segment (start 90.071 90.75) (end 86.485 90.75) (width 0.15) (layer "F.Cu") (net 258))
  (segment (start 90.073 90.748) (end 90.071 90.75) (width 0.15) (layer "F.Cu") (net 258))
  (segment (start 92.4 94.685) (end 92.4 93.725) (width 0.15) (layer "F.Cu") (net 259))
  (segment (start 92.815 95.1) (end 92.4 94.685) (width 0.15) (layer "F.Cu") (net 259))
  (segment (start 91.75 93.727) (end 91.748 93.725) (width 0.15) (layer "F.Cu") (net 260))
  (segment (start 91.75 95.065) (end 91.75 93.727) (width 0.15) (layer "F.Cu") (net 260))
  (segment (start 92.4 89.073) (end 92.4 87.585) (width 0.15) (layer "F.Cu") (net 261))
  (segment (start 93.05 89.073) (end 93.05 88.335) (width 0.15) (layer "F.Cu") (net 262))
  (segment (start 93.05 88.335) (end 93.8 87.585) (width 0.15) (layer "F.Cu") (net 262))
  (segment (start 91.748 89.073) (end 91.748 88.333) (width 0.15) (layer "F.Cu") (net 263))
  (segment (start 91.748 88.333) (end 91 87.585) (width 0.15) (layer "F.Cu") (net 263))
  (segment (start 155.447 73.6082) (end 155.447 76.8848) (width 0.254) (layer "F.Cu") (net 264))
  (segment (start 162.6694 77.3) (end 163.6 77.3) (width 0.254) (layer "F.Cu") (net 264))
  (segment (start 155.3972 73.5584) (end 155.447 73.6082) (width 0.254) (layer "F.Cu") (net 264))
  (segment (start 155.447 76.8848) (end 155.8798 77.3176) (width 0.254) (layer "F.Cu") (net 264))
  (segment (start 162.3314 76.962) (end 162.6694 77.3) (width 0.254) (layer "F.Cu") (net 264))
  (via (at 155.8798 77.3176) (size 0.5) (drill 0.15) (layers "F.Cu" "B.Cu") (net 264))
  (via (at 155.3972 73.5584) (size 0.5) (drill 0.15) (layers "F.Cu" "B.Cu") (net 264))
  (via (at 162.3314 76.962) (size 0.5) (drill 0.15) (layers "F.Cu" "B.Cu") (net 264))
  (segment (start 154.4828 73.1496) (end 154.9884 73.1496) (width 0.254) (layer "B.Cu") (net 264))
  (segment (start 155.8798 77.3176) (end 161.9758 77.3176) (width 0.254) (layer "B.Cu") (net 264))
  (segment (start 161.9758 77.3176) (end 162.3314 76.962) (width 0.254) (layer "B.Cu") (net 264))
  (segment (start 154.9884 73.1496) (end 155.3972 73.5584) (width 0.254) (layer "B.Cu") (net 264))
  (segment (start 161.75 71.5) (end 162.49872 72.24872) (width 0.2) (layer "F.Cu") (net 265))
  (segment (start 157.00604 70.2508) (end 160.4992 70.2508) (width 0.2) (layer "F.Cu") (net 265))
  (segment (start 156.18604 71.0708) (end 157.00604 70.2508) (width 0.2) (layer "F.Cu") (net 265))
  (segment (start 162.49872 72.24872) (end 163.64956 72.24872) (width 0.2) (layer "F.Cu") (net 265))
  (segment (start 160.4992 70.2508) (end 160.5 70.25) (width 0.2) (layer "F.Cu") (net 265))
  (via (at 160.5 70.25) (size 0.5) (drill 0.15) (layers "F.Cu" "B.Cu") (net 265))
  (via (at 161.75 71.5) (size 0.5) (drill 0.15) (layers "F.Cu" "B.Cu") (net 265))
  (segment (start 160.5 70.25) (end 161.75 71.5) (width 0.2) (layer "B.Cu") (net 265))
  (segment (start 166.74956 73.14872) (end 166.74956 74.33512) (width 0.2) (layer "F.Cu") (net 266))
  (segment (start 163.64956 73.14872) (end 163.64956 74.33004) (width 0.2) (layer "F.Cu") (net 267))
  (segment (start 159.53196 70.89872) (end 159.37724 71.05344) (width 0.254) (layer "F.Cu") (net 268))
  (segment (start 163.64956 70.89872) (end 159.53196 70.89872) (width 0.254) (layer "F.Cu") (net 268))
  (segment (start 95.501 90.099) (end 96.3 89.3) (width 0.15) (layer "F.Cu") (net 269))
  (segment (start 94.725 90.099) (end 95.501 90.099) (width 0.15) (layer "F.Cu") (net 269))
  (segment (start 132 85.7) (end 132 85) (width 0.25) (layer "B.Cu") (net 270))
  (segment (start 132 85) (end 133.25 83.75) (width 0.25) (layer "B.Cu") (net 270))
  (segment (start 133.25 83.75) (end 133.75 83.75) (width 0.25) (layer "B.Cu") (net 270))
  (segment (start 96.0972 90.748) (end 96.0992 90.75) (width 0.15) (layer "F.Cu") (net 271))
  (segment (start 94.76 90.75) (end 94.762 90.748) (width 0.15) (layer "F.Cu") (net 271))
  (segment (start 94.762 90.748) (end 96.0972 90.748) (width 0.15) (layer "F.Cu") (net 271))
  (segment (start 95.8 87.2508) (end 93.9778 89.073) (width 0.15) (layer "F.Cu") (net 272))
  (segment (start 93.9778 89.073) (end 93.7 89.073) (width 0.15) (layer "F.Cu") (net 272))

  (zone (net 12) (net_name "VCC5V0") (layer "F.Cu") (hatch edge 0.508)
    (connect_pads thru_hole_only (clearance 0.127))
    (min_thickness 0.254) (filled_areas_thickness no)
    (fill yes (thermal_gap 0.508) (thermal_bridge_width 0.508))
    (polygon
      (pts
        (xy 162 57.754)
        (xy 162 58.77)
        (xy 161.85 59.2)
        (xy 159.7 59.2)
        (xy 159.55 58.77)
        (xy 159.55 57.75)
        (xy 159.7 57.3)
        (xy 161.85 57.3)
      )
    )
  )
  (zone (net 11) (net_name "GND") (layer "F.Cu") (hatch edge 0.508)
    (connect_pads thru_hole_only (clearance 0.254))
    (min_thickness 0.254) (filled_areas_thickness no)
    (fill yes (thermal_gap 0.254) (thermal_bridge_width 0.376) (smoothing fillet) (radius 1))
    (polygon
      (pts
        (xy 174.8922 83.9668)
        (xy 174.8922 82.4428)
        (xy 175.0192 82.3158)
        (xy 176.0352 82.3158)
        (xy 176.6702 82.9508)
        (xy 176.6702 83.4588)
        (xy 176.0352 84.0938)
        (xy 175.0192 84.0938)
      )
    )
  )
  (zone (net 11) (net_name "GND") (layer "F.Cu") (hatch edge 0.508)
    (connect_pads thru_hole_only (clearance 0.254))
    (min_thickness 0.254) (filled_areas_thickness no)
    (fill yes (thermal_gap 0.254) (thermal_bridge_width 0.376) (smoothing fillet) (radius 1))
    (polygon
      (pts
        (xy 171.387 87.726)
        (xy 171.387 88.615)
        (xy 171.133 88.869)
        (xy 168.847 88.869)
        (xy 168.593 88.615)
        (xy 168.593 87.726)
        (xy 169.228 87.091)
        (xy 170.752 87.091)
      )
    )
  )
  (zone (net 11) (net_name "GND") (layer "F.Cu") (hatch edge 0.508)
    (connect_pads thru_hole_only (clearance 0.127))
    (min_thickness 0.254) (filled_areas_thickness no)
    (fill yes (thermal_gap 0.254) (thermal_bridge_width 0.376) (smoothing fillet) (radius 1))
    (polygon
      (pts
        (xy 80.767718 83.163757)
        (xy 80.767718 85.576757)
        (xy 80.640718 85.703757)
        (xy 78.862718 85.703757)
        (xy 78.735718 85.830757)
        (xy 78.735718 88.243757)
        (xy 78.862718 88.370757)
        (xy 80.39872 88.370757)
        (xy 80.71622 87.87104)
        (xy 82.04972 87.87104)
        (xy 82.11322 87.80754)
        (xy 82.164718 87.735757)
        (xy 82.291718 87.608757)
        (xy 83.180718 87.366)
        (xy 84.105 87.378)
        (xy 84.076 90.281)
        (xy 83.25 91.676)
        (xy 80.513718 91.672757)
        (xy 76.068718 91.672757)
        (xy 75.814718 91.418757)
        (xy 75.814718 83.417757)
        (xy 76.068718 83.163757)
        (xy 78.608718 83.163757)
        (xy 78.989718 82.782757)
        (xy 80.386718 82.782757)
      )
    )
  )
  (zone (net 253) (net_name "3V3_OUT") (layer "F.Cu") (hatch edge 0.508)
    (connect_pads (clearance 0.127))
    (min_thickness 0.254) (filled_areas_thickness no)
    (fill yes (thermal_gap 0.508) (thermal_bridge_width 0.508))
    (polygon
      (pts
        (xy 198.2216 90.05)
        (xy 183.2 90.075)
        (xy 183.2102 88.7)
        (xy 198.1962 88.7)
      )
    )
  )
  (zone (net 4) (net_name "GNDD") (layer "F.Cu") (hatch edge 0.508)
    (connect_pads yes (clearance 0.2))
    (min_thickness 0.2) (filled_areas_thickness no)
    (fill yes (thermal_gap 0.254) (thermal_bridge_width 0.376))
    (polygon
      (pts
        (xy 118.3 79.546)
        (xy 118.3 81.5)
        (xy 117.8 81.996)
        (xy 112.5 82)
        (xy 111.43 83.25)
        (xy 111.41 93.37)
        (xy 110.616 94.25)
        (xy 105.8 94.25)
        (xy 105.3 94.25)
        (xy 105.25 89)
        (xy 106 89)
        (xy 106 84.5)
        (xy 111.5 79)
        (xy 117.75 79)
      )
    )
  )
  (zone (net 12) (net_name "VCC5V0") (layer "F.Cu") (hatch edge 0.508)
    (priority 3)
    (connect_pads yes (clearance 0.254))
    (min_thickness 0.2) (filled_areas_thickness no)
    (fill yes (thermal_gap 0.2) (thermal_bridge_width 0.255) (smoothing fillet) (radius 1))
    (polygon
      (pts
        (xy 134.625 59.1)
        (xy 134.625 63)
        (xy 134.2 63.425)
        (xy 131.025 63.425)
        (xy 129.625 63.025)
        (xy 129.625 59.125)
        (xy 131.1 58.65)
        (xy 134.175 58.65)
      )
    )
  )
  (zone (net 6) (net_name "/PoE/VDD_POE_IN") (layer "F.Cu") (hatch edge 0.508)
    (connect_pads yes (clearance 0.254))
    (min_thickness 0.254) (filled_areas_thickness no)
    (fill yes (thermal_gap 0.254) (thermal_bridge_width 0.376) (smoothing fillet) (radius 1))
    (polygon
      (pts
        (xy 118.3 83.316)
        (xy 118.3 94.216)
        (xy 117.6 94.916)
        (xy 112.3 94.916)
        (xy 111.9 94.516)
        (xy 111.9 83.316)
        (xy 112.2 83.016)
        (xy 118 83.016)
      )
    )
  )
  (zone (net 5) (net_name "VSS") (layer "F.Cu") (hatch edge 0.508)
    (connect_pads yes (clearance 0.2))
    (min_thickness 0.254) (filled_areas_thickness no)
    (fill yes (thermal_gap 0.508) (thermal_bridge_width 0.508))
    (polygon
      (pts
        (xy 94 96.25)
        (xy 89.25 96.25)
        (xy 88.25 96.25)
        (xy 87.75 96.25)
        (xy 87.75 94.5)
        (xy 87.75 93.75)
        (xy 87.25 93.75)
        (xy 87.25 92.75)
        (xy 87 92.75)
        (xy 87 91.35)
        (xy 94 91.35)
      )
    )
  )
  (zone (net 6) (net_name "/PoE/VDD_POE_IN") (layer "F.Cu") (hatch edge 0.508)
    (priority 1)
    (connect_pads yes (clearance 0.2))
    (min_thickness 0.254) (filled_areas_thickness no)
    (fill yes (thermal_gap 0.508) (thermal_bridge_width 0.508))
    (polygon
      (pts
        (xy 90.7 90.3)
        (xy 85.9 90.3)
        (xy 85.9 92.8)
        (xy 87.2 92.8)
        (xy 87.2 93.7)
        (xy 88.3 93.7)
        (xy 88.3 95.3)
        (xy 85.15 95.3)
        (xy 85.15 93.3)
        (xy 84.4 92.55)
        (xy 84.4 89)
        (xy 90.7 89)
      )
    )
  )
  (zone (net 12) (net_name "VCC5V0") (layer "F.Cu") (hatch edge 0.508)
    (priority 3)
    (connect_pads yes (clearance 0.254))
    (min_thickness 0.2) (filled_areas_thickness no)
    (fill yes (thermal_gap 0.2) (thermal_bridge_width 0.255) (smoothing fillet) (radius 1))
    (polygon
      (pts
        (xy 134.85 72.6)
        (xy 134.375 73.08)
        (xy 125.31 73.08)
        (xy 124.4 74)
        (xy 124.4 78)
        (xy 123.4 79)
        (xy 123.4 88.6)
        (xy 124.5 89.8)
        (xy 124.5 92.7)
        (xy 124 93.2)
        (xy 122.4 93.2)
        (xy 120.2 91)
        (xy 120.2 77.8)
        (xy 121.2 76.8)
        (xy 121.2 71.6)
        (xy 122.4 70.395)
        (xy 134.45 70.395)
        (xy 134.85 70.8)
      )
    )
  )
  (zone (net 4) (net_name "GNDD") (layer "F.Cu") (hatch edge 0.508)
    (priority 1)
    (connect_pads yes (clearance 0.2))
    (min_thickness 0.254) (filled_areas_thickness no)
    (fill yes (thermal_gap 0.508) (thermal_bridge_width 0.508))
    (polygon
      (pts
        (xy 104.6 96.5)
        (xy 94.3 96.5)
        (xy 94.3 94.5)
        (xy 93.4 94.5)
        (xy 93.4 93.1)
        (xy 94.1 93.1)
        (xy 94.1 91.7)
        (xy 97.1 91.7)
        (xy 97.1 95)
        (xy 99.2 95)
        (xy 99.2 93.9)
        (xy 100.2 93.9)
        (xy 100.2 95)
        (xy 102.2 95)
        (xy 102.2 89)
        (xy 104.6 89)
      )
    )
  )
  (zone (net 170) (net_name "3V3_SSD") (layer "F.Cu") (hatch edge 0.508)
    (connect_pads (clearance 0.127))
    (min_thickness 0.254) (filled_areas_thickness no)
    (fill yes (thermal_gap 0.508) (thermal_bridge_width 0.508))
    (polygon
      (pts
        (xy 152.781 89.7128)
        (xy 153.7208 89.7382)
        (xy 153.6954 93.7768)
        (xy 147.193 93.7768)
        (xy 147.2438 78.6384)
        (xy 148.6408 77.2414)
        (xy 152.781 77.2414)
      )
    )
  )
  (zone (net 230) (net_name "Earth") (layer "In1.Cu") (hatch edge 0.508)
    (priority 1)
    (connect_pads thru_hole_only (clearance 0.254))
    (min_thickness 0.254) (filled_areas_thickness no)
    (fill yes (thermal_gap 0.254) (thermal_bridge_width 0.376) (smoothing fillet) (radius 1))
    (polygon
      (pts
        (xy 99.6 67.206)
        (xy 99.6 78.706)
        (xy 75.1 78.706)
        (xy 75.1 56.656)
        (xy 102.1 56.706)
        (xy 102.15 63.756)
        (xy 108.139152 63.756)
        (xy 108.139152 67.256)
      )
    )
  )
  (zone (net 11) (net_name "GND") (layer "In1.Cu") (hatch edge 0.508)
    (connect_pads thru_hole_only (clearance 0.2))
    (min_thickness 0.15) (filled_areas_thickness no)
    (fill yes (thermal_gap 0.254) (thermal_bridge_width 0.376) (smoothing fillet) (radius 1))
    (polygon
      (pts
        (xy 203.553998 96.607717)
        (xy 100.810998 96.607717)
        (xy 75.125 96.7)
        (xy 75.1 56.725)
        (xy 203.553998 56.729717)
      )
    )
  )
  (zone (net 253) (net_name "3V3_OUT") (layer "In2.Cu") (hatch edge 0.508)
    (priority 3)
    (connect_pads yes (clearance 0.254))
    (min_thickness 0.2) (filled_areas_thickness no)
    (fill yes (thermal_gap 0.2) (thermal_bridge_width 0.254))
    (polygon
      (pts
        (xy 203.584 96.7)
        (xy 195.92 96.68)
        (xy 195.93 86.78)
        (xy 199.04 86.8)
        (xy 199.12 72.54)
        (xy 200.31 72.54)
        (xy 200.31 56.69)
        (xy 203.584 56.7)
      )
    )
  )
  (zone (net 170) (net_name "3V3_SSD") (layer "In2.Cu") (hatch edge 0.508)
    (priority 3)
    (connect_pads yes (clearance 0.2))
    (min_thickness 0.2) (filled_areas_thickness no)
    (fill yes (thermal_gap 0.2) (thermal_bridge_width 0.254))
    (polygon
      (pts
        (xy 153.9 89.4)
        (xy 153.9 96.7)
        (xy 147.95 96.7)
        (xy 147.2 96.7)
        (xy 130.034 96.7)
        (xy 130 89.6)
        (xy 122 89.6)
        (xy 122 83)
        (xy 135 83)
        (xy 138 86.66597)
        (xy 146.7 86.639161)
        (xy 146.7 89.4)
      )
    )
  )
  (zone (net 231) (net_name "Net-(D4-Pad2)") (layer "In2.Cu") (hatch edge 0.508)
    (priority 3)
    (connect_pads yes (clearance 0.254))
    (min_thickness 0.2) (filled_areas_thickness no)
    (fill yes (thermal_gap 0.2) (thermal_bridge_width 0.255) (smoothing fillet) (radius 1))
    (polygon
      (pts
        (xy 104.2 79.25)
        (xy 101.3 81.8)
        (xy 101.25 88.8)
        (xy 99.05 90.6)
        (xy 92.628753 90.628393)
        (xy 89.2 94)
        (xy 89.2 96.756)
        (xy 83.55 96.706)
        (xy 83.55 91.456)
        (xy 87.6 87.41)
        (xy 88.16 87.41)
        (xy 88.86 86.72)
        (xy 90.1 86.71)
        (xy 90.36 86.53)
        (xy 90.35 84.58)
        (xy 99.55 75.356)
        (xy 99.55 69.056)
        (xy 104.21 69.066)
      )
    )
  )
  (zone (net 191) (net_name "Net-(D4-Pad1)") (layer "In2.Cu") (hatch edge 0.508)
    (priority 3)
    (connect_pads yes (clearance 0.254))
    (min_thickness 0.2) (filled_areas_thickness no)
    (fill yes (thermal_gap 0.2) (thermal_bridge_width 0.255) (smoothing fillet) (radius 1))
    (polygon
      (pts
        (xy 94.35 76.02)
        (xy 97 76.02)
        (xy 97.15 76.17)
        (xy 97.15 77.4)
        (xy 90.09 84.38)
        (xy 90.09 86.29)
        (xy 89.94 86.44)
        (xy 88.74 86.44)
        (xy 88.1 87.09)
        (xy 87.39 87.09)
        (xy 83.2 91.156)
        (xy 83.2 96.706)
        (xy 80.7 96.706)
        (xy 80.7 76.406)
        (xy 94.1 76.406)
      )
    )
  )
  (zone (net 230) (net_name "Earth") (layer "In2.Cu") (hatch edge 0.508)
    (connect_pads thru_hole_only (clearance 0.254))
    (min_thickness 0.254) (filled_areas_thickness no)
    (fill yes (thermal_gap 0.254) (thermal_bridge_width 0.376) (smoothing fillet) (radius 1))
    (polygon
      (pts
        (xy 104.21 75.316)
        (xy 87.77 75.356)
        (xy 87.77 56.641)
        (xy 104.22 56.641)
      )
    )
  )
  (zone (net 11) (net_name "GND") (layer "In2.Cu") (hatch edge 0.508)
    (connect_pads (clearance 0.127))
    (min_thickness 0.2) (filled_areas_thickness no)
    (fill yes (thermal_gap 0.2) (thermal_bridge_width 0.254))
    (polygon
      (pts
        (xy 171.31 96.51)
        (xy 154.39 96.49)
        (xy 154.47 88.19)
        (xy 171.3 88.27)
      )
    )
  )
  (zone (net 170) (net_name "3V3_SSD") (layer "In2.Cu") (hatch edge 0.508)
    (connect_pads (clearance 0.2))
    (min_thickness 0.254) (filled_areas_thickness no)
    (fill yes (thermal_gap 0.508) (thermal_bridge_width 0.508))
    (polygon
      (pts
        (xy 185.12 86.46)
        (xy 175.51 86.42)
        (xy 175.48 72.62)
        (xy 168.15 72.65)
        (xy 168.15 65.9)
        (xy 173.65 65.9)
        (xy 174.25 65.3)
        (xy 185.03 65.29)
      )
    )
  )
  (zone (net 170) (net_name "3V3_SSD") (layer "In2.Cu") (hatch edge 0.508)
    (connect_pads yes (clearance 0.508))
    (min_thickness 0.254) (filled_areas_thickness no)
    (fill yes (thermal_gap 0.508) (thermal_bridge_width 0.508))
    (polygon
      (pts
        (xy 127.25 89)
        (xy 122.25 89)
        (xy 122.25 85)
        (xy 127.25 85)
      )
    )
  )
  (zone (net 11) (net_name "GND") (layer "In2.Cu") (hatch edge 0.508)
    (connect_pads (clearance 0.127))
    (min_thickness 0.2) (filled_areas_thickness no)
    (fill yes (thermal_gap 0.2) (thermal_bridge_width 0.254))
    (polygon
      (pts
        (xy 198.82 86.43)
        (xy 195.68 86.43)
        (xy 195.6816 96.5454)
        (xy 171.77 96.51)
        (xy 171.74 90.95)
        (xy 185.51 90.78)
        (xy 185.575 65.525)
        (xy 194.175 65.55)
        (xy 194.175 72.525)
        (xy 198.79 72.525)
      )
    )
  )
  (zone (net 232) (net_name "3V3_RPi") (layer "In2.Cu") (hatch edge 0.508)
    (priority 2)
    (connect_pads yes (clearance 0.127))
    (min_thickness 0.2) (filled_areas_thickness no)
    (fill yes (thermal_gap 0.2) (thermal_bridge_width 0.254))
    (polygon
      (pts
        (xy 155.71 61.19)
        (xy 162.54 61.21)
        (xy 162.62 65.7)
        (xy 167.536 65.7)
        (xy 167.956 66.13)
        (xy 167.943782 72.799989)
        (xy 175.21 72.89)
        (xy 175.24 86.63)
        (xy 170.434 86.6394)
        (xy 170.434 84.7)
        (xy 146.55 84.7)
        (xy 146.55 96.7)
        (xy 140.3 96.7)
        (xy 84.58 96.7)
        (xy 84.58 56.7)
        (xy 130.276 56.72)
        (xy 130.276 65.7)
        (xy 137.08 65.7)
        (xy 155.72 65.7)
      )
    )
  )
  (zone (net 253) (net_name "3V3_OUT") (layer "In2.Cu") (hatch edge 0.508)
    (connect_pads (clearance 0.2))
    (min_thickness 0.254) (filled_areas_thickness no)
    (fill yes (thermal_gap 0.508) (thermal_bridge_width 0.508))
    (polygon
      (pts
        (xy 185.12 86.74)
        (xy 185.19 90.47)
        (xy 171.74 90.46)
        (xy 171.73 87.98)
        (xy 154.05 87.69)
        (xy 154.05 89.3)
        (xy 146.85 89.3)
        (xy 146.85 84.75)
        (xy 170.2308 84.836)
        (xy 170.2308 86.741)
        (xy 172.05 86.76)
      )
    )
  )
  (zone (net 12) (net_name "VCC5V0") (layer "In2.Cu") (hatch edge 0.508)
    (connect_pads (clearance 0.2))
    (min_thickness 0.254) (filled_areas_thickness no)
    (fill yes (thermal_gap 0.508) (thermal_bridge_width 0.508))
    (polygon
      (pts
        (xy 200.06 72.12)
        (xy 194.6 72.175)
        (xy 194.6 65.025)
        (xy 185.56 65.01)
        (xy 162.86 65.08)
        (xy 162.83 60.82)
        (xy 155.25 60.82)
        (xy 155.25 65.26)
        (xy 130.53 65.39)
        (xy 130.5 56.92)
        (xy 185.84 56.92)
        (xy 199.96 56.68)
      )
    )
  )
  (zone (net 253) (net_name "3V3_OUT") (layer "B.Cu") (hatch edge 0.508)
    (connect_pads yes (clearance 0.127))
    (min_thickness 0.2) (filled_areas_thickness no)
    (fill yes (thermal_gap 0.2) (thermal_bridge_width 0.254))
    (polygon
      (pts
        (xy 147.05 88.95)
        (xy 153.25 88.95)
        (xy 153.25 85.9)
        (xy 147.05 85.9)
      )
    )
  )
  (zone (net 170) (net_name "3V3_SSD") (layer "B.Cu") (hatch edge 0.508)
    (connect_pads yes (clearance 0.127))
    (min_thickness 0.2) (filled_areas_thickness no)
    (fill yes (thermal_gap 0.2) (thermal_bridge_width 0.254))
    (polygon
      (pts
        (xy 153.6988 93.7768)
        (xy 150.4988 93.7768)
        (xy 150.4988 89.7268)
        (xy 153.6988 89.7268)
      )
    )
  )
  (zone (net 232) (net_name "3V3_RPi") (layer "B.Cu") (hatch edge 0.508)
    (connect_pads yes (clearance 0.127))
    (min_thickness 0.2) (filled_areas_thickness no)
    (fill yes (thermal_gap 0.2) (thermal_bridge_width 0.254))
    (polygon
      (pts
        (xy 150.65 84.6)
        (xy 154.45 84.6)
        (xy 154.45 82.1)
        (xy 150.65 82.1)
      )
    )
  )
  (zone (net 253) (net_name "3V3_OUT") (layer "B.Cu") (hatch edge 0.508)
    (connect_pads (clearance 0.127))
    (min_thickness 0.2) (filled_areas_thickness no)
    (fill yes (thermal_gap 0.2) (thermal_bridge_width 0.254))
    (polygon
      (pts
        (xy 202.8985 72.25)
        (xy 202.9085 68.7832)
        (xy 200.2685 68.7578)
        (xy 200.306 72.2)
        (xy 202.4685 72.25)
      )
    )
  )
  (zone (net 12) (net_name "VCC5V0") (layer "B.Cu") (hatch edge 0.508)
    (priority 2)
    (connect_pads (clearance 0.127))
    (min_thickness 0.254) (filled_areas_thickness no)
    (fill yes (thermal_gap 0.508) (thermal_bridge_width 0.508) (smoothing fillet))
    (polygon
      (pts
        (xy 199.96 66.99)
        (xy 194.96 66.94)
        (xy 194.96 69.24)
        (xy 196.16 70.68)
        (xy 197.37 72.13)
        (xy 199.9935 72.15)
      )
    )
  )
  (zone (net 170) (net_name "3V3_SSD") (layer "B.Cu") (hatch edge 0.508)
    (priority 2)
    (connect_pads thru_hole_only (clearance 0.127))
    (min_thickness 0.254) (filled_areas_thickness no)
    (fill yes (thermal_gap 0.508) (thermal_bridge_width 0.508) (smoothing fillet))
    (polygon
      (pts
        (xy 180.634 69.025)
        (xy 178.984 69.025)
        (xy 178.084 70.2)
        (xy 173.584 70.2)
        (xy 173.584 72.2)
        (xy 171.184 72.2)
        (xy 171.184 67.5)
        (xy 180.634 67.5)
      )
    )
  )
  (zone (net 170) (net_name "3V3_SSD") (layer "B.Cu") (hatch edge 0.508)
    (priority 2)
    (connect_pads thru_hole_only (clearance 0.127))
    (min_thickness 0.254) (filled_areas_thickness no)
    (fill yes (thermal_gap 0.508) (thermal_bridge_width 0.508) (smoothing fillet))
    (polygon
      (pts
        (xy 178.909 81.65)
        (xy 180.684 81.65)
        (xy 180.684 86.25)
        (xy 178.909 86.25)
        (xy 178.534 85.875)
        (xy 172.309 85.875)
        (xy 172.309 81.25)
        (xy 178.509 81.25)
      )
    )
  )
  (zone (net 191) (net_name "Net-(D4-Pad1)") (layer "B.Cu") (hatch edge 0.508)
    (priority 1)
    (connect_pads yes (clearance 0.254))
    (min_thickness 0.2) (filled_areas_thickness no)
    (fill yes (thermal_gap 0.2) (thermal_bridge_width 0.255) (smoothing fillet) (radius 1))
    (polygon
      (pts
        (xy 83.25 94.406)
        (xy 85 94.406)
        (xy 85 96.4)
        (xy 80.85 96.306)
        (xy 80.7 91.456)
        (xy 83.25 91.456)
      )
    )
  )
  (zone (net 191) (net_name "Net-(D4-Pad1)") (layer "B.Cu") (hatch edge 0.508)
    (priority 1)
    (connect_pads thru_hole_only (clearance 0.5))
    (min_thickness 0.254) (filled_areas_thickness no)
    (fill yes (thermal_gap 0.254) (thermal_bridge_width 0.376) (smoothing fillet) (radius 1))
    (polygon
      (pts
        (xy 97.1 77.906)
        (xy 94.05 77.906)
        (xy 94.05 76.456)
        (xy 95.7 75.206)
        (xy 95.7 73.356)
        (xy 97.1 73.356)
      )
    )
  )
  (zone (net 231) (net_name "Net-(D4-Pad2)") (layer "B.Cu") (hatch edge 0.508)
    (connect_pads thru_hole_only (clearance 0.254))
    (min_thickness 0.254) (filled_areas_thickness no)
    (fill yes (thermal_gap 0.254) (thermal_bridge_width 0.376) (smoothing fillet) (radius 1))
    (polygon
      (pts
        (xy 85.95 91.681)
        (xy 85.987 92.006)
        (xy 85.987 92.431)
        (xy 85.86 92.939)
        (xy 85.479 93.32)
        (xy 84.971 93.955)
        (xy 84.463 93.955)
        (xy 83.574 93.066)
        (xy 83.574 91.669)
      )
    )
  )
  (zone (net 11) (net_name "GND") (layer "B.Cu") (hatch edge 0.508)
    (connect_pads thru_hole_only (clearance 0.254))
    (min_thickness 0.254) (filled_areas_thickness no)
    (fill yes (thermal_gap 0.254) (thermal_bridge_width 0.376) (smoothing fillet) (radius 1))
    (polygon
      (pts
        (xy 179.007 65.628)
        (xy 179.007 66.517)
        (xy 178.499 67.152)
        (xy 172.657 67.152)
        (xy 172.403 67.025)
        (xy 172.403 66.263)
        (xy 172.657 66.009)
        (xy 174.6255 66.009)
        (xy 175.3875 65.247)
        (xy 178.626 65.247)
      )
    )
  )
  (zone (net 11) (net_name "GND") (layer "B.Cu") (hatch edge 0.508)
    (connect_pads thru_hole_only (clearance 0.254))
    (min_thickness 0.254) (filled_areas_thickness no)
    (fill yes (thermal_gap 0.254) (thermal_bridge_width 0.376) (smoothing fillet) (radius 1))
    (polygon
      (pts
        (xy 177.61 79.598)
        (xy 177.864 79.598)
        (xy 178.245 79.979)
        (xy 178.245 80.614)
        (xy 177.991 80.868)
        (xy 172.657 80.868)
        (xy 172.403 80.614)
        (xy 172.403 79.852)
        (xy 172.657 79.598)
        (xy 173.038 79.598)
        (xy 173.546 79.09)
        (xy 177.102 79.09)
      )
    )
  )
  (zone (net 11) (net_name "GND") (layer "B.Cu") (hatch edge 0.508)
    (connect_pads thru_hole_only (clearance 0.254))
    (min_thickness 0.254) (filled_areas_thickness no)
    (fill yes (thermal_gap 0.254) (thermal_bridge_width 0.376) (smoothing fillet) (radius 1))
    (polygon
      (pts
        (xy 178.245 86.71)
        (xy 178.245 86.837)
        (xy 178.753 87.345)
        (xy 178.753 87.853)
        (xy 178.499 88.107)
        (xy 174.943 88.107)
        (xy 174.181 87.345)
        (xy 172.657 87.345)
        (xy 172.53 87.218)
        (xy 172.53 86.583)
        (xy 172.657 86.456)
        (xy 177.991 86.456)
      )
    )
  )
  (zone (net 11) (net_name "GND") (layer "B.Cu") (hatch edge 0.508)
    (connect_pads thru_hole_only (clearance 0.254))
    (min_thickness 0.254) (filled_areas_thickness no)
    (fill yes (thermal_gap 0.254) (thermal_bridge_width 0.376) (smoothing fillet) (radius 1))
    (polygon
      (pts
        (xy 189.0081 65.882)
        (xy 189.0081 66.771)
        (xy 188.2461 67.279)
        (xy 188.2461 68.7395)
        (xy 188.1191 68.8665)
        (xy 186.4681 68.8665)
        (xy 186.2141 69.1205)
        (xy 186.2141 71.597)
        (xy 186.4681 71.851)
        (xy 188.1191 71.851)
        (xy 188.1191 71.978)
        (xy 188.1191 72.232)
        (xy 188.1191 72.359)
        (xy 188.1191 72.613)
        (xy 188.1191 73.248)
        (xy 188.1191 73.502)
        (xy 188.1191 73.629)
        (xy 188.1191 73.838442)
        (xy 188.1191 73.965442)
        (xy 188.1191 74.346442)
        (xy 188.1191 74.772)
        (xy 188.1191 75.235442)
        (xy 188.1191 85.948)
        (xy 189.0081 86.71)
        (xy 189.0081 87.726)
        (xy 188.7541 87.98)
        (xy 184.3091 87.98)
        (xy 184.0551 87.726)
        (xy 184.0551 86.837)
        (xy 184.6901 86.329)
        (xy 185.0711 85.44)
        (xy 185.0711 68.041)
        (xy 184.6901 67.406)
        (xy 184.0551 67.025)
        (xy 183.8011 66.644)
        (xy 183.8011 66.136)
        (xy 184.0551 65.755)
        (xy 184.6901 65.628)
        (xy 188.7541 65.628)
      )
    )
  )
  (zone (net 5) (net_name "VSS") (layer "B.Cu") (hatch edge 0.508)
    (priority 1)
    (connect_pads thru_hole_only (clearance 0.254))
    (min_thickness 0.254) (filled_areas_thickness no)
    (fill yes (thermal_gap 0.254) (thermal_bridge_width 0.376) (smoothing fillet) (radius 1))
    (polygon
      (pts
        (xy 92.070998 89.247717)
        (xy 93.213998 89.247717)
        (xy 99.563998 89.247717)
        (xy 100.198998 89.882717)
        (xy 100.198998 93.057717)
        (xy 97.912998 93.057717)
        (xy 97.912998 90.771717)
        (xy 97.277998 90.136717)
        (xy 94.496 90.136717)
        (xy 93.988 90.517717)
        (xy 93.988 91.025717)
        (xy 93.861 91.161)
        (xy 91.435998 91.152717)
        (xy 91.308998 91.279717)
        (xy 91.3 91.3)
        (xy 89.1 93.290343)
        (xy 86.476 93.302)
        (xy 86.476 91.542)
        (xy 87.892 91.542)
        (xy 89.162 90.272)
        (xy 89.162 89.256)
        (xy 89.67 88.748)
        (xy 91.575 88.748)
      )
    )
  )
  (zone (net 6) (net_name "/PoE/VDD_POE_IN") (layer "B.Cu") (hatch edge 0.508)
    (connect_pads yes (clearance 0.254))
    (min_thickness 0.254) (filled_areas_thickness no)
    (fill yes (thermal_gap 0.254) (thermal_bridge_width 0.376) (smoothing fillet) (radius 1))
    (polygon
      (pts
        (xy 93.84 92.096)
        (xy 93.84 92.826)
        (xy 93.96 92.946)
        (xy 97.04 92.946)
        (xy 97.3 93.206)
        (xy 97.3 94.106)
        (xy 97.6 94.437717)
        (xy 112.516 94.437717)
        (xy 116.508768 94.44151)
        (xy 116.517557 82.643813)
        (xy 116.927444 82.30224)
        (xy 117.8 82.292)
        (xy 118.25 82.646)
        (xy 118.25 95.646)
        (xy 117.699808 96.685662)
        (xy 86.1 96.6)
        (xy 85.663998 95.851717)
        (xy 85.663998 94.581717)
        (xy 86.3 94.1)
        (xy 87.498998 93.565717)
        (xy 88.832498 93.565717)
        (xy 90.165998 91.914717)
        (xy 91.689998 91.914717)
        (xy 92.197998 91.914717)
        (xy 93.66 91.914717)
      )
    )
  )
  (zone (net 11) (net_name "GND") (layer "B.Cu") (hatch edge 0.508)
    (priority 3)
    (connect_pads yes (clearance 0.254))
    (min_thickness 0.2) (filled_areas_thickness no)
    (fill yes (thermal_gap 0.2) (thermal_bridge_width 0.255))
    (polygon
      (pts
        (xy 121.5 89)
        (xy 118.5 89)
        (xy 118.5 84.25)
        (xy 121.5 84.25)
      )
    )
  )
  (zone (net 4) (net_name "GNDD") (layer "B.Cu") (hatch edge 0.508)
    (connect_pads yes (clearance 0.254))
    (min_thickness 0.254) (filled_areas_thickness no)
    (fill yes (thermal_gap 0.254) (thermal_bridge_width 0.376) (smoothing fillet) (radius 1))
    (polygon
      (pts
        (xy 116.5 79.2)
        (xy 117.7 79.2)
        (xy 118.3 79.8)
        (xy 118.3 81.496)
        (xy 117.8 81.996)
        (xy 116 82)
        (xy 116 94)
        (xy 110.616 94.102)
        (xy 100.616 94.102)
        (xy 100.316 93.802)
        (xy 100.316 93.202)
        (xy 100.616 92.902)
        (xy 102.616 92.902)
        (xy 103.116 92.402)
        (xy 103.116 90.602)
        (xy 102.616 90.102)
        (xy 101.016 90.102)
        (xy 100.816 89.902)
        (xy 100.816 89.302)
        (xy 101.116 89.002)
        (xy 106.9 89)
        (xy 107.9 88)
        (xy 107.9 82.4)
        (xy 110.4 79.9)
        (xy 115.8 79.9)
      )
    )
  )
  (zone (net 170) (net_name "3V3_SSD") (layer "B.Cu") (hatch edge 0.508)
    (connect_pads yes (clearance 0.2))
    (min_thickness 0.254) (filled_areas_thickness no)
    (fill yes (thermal_gap 0.508) (thermal_bridge_width 0.508))
    (polygon
      (pts
        (xy 127.25 89)
        (xy 121.85 89)
        (xy 121.85 84.75)
        (xy 127.25 84.75)
      )
    )
  )
  (zone (net 12) (net_name "VCC5V0") (layer "B.Cu") (hatch edge 0.508)
    (priority 3)
    (connect_pads yes (clearance 0.254))
    (min_thickness 0.2) (filled_areas_thickness no)
    (fill yes (thermal_gap 0.2) (thermal_bridge_width 0.255) (smoothing fillet) (radius 1))
    (polygon
      (pts
        (xy 132 91.2)
        (xy 130.2 91.2)
        (xy 130.2 90.8)
        (xy 126.5 90.8)
        (xy 126.5 93.1)
        (xy 122 93.1)
        (xy 122 89.06467)
        (xy 130.5 89)
        (xy 130.5 87.75)
        (xy 132 87.75)
      )
    )
  )
  (zone (net 13) (net_name "/PoE/VO5V") (layer "B.Cu") (hatch edge 0.508)
    (priority 4)
    (connect_pads yes (clearance 0.254))
    (min_thickness 0.2) (filled_areas_thickness no)
    (fill yes (thermal_gap 0.2) (thermal_bridge_width 0.255) (smoothing fillet) (radius 1))
    (polygon
      (pts
        (xy 129.95 91.15)
        (xy 129.95 92.6)
        (xy 130.65 93.36)
        (xy 135.33 93.36)
        (xy 136.9 91.65)
        (xy 138.25 91.65)
        (xy 139.1 92.5)
        (xy 139.1 96.7)
        (xy 127.1 96.7)
        (xy 127.1 91.25)
        (xy 127.55 90.8)
        (xy 129.6 90.8)
      )
    )
  )
  (zone (net 12) (net_name "VCC5V0") (layer "B.Cu") (hatch edge 0.508)
    (priority 3)
    (connect_pads yes (clearance 0.254))
    (min_thickness 0.2) (filled_areas_thickness no)
    (fill yes (thermal_gap 0.2) (thermal_bridge_width 0.255) (smoothing fillet) (radius 1))
    (polygon
      (pts
        (xy 130.625 59.04)
        (xy 130.625 72.29)
        (xy 130.825 72.495)
        (xy 134.42 72.495)
        (xy 134.625 72.29)
        (xy 134.625 59.025)
        (xy 134.25 58.65)
        (xy 131.025 58.65)
      )
    )
  )
  (zone (net 170) (net_name "3V3_SSD") (layer "B.Cu") (hatch edge 0.508)
    (connect_pads (clearance 0.127))
    (min_thickness 0.254) (filled_areas_thickness no)
    (fill yes (thermal_gap 0.508) (thermal_bridge_width 0.508))
    (polygon
      (pts
        (xy 173.5836 76.7588)
        (xy 153.289 76.7588)
        (xy 151.2824 78.7654)
        (xy 147.1168 78.7654)
        (xy 150.622 75.2602)
        (xy 171.196 75.2602)
        (xy 171.196 72.136)
        (xy 173.5836 72.136)
      )
    )
  )
  (zone (net 11) (net_name "GND") (layer "B.Cu") (hatch edge 0.508)
    (connect_pads yes (clearance 0.2))
    (min_thickness 0.254) (filled_areas_thickness no)
    (fill yes (thermal_gap 0.508) (thermal_bridge_width 0.508))
    (polygon
      (pts
        (xy 135.75 92.5)
        (xy 135.25 93.2)
        (xy 131.4 93.2)
        (xy 131.4 91.35)
        (xy 132.5 91.35)
        (xy 132.5 87.5)
        (xy 135.75 87.5)
        (xy 135.75 91.5)
      )
    )
  )
  (zone (net 22) (net_name "Net-(U2-BST)") (layer "B.Cu") (hatch edge 0.508)
    (connect_pads yes (clearance 0.2))
    (min_thickness 0.254) (filled_areas_thickness no)
    (fill yes (thermal_gap 0.508) (thermal_bridge_width 0.508))
    (polygon
      (pts
        (xy 135 86.2)
        (xy 132.6 86.2)
        (xy 132.6 85)
        (xy 135 85)
      )
    )
  )
  (zone (net 11) (net_name "GND") (layer "B.Cu") (hatch edge 0.508)
    (priority 3)
    (connect_pads yes (clearance 0.254))
    (min_thickness 0.2) (filled_areas_thickness no)
    (fill yes (thermal_gap 0.2) (thermal_bridge_width 0.255) (smoothing fillet) (radius 1))
    (polygon
      (pts
        (xy 126.3 94)
        (xy 126.3 95.6)
        (xy 126.2 95.7)
        (xy 122.3 95.7)
        (xy 122 95.5)
        (xy 122 94.1)
        (xy 122.2 93.9)
        (xy 126.2 93.9)
      )
    )
  )
  (zone (net 19) (net_name "Net-(U2-SW)") (layer "B.Cu") (hatch edge 0.508)
    (priority 4)
    (connect_pads yes (clearance 0.2))
    (min_thickness 0.254) (filled_areas_thickness no)
    (fill yes (thermal_gap 0.508) (thermal_bridge_width 0.508))
    (polygon
      (pts
        (xy 130.5 86.25)
        (xy 135 86.25)
        (xy 135 87.5)
        (xy 132.5 87.5)
        (xy 132.5 88.75)
        (xy 127.75 88.75)
        (xy 127.75 84.75)
        (xy 130.5 84.75)
      )
    )
  )
  (zone (net 11) (net_name "GND") (layer "B.Cu") (hatch edge 0.508)
    (connect_pads (clearance 0.127))
    (min_thickness 0.254) (filled_areas_thickness no)
    (fill yes (thermal_gap 0.508) (thermal_bridge_width 0.508))
    (polygon
      (pts
        (xy 194.8989 70.007)
        (xy 195.54 70.82)
        (xy 197.17 72.79)
        (xy 202.1171 72.7964)
        (xy 202.1171 75.6412)
        (xy 197.5501 75.6362)
        (xy 194.98 72.52)
        (xy 192.39 69.68)
        (xy 189.52 69.66)
        (xy 189.52 67.16)
        (xy 192.17 67.15)
      )
    )
  )
)
